FILE_TYPE=EXPANDEDPARTLIST;
{ Packager-XL run on 14-Sep-2023 AT 16:11:04 }
DIRECTIVES
 PST_VERSION='PST_HDL_CENTRIC_VERSION_0';
 ROOT_DRAWING='T6G';
 POST_TIME='14-Sep-2023 AT 16:11:04';
 SOURCE_TOOL='PACKAGER_XL';
END_DIRECTIVES;

PART_NAME
 BT2 'CONN2_AAABAT029Y19-CONN2_AAA-BAT-029-Y19,THLF,IO,DA':;

SECTION_NUMBER 1
 '@T6G_MB_LIB.T6G(SCH_1):PAGE156_I86@PURE_QUANTA.CONN2_AAABAT029Y19(CHIPS)':
 C_PATH='@t6g_mb_lib.t6g(sch_1):page156_i86@pure_quanta.conn2_aaabat029y19(chips~
)',
 P_PATH='@t6g_mb_lib.t6g(sch_1):page187_i86@pure_quanta.conn2_aaabat029y19(chips~
)',
 PATH='I86',
 DRAWING='@T6G_MB_LIB.T6G(SCH_1):PAGE156',
 PART_TYPE='THLF',
 MATERIAL='IO',
 PHYS_PAGE='187',
 XY='(-9125,6950)',
 ROT='2',
 VER='1',
 LOCATION='BT2',
 CDS_LIB='pure_quanta',
 CDS_PART_NAME='CONN2_AAABAT029Y19-CONN2_AAA-BAT-029-Y19,THLF,IO,DA',
 PART_NUMBER='DFHS02FR062',
 VALUE='CONN2_AAA-BAT-029-Y19',
 PRIM_FILE='./archive_libs/logical/conn2_aaabat029y19/chips/chips.prt';

PART_NAME
 C1 'Q_CAP_0402-0.1UF,25V,10%,X7R,CH4104K1B00':;

SECTION_NUMBER 1
 '@T6G_MB_LIB.T6G(SCH_1):PAGE361_I110@PURE_QUANTA.Q_CAP(CHIPS)':
 C_PATH='@t6g_mb_lib.t6g(sch_1):page361_i110@pure_quanta.q_cap(chips)',
 P_PATH='@t6g_mb_lib.t6g(sch_1):page238_i110@pure_quanta.q_cap(chips)',
 PATH='I110',
 DRAWING='@T6G_MB_LIB.T6G(SCH_1):PAGE361',
 TOLERANCE='10%',
 MATERIAL='X7R',
 PHYS_PAGE='238',
 XY='(-750,1400)',
 ROT='2',
 VER='1',
 PACK_TYPE='0402',
 LOCATION='C1',
 CDS_LIB='pure_quanta',
 CDS_PART_NAME='Q_CAP_0402-0.1UF,25V,10%,X7R,CH4104K1B00',
 VOLTAGE='25V',
 PART_NUMBER='CH4104K1B00',
 VALUE='0.1UF',
 PRIM_FILE='./archive_libs/logical/q_cap/chips/chips.prt';

PART_NAME
 C2 'Q_CAP_0402-0.1UF,25V,10%,X7R,CH4104K1B00':;

SECTION_NUMBER 1
 '@T6G_MB_LIB.T6G(SCH_1):PAGE137_I59@PURE_QUANTA.Q_CAP(CHIPS)':
 C_PATH='@t6g_mb_lib.t6g(sch_1):page137_i59@pure_quanta.q_cap(chips)',
 P_PATH='@t6g_mb_lib.t6g(sch_1):page160_i59@pure_quanta.q_cap(chips)',
 PATH='I59',
 DRAWING='@T6G_MB_LIB.T6G(SCH_1):PAGE137',
 TOLERANCE='10%',
 MATERIAL='X7R',
 PHYS_PAGE='160',
 XY='(-6675,1200)',
 ROT='0',
 VER='1',
 PACK_TYPE='0402',
 LOCATION='C2',
 CDS_LIB='pure_quanta',
 CDS_PART_NAME='Q_CAP_0402-0.1UF,25V,10%,X7R,CH4104K1B00',
 VOLTAGE='25V',
 PART_NUMBER='CH4104K1B00',
 VALUE='0.1UF',
 PRIM_FILE='./archive_libs/logical/q_cap/chips/chips.prt';

PART_NAME
 C3 'Q_CAP_0402-0.1UF,25V,10%,X7R,CH4104K1B00':;

SECTION_NUMBER 1
 '@T6G_MB_LIB.T6G(SCH_1):PAGE137_I56@PURE_QUANTA.Q_CAP(CHIPS)':
 C_PATH='@t6g_mb_lib.t6g(sch_1):page137_i56@pure_quanta.q_cap(chips)',
 P_PATH='@t6g_mb_lib.t6g(sch_1):page160_i56@pure_quanta.q_cap(chips)',
 PATH='I56',
 DRAWING='@T6G_MB_LIB.T6G(SCH_1):PAGE137',
 TOLERANCE='10%',
 MATERIAL='X7R',
 PHYS_PAGE='160',
 XY='(-5275,1150)',
 ROT='0',
 VER='1',
 PACK_TYPE='0402',
 LOCATION='C3',
 CDS_LIB='pure_quanta',
 CDS_PART_NAME='Q_CAP_0402-0.1UF,25V,10%,X7R,CH4104K1B00',
 VOLTAGE='25V',
 PART_NUMBER='CH4104K1B00',
 VALUE='0.1UF',
 PRIM_FILE='./archive_libs/logical/q_cap/chips/chips.prt';

PART_NAME
 C4 'Q_CAP_0402-0.1UF,25V,10%,X7R,CH4104K1B00':;

SECTION_NUMBER 1
 '@T6G_MB_LIB.T6G(SCH_1):PAGE331_I44@PURE_QUANTA.Q_CAP(CHIPS)':
 C_PATH='@t6g_mb_lib.t6g(sch_1):page331_i44@pure_quanta.q_cap(chips)',
 P_PATH='@t6g_mb_lib.t6g(sch_1):page124_i44@pure_quanta.q_cap(chips)',
 PATH='I44',
 DRAWING='@T6G_MB_LIB.T6G(SCH_1):PAGE331',
 TOLERANCE='10%',
 MATERIAL='X7R',
 PHYS_PAGE='124',
 XY='(1100,5225)',
 ROT='0',
 VER='1',
 PACK_TYPE='0402',
 LOCATION='C4',
 CDS_LIB='pure_quanta',
 CDS_PART_NAME='Q_CAP_0402-0.1UF,25V,10%,X7R,CH4104K1B00',
 VOLTAGE='25V',
 PART_NUMBER='CH4104K1B00',
 VALUE='0.1UF',
 PRIM_FILE='./archive_libs/logical/q_cap/chips/chips.prt';

PART_NAME
 C5 'Q_CAP_0402-0.1UF,25V,10%,X7R,CH4104K1B00':;

SECTION_NUMBER 1
 '@T6G_MB_LIB.T6G(SCH_1):PAGE331_I33@PURE_QUANTA.Q_CAP(CHIPS)':
 C_PATH='@t6g_mb_lib.t6g(sch_1):page331_i33@pure_quanta.q_cap(chips)',
 P_PATH='@t6g_mb_lib.t6g(sch_1):page124_i33@pure_quanta.q_cap(chips)',
 PATH='I33',
 DRAWING='@T6G_MB_LIB.T6G(SCH_1):PAGE331',
 TOLERANCE='10%',
 MATERIAL='X7R',
 PHYS_PAGE='124',
 XY='(1100,2400)',
 ROT='0',
 VER='1',
 PACK_TYPE='0402',
 LOCATION='C5',
 CDS_LIB='pure_quanta',
 CDS_PART_NAME='Q_CAP_0402-0.1UF,25V,10%,X7R,CH4104K1B00',
 VOLTAGE='25V',
 PART_NUMBER='CH4104K1B00',
 VALUE='0.1UF',
 PRIM_FILE='./archive_libs/logical/q_cap/chips/chips.prt';

PART_NAME
 C6 'Q_CAP_0402-0.1UF,25V,10%,EMPTY,CH4104K1B00':;

SECTION_NUMBER 1
 '@T6G_MB_LIB.T6G(SCH_1):PAGE331_I111@PURE_QUANTA.Q_CAP(CHIPS)':
 C_PATH='@t6g_mb_lib.t6g(sch_1):page331_i111@pure_quanta.q_cap(chips)',
 P_PATH='@t6g_mb_lib.t6g(sch_1):page124_i111@pure_quanta.q_cap(chips)',
 PATH='I111',
 DRAWING='@T6G_MB_LIB.T6G(SCH_1):PAGE331',
 TOLERANCE='10%',
 MATERIAL='EMPTY',
 PHYS_PAGE='124',
 XY='(1100,775)',
 ROT='0',
 VER='1',
 PACK_TYPE='0402',
 LOCATION='C6',
 CDS_LIB='pure_quanta',
 CDS_PART_NAME='Q_CAP_0402-0.1UF,25V,10%,EMPTY,CH4104K1B00',
 VOLTAGE='25V',
 PART_NUMBER='CH4104K1B00',
 VALUE='0.1UF',
 PRIM_FILE='./archive_libs/logical/q_cap/chips/chips.prt';

PART_NAME
 C7 'Q_CAP_0402-0.1UF,25V,10%,X7R,CH4104K1B00':;

SECTION_NUMBER 1
 '@T6G_MB_LIB.T6G(SCH_1):PAGE331_I42@PURE_QUANTA.Q_CAP(CHIPS)':
 C_PATH='@t6g_mb_lib.t6g(sch_1):page331_i42@pure_quanta.q_cap(chips)',
 P_PATH='@t6g_mb_lib.t6g(sch_1):page124_i42@pure_quanta.q_cap(chips)',
 PATH='I42',
 DRAWING='@T6G_MB_LIB.T6G(SCH_1):PAGE331',
 TOLERANCE='10%',
 MATERIAL='X7R',
 PHYS_PAGE='124',
 XY='(1125,3850)',
 ROT='0',
 VER='1',
 PACK_TYPE='0402',
 LOCATION='C7',
 CDS_LIB='pure_quanta',
 CDS_PART_NAME='Q_CAP_0402-0.1UF,25V,10%,X7R,CH4104K1B00',
 VOLTAGE='25V',
 PART_NUMBER='CH4104K1B00',
 VALUE='0.1UF',
 PRIM_FILE='./archive_libs/logical/q_cap/chips/chips.prt';

PART_NAME
 C8 'Q_CAP_0402-0.1UF,25V,10%,X7R,CH4104K1B00':;

SECTION_NUMBER 1
 '@T6G_MB_LIB.T6G(SCH_1):PAGE331_I93@PURE_QUANTA.Q_CAP(CHIPS)':
 C_PATH='@t6g_mb_lib.t6g(sch_1):page331_i93@pure_quanta.q_cap(chips)',
 P_PATH='@t6g_mb_lib.t6g(sch_1):page124_i93@pure_quanta.q_cap(chips)',
 PATH='I93',
 DRAWING='@T6G_MB_LIB.T6G(SCH_1):PAGE331',
 TOLERANCE='10%',
 MATERIAL='X7R',
 PHYS_PAGE='124',
 XY='(4100,5425)',
 ROT='0',
 VER='1',
 PACK_TYPE='0402',
 LOCATION='C8',
 CDS_LIB='pure_quanta',
 CDS_PART_NAME='Q_CAP_0402-0.1UF,25V,10%,X7R,CH4104K1B00',
 VOLTAGE='25V',
 PART_NUMBER='CH4104K1B00',
 VALUE='0.1UF',
 PRIM_FILE='./archive_libs/logical/q_cap/chips/chips.prt';

PART_NAME
 C9 'Q_CAP_C0402-1UF,25V,10%,EMPTY,CH5104KEB02':;

SECTION_NUMBER 1
 '@T6G_MB_LIB.T6G(SCH_1):PAGE138_I113@PURE_QUANTA.Q_CAP(CHIPS)':
 C_PATH='@t6g_mb_lib.t6g(sch_1):page138_i113@pure_quanta.q_cap(chips)',
 P_PATH='@t6g_mb_lib.t6g(sch_1):page161_i113@pure_quanta.q_cap(chips)',
 PATH='I113',
 DRAWING='@T6G_MB_LIB.T6G(SCH_1):PAGE138',
 TOLERANCE='10%',
 MATERIAL='EMPTY',
 PHYS_PAGE='161',
 XY='(175,4350)',
 ROT='2',
 VER='1',
 PACK_TYPE='C0402',
 LOCATION='C9',
 CDS_LIB='pure_quanta',
 CDS_PART_NAME='Q_CAP_C0402-1UF,25V,10%,EMPTY,CH5104KEB02',
 VOLTAGE='25V',
 PART_NUMBER='CH5104KEB02',
 VALUE='1UF',
 PRIM_FILE='./archive_libs/logical/q_cap/chips/chips.prt';

PART_NAME
 C10 'Q_CAP_0402-0.1UF,25V,10%,X7R,CH4104K1B00':;

SECTION_NUMBER 1
 '@T6G_MB_LIB.T6G(SCH_1):PAGE337_I61@PURE_QUANTA.Q_CAP(CHIPS)':
 C_PATH='@t6g_mb_lib.t6g(sch_1):page337_i61@pure_quanta.q_cap(chips)',
 P_PATH='@t6g_mb_lib.t6g(sch_1):page133_i61@pure_quanta.q_cap(chips)',
 PATH='I61',
 DRAWING='@T6G_MB_LIB.T6G(SCH_1):PAGE337',
 TOLERANCE='10%',
 MATERIAL='X7R',
 PHYS_PAGE='133',
 XY='(-8475,7350)',
 ROT='2',
 VER='1',
 PACK_TYPE='0402',
 LOCATION='C10',
 CDS_LIB='pure_quanta',
 CDS_PART_NAME='Q_CAP_0402-0.1UF,25V,10%,X7R,CH4104K1B00',
 VOLTAGE='25V',
 PART_NUMBER='CH4104K1B00',
 VALUE='0.1UF',
 PRIM_FILE='./archive_libs/logical/q_cap/chips/chips.prt';

PART_NAME
 C11 'Q_CAP_0402-0.1UF,25V,10%,X7R,CH4104K1B00':;

SECTION_NUMBER 1
 '@T6G_MB_LIB.T6G(SCH_1):PAGE138_I89@PURE_QUANTA.Q_CAP(CHIPS)':
 C_PATH='@t6g_mb_lib.t6g(sch_1):page138_i89@pure_quanta.q_cap(chips)',
 P_PATH='@t6g_mb_lib.t6g(sch_1):page161_i89@pure_quanta.q_cap(chips)',
 PATH='I89',
 DRAWING='@T6G_MB_LIB.T6G(SCH_1):PAGE138',
 TOLERANCE='10%',
 MATERIAL='X7R',
 PHYS_PAGE='161',
 XY='(3750,5900)',
 ROT='0',
 VER='1',
 PACK_TYPE='0402',
 LOCATION='C11',
 CDS_LIB='pure_quanta',
 CDS_PART_NAME='Q_CAP_0402-0.1UF,25V,10%,X7R,CH4104K1B00',
 VOLTAGE='25V',
 PART_NUMBER='CH4104K1B00',
 VALUE='0.1UF',
 PRIM_FILE='./archive_libs/logical/q_cap/chips/chips.prt';

PART_NAME
 C12 'Q_CAP_0402-0.1UF,25V,10%,X7R,CH4104K1B00':;

SECTION_NUMBER 1
 '@T6G_MB_LIB.T6G(SCH_1):PAGE332_I75@PURE_QUANTA.Q_CAP(CHIPS)':
 C_PATH='@t6g_mb_lib.t6g(sch_1):page332_i75@pure_quanta.q_cap(chips)',
 P_PATH='@t6g_mb_lib.t6g(sch_1):page125_i75@pure_quanta.q_cap(chips)',
 PATH='I75',
 DRAWING='@T6G_MB_LIB.T6G(SCH_1):PAGE332',
 TOLERANCE='10%',
 MATERIAL='X7R',
 PHYS_PAGE='125',
 XY='(950,3675)',
 ROT='0',
 VER='1',
 PACK_TYPE='0402',
 LOCATION='C12',
 CDS_LIB='pure_quanta',
 CDS_PART_NAME='Q_CAP_0402-0.1UF,25V,10%,X7R,CH4104K1B00',
 VOLTAGE='25V',
 PART_NUMBER='CH4104K1B00',
 VALUE='0.1UF',
 PRIM_FILE='./archive_libs/logical/q_cap/chips/chips.prt';

PART_NAME
 C13 'Q_CAP_0402-0.1UF,25V,10%,X7R,CH4104K1B00':;

SECTION_NUMBER 1
 '@T6G_MB_LIB.T6G(SCH_1):PAGE332_I64@PURE_QUANTA.Q_CAP(CHIPS)':
 C_PATH='@t6g_mb_lib.t6g(sch_1):page332_i64@pure_quanta.q_cap(chips)',
 P_PATH='@t6g_mb_lib.t6g(sch_1):page125_i64@pure_quanta.q_cap(chips)',
 PATH='I64',
 DRAWING='@T6G_MB_LIB.T6G(SCH_1):PAGE332',
 TOLERANCE='10%',
 MATERIAL='X7R',
 PHYS_PAGE='125',
 XY='(950,850)',
 ROT='0',
 VER='1',
 PACK_TYPE='0402',
 LOCATION='C13',
 CDS_LIB='pure_quanta',
 CDS_PART_NAME='Q_CAP_0402-0.1UF,25V,10%,X7R,CH4104K1B00',
 VOLTAGE='25V',
 PART_NUMBER='CH4104K1B00',
 VALUE='0.1UF',
 PRIM_FILE='./archive_libs/logical/q_cap/chips/chips.prt';

PART_NAME
 C14 'Q_CAP_0402-0.1UF,25V,10%,X7R,CH4104K1B00':;

SECTION_NUMBER 1
 '@T6G_MB_LIB.T6G(SCH_1):PAGE332_I73@PURE_QUANTA.Q_CAP(CHIPS)':
 C_PATH='@t6g_mb_lib.t6g(sch_1):page332_i73@pure_quanta.q_cap(chips)',
 P_PATH='@t6g_mb_lib.t6g(sch_1):page125_i73@pure_quanta.q_cap(chips)',
 PATH='I73',
 DRAWING='@T6G_MB_LIB.T6G(SCH_1):PAGE332',
 TOLERANCE='10%',
 MATERIAL='X7R',
 PHYS_PAGE='125',
 XY='(975,2300)',
 ROT='0',
 VER='1',
 PACK_TYPE='0402',
 LOCATION='C14',
 CDS_LIB='pure_quanta',
 CDS_PART_NAME='Q_CAP_0402-0.1UF,25V,10%,X7R,CH4104K1B00',
 VOLTAGE='25V',
 PART_NUMBER='CH4104K1B00',
 VALUE='0.1UF',
 PRIM_FILE='./archive_libs/logical/q_cap/chips/chips.prt';

PART_NAME
 C15 'Q_CAP_0402-0.1UF,25V,10%,X7R,CH4104K1B00':;

SECTION_NUMBER 1
 '@T6G_MB_LIB.T6G(SCH_1):PAGE332_I50@PURE_QUANTA.Q_CAP(CHIPS)':
 C_PATH='@t6g_mb_lib.t6g(sch_1):page332_i50@pure_quanta.q_cap(chips)',
 P_PATH='@t6g_mb_lib.t6g(sch_1):page125_i50@pure_quanta.q_cap(chips)',
 PATH='I50',
 DRAWING='@T6G_MB_LIB.T6G(SCH_1):PAGE332',
 TOLERANCE='10%',
 MATERIAL='X7R',
 PHYS_PAGE='125',
 XY='(1025,-700)',
 ROT='0',
 VER='1',
 PACK_TYPE='0402',
 LOCATION='C15',
 CDS_LIB='pure_quanta',
 CDS_PART_NAME='Q_CAP_0402-0.1UF,25V,10%,X7R,CH4104K1B00',
 VOLTAGE='25V',
 PART_NUMBER='CH4104K1B00',
 VALUE='0.1UF',
 PRIM_FILE='./archive_libs/logical/q_cap/chips/chips.prt';

PART_NAME
 C16 'Q_CAP_0402-0.1UF,25V,10%,X7R,CH4104K1B00':;

SECTION_NUMBER 1
 '@T6G_MB_LIB.T6G(SCH_1):PAGE332_I130@PURE_QUANTA.Q_CAP(CHIPS)':
 C_PATH='@t6g_mb_lib.t6g(sch_1):page332_i130@pure_quanta.q_cap(chips)',
 P_PATH='@t6g_mb_lib.t6g(sch_1):page125_i130@pure_quanta.q_cap(chips)',
 PATH='I130',
 DRAWING='@T6G_MB_LIB.T6G(SCH_1):PAGE332',
 TOLERANCE='10%',
 MATERIAL='X7R',
 PHYS_PAGE='125',
 XY='(5575,3975)',
 ROT='0',
 VER='1',
 PACK_TYPE='0402',
 LOCATION='C16',
 CDS_LIB='pure_quanta',
 CDS_PART_NAME='Q_CAP_0402-0.1UF,25V,10%,X7R,CH4104K1B00',
 VOLTAGE='25V',
 PART_NUMBER='CH4104K1B00',
 VALUE='0.1UF',
 PRIM_FILE='./archive_libs/logical/q_cap/chips/chips.prt';

PART_NAME
 C17 'Q_CAP_0402-0.1UF,25V,10%,X7R,CH4104K1B00':;

SECTION_NUMBER 1
 '@T6G_MB_LIB.T6G(SCH_1):PAGE332_I118@PURE_QUANTA.Q_CAP(CHIPS)':
 C_PATH='@t6g_mb_lib.t6g(sch_1):page332_i118@pure_quanta.q_cap(chips)',
 P_PATH='@t6g_mb_lib.t6g(sch_1):page125_i118@pure_quanta.q_cap(chips)',
 PATH='I118',
 DRAWING='@T6G_MB_LIB.T6G(SCH_1):PAGE332',
 TOLERANCE='10%',
 MATERIAL='X7R',
 PHYS_PAGE='125',
 XY='(5575,1150)',
 ROT='0',
 VER='1',
 PACK_TYPE='0402',
 LOCATION='C17',
 CDS_LIB='pure_quanta',
 CDS_PART_NAME='Q_CAP_0402-0.1UF,25V,10%,X7R,CH4104K1B00',
 VOLTAGE='25V',
 PART_NUMBER='CH4104K1B00',
 VALUE='0.1UF',
 PRIM_FILE='./archive_libs/logical/q_cap/chips/chips.prt';

PART_NAME
 C18 'Q_CAP_0402-0.1UF,25V,10%,X7R,CH4104K1B00':;

SECTION_NUMBER 1
 '@T6G_MB_LIB.T6G(SCH_1):PAGE332_I61@PURE_QUANTA.Q_CAP(CHIPS)':
 C_PATH='@t6g_mb_lib.t6g(sch_1):page332_i61@pure_quanta.q_cap(chips)',
 P_PATH='@t6g_mb_lib.t6g(sch_1):page125_i61@pure_quanta.q_cap(chips)',
 PATH='I61',
 DRAWING='@T6G_MB_LIB.T6G(SCH_1):PAGE332',
 TOLERANCE='10%',
 MATERIAL='X7R',
 PHYS_PAGE='125',
 XY='(5575,-325)',
 ROT='0',
 VER='1',
 PACK_TYPE='0402',
 LOCATION='C18',
 CDS_LIB='pure_quanta',
 CDS_PART_NAME='Q_CAP_0402-0.1UF,25V,10%,X7R,CH4104K1B00',
 VOLTAGE='25V',
 PART_NUMBER='CH4104K1B00',
 VALUE='0.1UF',
 PRIM_FILE='./archive_libs/logical/q_cap/chips/chips.prt';

PART_NAME
 C19 'Q_CAP_0402-0.1UF,25V,10%,X7R,CH4104K1B00':;

SECTION_NUMBER 1
 '@T6G_MB_LIB.T6G(SCH_1):PAGE332_I127@PURE_QUANTA.Q_CAP(CHIPS)':
 C_PATH='@t6g_mb_lib.t6g(sch_1):page332_i127@pure_quanta.q_cap(chips)',
 P_PATH='@t6g_mb_lib.t6g(sch_1):page125_i127@pure_quanta.q_cap(chips)',
 PATH='I127',
 DRAWING='@T6G_MB_LIB.T6G(SCH_1):PAGE332',
 TOLERANCE='10%',
 MATERIAL='X7R',
 PHYS_PAGE='125',
 XY='(5600,2600)',
 ROT='0',
 VER='1',
 PACK_TYPE='0402',
 LOCATION='C19',
 CDS_LIB='pure_quanta',
 CDS_PART_NAME='Q_CAP_0402-0.1UF,25V,10%,X7R,CH4104K1B00',
 VOLTAGE='25V',
 PART_NUMBER='CH4104K1B00',
 VALUE='0.1UF',
 PRIM_FILE='./archive_libs/logical/q_cap/chips/chips.prt';

PART_NAME
 C20 'Q_CAP_C0402-0.1UF,16V,10%,X7R,CH4103K1B08':;

SECTION_NUMBER 1
 '@T6G_MB_LIB.T6G(SCH_1):PAGE84_I42@PURE_QUANTA.Q_CAP(CHIPS)':
 C_PATH='@t6g_mb_lib.t6g(sch_1):page84_i42@pure_quanta.q_cap(chips)',
 P_PATH='@t6g_mb_lib.t6g(sch_1):page85_i42@pure_quanta.q_cap(chips)',
 PATH='I42',
 DRAWING='@T6G_MB_LIB.T6G(SCH_1):PAGE84',
 TOLERANCE='10%',
 MATERIAL='X7R',
 PHYS_PAGE='85',
 XY='(-1850,2075)',
 ROT='0',
 VER='1',
 PACK_TYPE='C0402',
 LOCATION='C20',
 CDS_LIB='pure_quanta',
 CDS_PART_NAME='Q_CAP_C0402-0.1UF,16V,10%,X7R,CH4103K1B08',
 VOLTAGE='16V',
 PART_NUMBER='CH4103K1B08',
 VALUE='0.1UF',
 PRIM_FILE='./archive_libs/logical/q_cap/chips/chips.prt';

PART_NAME
 C21 'Q_CAP_0402-0.1UF,25V,10%,X7R,CH4104K1B00':;

SECTION_NUMBER 1
 '@T6G_MB_LIB.T6G(SCH_1):PAGE335_I89@PURE_QUANTA.Q_CAP(CHIPS)':
 C_PATH='@t6g_mb_lib.t6g(sch_1):page335_i89@pure_quanta.q_cap(chips)',
 P_PATH='@t6g_mb_lib.t6g(sch_1):page131_i89@pure_quanta.q_cap(chips)',
 PATH='I89',
 DRAWING='@T6G_MB_LIB.T6G(SCH_1):PAGE335',
 TOLERANCE='10%',
 MATERIAL='X7R',
 PHYS_PAGE='131',
 XY='(1500,1750)',
 ROT='0',
 VER='1',
 PACK_TYPE='0402',
 LOCATION='C21',
 CDS_LIB='pure_quanta',
 CDS_PART_NAME='Q_CAP_0402-0.1UF,25V,10%,X7R,CH4104K1B00',
 VOLTAGE='25V',
 PART_NUMBER='CH4104K1B00',
 VALUE='0.1UF',
 PRIM_FILE='./archive_libs/logical/q_cap/chips/chips.prt';

PART_NAME
 C22 'Q_CAP_C0402-0.01UF,50V,10%,EMPTY,CH31006KB18':;

SECTION_NUMBER 1
 '@T6G_MB_LIB.T6G(SCH_1):PAGE156_I113@PURE_QUANTA.Q_CAP(CHIPS)':
 C_PATH='@t6g_mb_lib.t6g(sch_1):page156_i113@pure_quanta.q_cap(chips)',
 P_PATH='@t6g_mb_lib.t6g(sch_1):page187_i113@pure_quanta.q_cap(chips)',
 PATH='I113',
 DRAWING='@T6G_MB_LIB.T6G(SCH_1):PAGE156',
 TOLERANCE='10%',
 MATERIAL='EMPTY',
 PHYS_PAGE='187',
 XY='(-3250,3375)',
 ROT='0',
 VER='1',
 PACK_TYPE='C0402',
 LOCATION='C22',
 CDS_LIB='pure_quanta',
 CDS_PART_NAME='Q_CAP_C0402-0.01UF,50V,10%,EMPTY,CH31006KB18',
 VOLTAGE='50V',
 PART_NUMBER='CH31006KB18',
 VALUE='0.01UF',
 PRIM_FILE='./archive_libs/logical/q_cap/chips/chips.prt';

PART_NAME
 C23 'Q_CAP_0402-0.1UF,25V,10%,X7R,CH4104K1B00':;

SECTION_NUMBER 1
 '@T6G_MB_LIB.T6G(SCH_1):PAGE137_I26@PURE_QUANTA.Q_CAP(CHIPS)':
 C_PATH='@t6g_mb_lib.t6g(sch_1):page137_i26@pure_quanta.q_cap(chips)',
 P_PATH='@t6g_mb_lib.t6g(sch_1):page160_i26@pure_quanta.q_cap(chips)',
 PATH='I26',
 DRAWING='@T6G_MB_LIB.T6G(SCH_1):PAGE137',
 TOLERANCE='10%',
 MATERIAL='X7R',
 PHYS_PAGE='160',
 XY='(-6650,2750)',
 ROT='0',
 VER='1',
 PACK_TYPE='0402',
 LOCATION='C23',
 CDS_LIB='pure_quanta',
 CDS_PART_NAME='Q_CAP_0402-0.1UF,25V,10%,X7R,CH4104K1B00',
 VOLTAGE='25V',
 PART_NUMBER='CH4104K1B00',
 VALUE='0.1UF',
 PRIM_FILE='./archive_libs/logical/q_cap/chips/chips.prt';

PART_NAME
 C24 'Q_CAP_C0402-10UF,6.3V,20%,EMPTY,CH6101MEB01':;

SECTION_NUMBER 1
 '@T6G_MB_LIB.T6G(SCH_1):PAGE138_I112@PURE_QUANTA.Q_CAP(CHIPS)':
 C_PATH='@t6g_mb_lib.t6g(sch_1):page138_i112@pure_quanta.q_cap(chips)',
 P_PATH='@t6g_mb_lib.t6g(sch_1):page161_i112@pure_quanta.q_cap(chips)',
 PATH='I112',
 DRAWING='@T6G_MB_LIB.T6G(SCH_1):PAGE138',
 TOLERANCE='20%',
 MATERIAL='EMPTY',
 PHYS_PAGE='161',
 XY='(700,4350)',
 ROT='2',
 VER='1',
 PACK_TYPE='C0402',
 LOCATION='C24',
 CDS_LIB='pure_quanta',
 CDS_PART_NAME='Q_CAP_C0402-10UF,6.3V,20%,EMPTY,CH6101MEB01',
 VOLTAGE='6.3V',
 PART_NUMBER='CH6101MEB01',
 VALUE='10UF',
 PRIM_FILE='./archive_libs/logical/q_cap/chips/chips.prt';

PART_NAME
 C25 'Q_CAP_0402-0.1UF,25V,10%,X7R,CH4104K1B00':;

SECTION_NUMBER 1
 '@T6G_MB_LIB.T6G(SCH_1):PAGE138_I69@PURE_QUANTA.Q_CAP(CHIPS)':
 C_PATH='@t6g_mb_lib.t6g(sch_1):page138_i69@pure_quanta.q_cap(chips)',
 P_PATH='@t6g_mb_lib.t6g(sch_1):page161_i69@pure_quanta.q_cap(chips)',
 PATH='I69',
 DRAWING='@T6G_MB_LIB.T6G(SCH_1):PAGE138',
 TOLERANCE='10%',
 MATERIAL='X7R',
 PHYS_PAGE='161',
 XY='(750,2350)',
 ROT='0',
 VER='1',
 PACK_TYPE='0402',
 LOCATION='C25',
 CDS_LIB='pure_quanta',
 CDS_PART_NAME='Q_CAP_0402-0.1UF,25V,10%,X7R,CH4104K1B00',
 VOLTAGE='25V',
 PART_NUMBER='CH4104K1B00',
 VALUE='0.1UF',
 PRIM_FILE='./archive_libs/logical/q_cap/chips/chips.prt';

PART_NAME
 C26 'Q_CAP_0402-0.1UF,25V,10%,X7R,CH4104K1B00':;

SECTION_NUMBER 1
 '@T6G_MB_LIB.T6G(SCH_1):PAGE137_I29@PURE_QUANTA.Q_CAP(CHIPS)':
 C_PATH='@t6g_mb_lib.t6g(sch_1):page137_i29@pure_quanta.q_cap(chips)',
 P_PATH='@t6g_mb_lib.t6g(sch_1):page160_i29@pure_quanta.q_cap(chips)',
 PATH='I29',
 DRAWING='@T6G_MB_LIB.T6G(SCH_1):PAGE137',
 TOLERANCE='10%',
 MATERIAL='X7R',
 PHYS_PAGE='160',
 XY='(-5325,2750)',
 ROT='0',
 VER='1',
 PACK_TYPE='0402',
 LOCATION='C26',
 CDS_LIB='pure_quanta',
 CDS_PART_NAME='Q_CAP_0402-0.1UF,25V,10%,X7R,CH4104K1B00',
 VOLTAGE='25V',
 PART_NUMBER='CH4104K1B00',
 VALUE='0.1UF',
 PRIM_FILE='./archive_libs/logical/q_cap/chips/chips.prt';

PART_NAME
 C27 'Q_CAP_0402-0.1UF,25V,10%,X7R,CH4104K1B00':;

SECTION_NUMBER 1
 '@T6G_MB_LIB.T6G(SCH_1):PAGE335_I163@PURE_QUANTA.Q_CAP(CHIPS)':
 C_PATH='@t6g_mb_lib.t6g(sch_1):page335_i163@pure_quanta.q_cap(chips)',
 P_PATH='@t6g_mb_lib.t6g(sch_1):page131_i163@pure_quanta.q_cap(chips)',
 PATH='I163',
 DRAWING='@T6G_MB_LIB.T6G(SCH_1):PAGE335',
 TOLERANCE='10%',
 MATERIAL='X7R',
 PHYS_PAGE='131',
 XY='(1775,1750)',
 ROT='0',
 VER='1',
 PACK_TYPE='0402',
 LOCATION='C27',
 CDS_LIB='pure_quanta',
 CDS_PART_NAME='Q_CAP_0402-0.1UF,25V,10%,X7R,CH4104K1B00',
 VOLTAGE='25V',
 PART_NUMBER='CH4104K1B00',
 VALUE='0.1UF',
 PRIM_FILE='./archive_libs/logical/q_cap/chips/chips.prt';

PART_NAME
 C28 'Q_CAP_C0402-10UF,6.3V,20%,X6S,CH6101MEB01':;

SECTION_NUMBER 1
 '@T6G_MB_LIB.T6G(SCH_1):PAGE379_I79@PURE_QUANTA.Q_CAP(CHIPS)':
 C_PATH='@t6g_mb_lib.t6g(sch_1):page379_i79@pure_quanta.q_cap(chips)',
 P_PATH='@t6g_mb_lib.t6g(sch_1):page183_i79@pure_quanta.q_cap(chips)',
 PATH='I79',
 DRAWING='@T6G_MB_LIB.T6G(SCH_1):PAGE379',
 TOLERANCE='20%',
 MATERIAL='X6S',
 PHYS_PAGE='183',
 XY='(-4600,5300)',
 ROT='0',
 VER='1',
 PACK_TYPE='C0402',
 LOCATION='C28',
 CDS_LIB='pure_quanta',
 CDS_PART_NAME='Q_CAP_C0402-10UF,6.3V,20%,X6S,CH6101MEB01',
 VOLTAGE='6.3V',
 PART_NUMBER='CH6101MEB01',
 VALUE='10UF',
 PRIM_FILE='./archive_libs/logical/q_cap/chips/chips.prt';

PART_NAME
 C29 'Q_CAP_C0402-0.22UF,25V,10%,X7R,CH4224K1B01':;

SECTION_NUMBER 1
 '@T6G_MB_LIB.T6G(SCH_1):PAGE273_I116@PURE_QUANTA.Q_CAP(CHIPS)':
 C_PATH='@t6g_mb_lib.t6g(sch_1):page273_i116@pure_quanta.q_cap(chips)',
 P_PATH='@t6g_mb_lib.t6g(sch_1):page188_i116@pure_quanta.q_cap(chips)',
 PATH='I116',
 DRAWING='@T6G_MB_LIB.T6G(SCH_1):PAGE273',
 TOLERANCE='10%',
 MATERIAL='X7R',
 PHYS_PAGE='188',
 XY='(325,4575)',
 ROT='0',
 VER='1',
 PACK_TYPE='C0402',
 LOCATION='C29',
 CDS_LIB='pure_quanta',
 CDS_PART_NAME='Q_CAP_C0402-0.22UF,25V,10%,X7R,CH4224K1B01',
 VOLTAGE='25V',
 PART_NUMBER='CH4224K1B01',
 VALUE='0.22UF',
 PRIM_FILE='./archive_libs/logical/q_cap/chips/chips.prt';

PART_NAME
 C30 'Q_CAP_0402-0.1UF,25V,10%,X7R,CH4104K1B00':;

SECTION_NUMBER 1
 '@T6G_MB_LIB.T6G(SCH_1):PAGE29_I379@PURE_QUANTA.Q_CAP(CHIPS)':
 C_PATH='@t6g_mb_lib.t6g(sch_1):page29_i379@pure_quanta.q_cap(chips)',
 P_PATH='@t6g_mb_lib.t6g(sch_1):page29_i379@pure_quanta.q_cap(chips)',
 PATH='I379',
 DRAWING='@T6G_MB_LIB.T6G(SCH_1):PAGE29',
 TOLERANCE='10%',
 MATERIAL='X7R',
 PHYS_PAGE='29',
 XY='(-3725,2475)',
 ROT='2',
 VER='1',
 PACK_TYPE='0402',
 LOCATION='C30',
 CDS_LIB='pure_quanta',
 CDS_PART_NAME='Q_CAP_0402-0.1UF,25V,10%,X7R,CH4104K1B00',
 VOLTAGE='25V',
 PART_NUMBER='CH4104K1B00',
 VALUE='0.1UF',
 PRIM_FILE='./archive_libs/logical/q_cap/chips/chips.prt';

PART_NAME
 C31 'Q_CAP_0402-0.1UF,25V,10%,X7R,CH4104K1B00':;

SECTION_NUMBER 1
 '@T6G_MB_LIB.T6G(SCH_1):PAGE359_I139@PURE_QUANTA.Q_CAP(CHIPS)':
 C_PATH='@t6g_mb_lib.t6g(sch_1):page359_i139@pure_quanta.q_cap(chips)',
 P_PATH='@t6g_mb_lib.t6g(sch_1):page235_i139@pure_quanta.q_cap(chips)',
 PATH='I139',
 DRAWING='@T6G_MB_LIB.T6G(SCH_1):PAGE359',
 TOLERANCE='10%',
 MATERIAL='X7R',
 PHYS_PAGE='235',
 XY='(2475,-2475)',
 ROT='2',
 VER='1',
 PACK_TYPE='0402',
 LOCATION='C31',
 CDS_LIB='pure_quanta',
 CDS_PART_NAME='Q_CAP_0402-0.1UF,25V,10%,X7R,CH4104K1B00',
 VOLTAGE='25V',
 PART_NUMBER='CH4104K1B00',
 VALUE='0.1UF',
 PRIM_FILE='./archive_libs/logical/q_cap/chips/chips.prt';

PART_NAME
 C32 'Q_CAP_0402-0.1UF,25V,10%,X7R,CH4104K1B00':;

SECTION_NUMBER 1
 '@T6G_MB_LIB.T6G(SCH_1):PAGE359_I119@PURE_QUANTA.Q_CAP(CHIPS)':
 C_PATH='@t6g_mb_lib.t6g(sch_1):page359_i119@pure_quanta.q_cap(chips)',
 P_PATH='@t6g_mb_lib.t6g(sch_1):page235_i119@pure_quanta.q_cap(chips)',
 PATH='I119',
 DRAWING='@T6G_MB_LIB.T6G(SCH_1):PAGE359',
 TOLERANCE='10%',
 MATERIAL='X7R',
 PHYS_PAGE='235',
 XY='(2525,-1000)',
 ROT='2',
 VER='1',
 PACK_TYPE='0402',
 LOCATION='C32',
 CDS_LIB='pure_quanta',
 CDS_PART_NAME='Q_CAP_0402-0.1UF,25V,10%,X7R,CH4104K1B00',
 VOLTAGE='25V',
 PART_NUMBER='CH4104K1B00',
 VALUE='0.1UF',
 PRIM_FILE='./archive_libs/logical/q_cap/chips/chips.prt';

PART_NAME
 C33 'Q_CAP_0402-0.1UF,25V,10%,X7R,CH4104K1B00':
 ROOM='ADC_TI_BOM1';

SECTION_NUMBER 1
 '@T6G_MB_LIB.T6G(SCH_1):PAGE369_I84@PURE_QUANTA.Q_CAP(CHIPS)':
 C_PATH='@t6g_mb_lib.t6g(sch_1):page369_i84@pure_quanta.q_cap(chips)',
 P_PATH='@t6g_mb_lib.t6g(sch_1):page257_i84@pure_quanta.q_cap(chips)',
 PATH='I84',
 DRAWING='@T6G_MB_LIB.T6G(SCH_1):PAGE369',
 TOLERANCE='10%',
 MATERIAL='X7R',
 PHYS_PAGE='257',
 XY='(-4975,4350)',
 ROT='2',
 VER='1',
 PACK_TYPE='0402',
 LOCATION='C33',
 CDS_LIB='pure_quanta',
 CDS_PART_NAME='Q_CAP_0402-0.1UF,25V,10%,X7R,CH4104K1B00',
 VOLTAGE='25V',
 ROOM='ADC_TI_BOM1',
 PART_NUMBER='CH4104K1B00',
 VALUE='0.1UF',
 PRIM_FILE='./archive_libs/logical/q_cap/chips/chips.prt';

PART_NAME
 C34 'Q_CAP_C0805-22UF,16V,20%,X6S,CH6223MEA00':;

SECTION_NUMBER 1
 '@T6G_MB_LIB.T6G(SCH_1):PAGE335_I88@PURE_QUANTA.Q_CAP(CHIPS)':
 C_PATH='@t6g_mb_lib.t6g(sch_1):page335_i88@pure_quanta.q_cap(chips)',
 P_PATH='@t6g_mb_lib.t6g(sch_1):page131_i88@pure_quanta.q_cap(chips)',
 PATH='I88',
 DRAWING='@T6G_MB_LIB.T6G(SCH_1):PAGE335',
 TOLERANCE='20%',
 MATERIAL='X6S',
 PHYS_PAGE='131',
 XY='(1100,1750)',
 ROT='0',
 VER='1',
 PACK_TYPE='C0805',
 LOCATION='C34',
 CDS_LIB='pure_quanta',
 CDS_PART_NAME='Q_CAP_C0805-22UF,16V,20%,X6S,CH6223MEA00',
 VOLTAGE='16V',
 PART_NUMBER='CH6223MEA00',
 VALUE='22UF',
 PRIM_FILE='./archive_libs/logical/q_cap/chips/chips.prt';

PART_NAME
 C35 'Q_CAP_0402-100PF,50V,5%,EMPTY,CH11006JB18':
 ROOM='ADC_MAM_BOM2';

SECTION_NUMBER 1
 '@T6G_MB_LIB.T6G(SCH_1):PAGE369_I78@PURE_QUANTA.Q_CAP(CHIPS)':
 C_PATH='@t6g_mb_lib.t6g(sch_1):page369_i78@pure_quanta.q_cap(chips)',
 P_PATH='@t6g_mb_lib.t6g(sch_1):page257_i78@pure_quanta.q_cap(chips)',
 PATH='I78',
 DRAWING='@T6G_MB_LIB.T6G(SCH_1):PAGE369',
 TOLERANCE='5%',
 MATERIAL='EMPTY',
 PHYS_PAGE='257',
 XY='(-4975,3875)',
 ROT='0',
 VER='1',
 PACK_TYPE='0402',
 LOCATION='C35',
 CDS_LIB='pure_quanta',
 CDS_PART_NAME='Q_CAP_0402-100PF,50V,5%,EMPTY,CH11006JB18',
 VOLTAGE='50V',
 ROOM='ADC_MAM_BOM2',
 PART_NUMBER='CH11006JB18',
 VALUE='100PF',
 PRIM_FILE='./archive_libs/logical/q_cap/chips/chips.prt';

PART_NAME
 C36 'Q_CAP_0402-0.1UF,25V,10%,X7R,CH4104K1B00':;

SECTION_NUMBER 1
 '@T6G_MB_LIB.T6G(SCH_1):PAGE337_I33@PURE_QUANTA.Q_CAP(CHIPS)':
 C_PATH='@t6g_mb_lib.t6g(sch_1):page337_i33@pure_quanta.q_cap(chips)',
 P_PATH='@t6g_mb_lib.t6g(sch_1):page133_i33@pure_quanta.q_cap(chips)',
 PATH='I33',
 DRAWING='@T6G_MB_LIB.T6G(SCH_1):PAGE337',
 TOLERANCE='10%',
 MATERIAL='X7R',
 PHYS_PAGE='133',
 XY='(-7900,4800)',
 ROT='0',
 VER='1',
 PACK_TYPE='0402',
 LOCATION='C36',
 CDS_LIB='pure_quanta',
 CDS_PART_NAME='Q_CAP_0402-0.1UF,25V,10%,X7R,CH4104K1B00',
 VOLTAGE='25V',
 PART_NUMBER='CH4104K1B00',
 VALUE='0.1UF',
 PRIM_FILE='./archive_libs/logical/q_cap/chips/chips.prt';

PART_NAME
 C37 'Q_CAP_0402-0.1UF,25V,10%,X7R,CH4104K1B00':
 ROOM='ADC_TI_BOM1';

SECTION_NUMBER 1
 '@T6G_MB_LIB.T6G(SCH_1):PAGE369_I112@PURE_QUANTA.Q_CAP(CHIPS)':
 C_PATH='@t6g_mb_lib.t6g(sch_1):page369_i112@pure_quanta.q_cap(chips)',
 P_PATH='@t6g_mb_lib.t6g(sch_1):page257_i112@pure_quanta.q_cap(chips)',
 PATH='I112',
 DRAWING='@T6G_MB_LIB.T6G(SCH_1):PAGE369',
 TOLERANCE='10%',
 MATERIAL='X7R',
 PHYS_PAGE='257',
 XY='(-4950,5325)',
 ROT='2',
 VER='1',
 PACK_TYPE='0402',
 LOCATION='C37',
 CDS_LIB='pure_quanta',
 CDS_PART_NAME='Q_CAP_0402-0.1UF,25V,10%,X7R,CH4104K1B00',
 VOLTAGE='25V',
 ROOM='ADC_TI_BOM1',
 PART_NUMBER='CH4104K1B00',
 VALUE='0.1UF',
 PRIM_FILE='./archive_libs/logical/q_cap/chips/chips.prt';

PART_NAME
 C38 'Q_CAP_0402-0.1UF,25V,10%,X7R,CH4104K1B00':;

SECTION_NUMBER 1
 '@T6G_MB_LIB.T6G(SCH_1):PAGE342_I47@PURE_QUANTA.Q_CAP(CHIPS)':
 C_PATH='@t6g_mb_lib.t6g(sch_1):page342_i47@pure_quanta.q_cap(chips)',
 P_PATH='@t6g_mb_lib.t6g(sch_1):page139_i47@pure_quanta.q_cap(chips)',
 PATH='I47',
 DRAWING='@T6G_MB_LIB.T6G(SCH_1):PAGE342',
 TOLERANCE='10%',
 MATERIAL='X7R',
 PHYS_PAGE='139',
 XY='(10775,-3150)',
 ROT='0',
 VER='1',
 PACK_TYPE='0402',
 LOCATION='C38',
 CDS_LIB='pure_quanta',
 CDS_PART_NAME='Q_CAP_0402-0.1UF,25V,10%,X7R,CH4104K1B00',
 VOLTAGE='25V',
 PART_NUMBER='CH4104K1B00',
 VALUE='0.1UF',
 PRIM_FILE='./archive_libs/logical/q_cap/chips/chips.prt';

PART_NAME
 C39 'Q_CAP_C0402-1UF,25V,10%,X6S,CH5104KEB02':
 ROOM='NIC_P3V3_BOM1';

SECTION_NUMBER 1
 '@T6G_MB_LIB.T6G(SCH_1):PAGE343_I90@PURE_QUANTA.Q_CAP(CHIPS)':
 C_PATH='@t6g_mb_lib.t6g(sch_1):page343_i90@pure_quanta.q_cap(chips)',
 P_PATH='@t6g_mb_lib.t6g(sch_1):page140_i90@pure_quanta.q_cap(chips)',
 PATH='I90',
 DRAWING='@T6G_MB_LIB.T6G(SCH_1):PAGE343',
 TOLERANCE='10%',
 MATERIAL='X6S',
 PHYS_PAGE='140',
 XY='(300,8925)',
 ROT='0',
 VER='1',
 PACK_TYPE='C0402',
 LOCATION='C39',
 CDS_LIB='pure_quanta',
 CDS_PART_NAME='Q_CAP_C0402-1UF,25V,10%,X6S,CH5104KEB02',
 VOLTAGE='25V',
 ROOM='NIC_P3V3_BOM1',
 PART_NUMBER='CH5104KEB02',
 VALUE='1UF',
 PRIM_FILE='./archive_libs/logical/q_cap/chips/chips.prt';

PART_NAME
 C40 'Q_CAP_C0402-0.01UF,50V,10%,EMPTY,CH31006KB18':
 ROOM='NIC_P12V_MAM_TIC_BOM1';

SECTION_NUMBER 1
 '@T6G_MB_LIB.T6G(SCH_1):PAGE343_I72@PURE_QUANTA.Q_CAP(CHIPS)':
 C_PATH='@t6g_mb_lib.t6g(sch_1):page343_i72@pure_quanta.q_cap(chips)',
 P_PATH='@t6g_mb_lib.t6g(sch_1):page140_i72@pure_quanta.q_cap(chips)',
 PATH='I72',
 DRAWING='@T6G_MB_LIB.T6G(SCH_1):PAGE343',
 TOLERANCE='10%',
 MATERIAL='EMPTY',
 PHYS_PAGE='140',
 XY='(2275,6625)',
 ROT='0',
 VER='1',
 PACK_TYPE='C0402',
 LOCATION='C40',
 CDS_LIB='pure_quanta',
 CDS_PART_NAME='Q_CAP_C0402-0.01UF,50V,10%,EMPTY,CH31006KB18',
 VOLTAGE='50V',
 ROOM='NIC_P12V_MAM_TIC_BOM1',
 PART_NUMBER='CH31006KB18',
 VALUE='0.01UF',
 PRIM_FILE='./archive_libs/logical/q_cap/chips/chips.prt';

PART_NAME
 C41 'Q_CAP_DIFFBUS_C0201-DIFF BUS_0.22UF,6.3V,20%,X6S,SA':;

SECTION_NUMBER 1
 '@T6G_MB_LIB.T6G(SCH_1):PAGE353_I268@PURE_QUANTA.Q_CAP_DIFFBUS(CHIPS)':
 C_PATH='@t6g_mb_lib.t6g(sch_1):page353_i268@pure_quanta.q_cap_diffbus(chips)',
 P_PATH='@t6g_mb_lib.t6g(sch_1):page65_i268@pure_quanta.q_cap_diffbus(chips)',
 PATH='I268',
 DRAWING='@T6G_MB_LIB.T6G(SCH_1):PAGE353',
 PIN_NAMES_ROTATE='TRUE',
 TOLERANCE='20%',
 MATERIAL='X6S',
 PHYS_PAGE='65',
 XY='(-925,2975)',
 ROT='2',
 VER='2',
 PACK_TYPE='C0201',
 LOCATION='C41',
 CDS_LIB='pure_quanta',
 CDS_PART_NAME='Q_CAP_DIFFBUS_C0201-DIFF BUS_0.22UF,6.3V,20%,X6S,SA',
 VOLTAGE='6.3V',
 PART_NUMBER='SP_CH4221MEE01',
 VALUE='DIFF BUS_0.22UF',
 PRIM_FILE='./archive_libs/logical/q_cap_diffbus/chips/chips.prt';

PART_NAME
 C42 'Q_CAP_0402-0.1UF,25V,10%,X7R,CH4104K1B00':;

SECTION_NUMBER 1
 '@T6G_MB_LIB.T6G(SCH_1):PAGE34_I44@PURE_QUANTA.Q_CAP(CHIPS)':
 C_PATH='@t6g_mb_lib.t6g(sch_1):page34_i44@pure_quanta.q_cap(chips)',
 P_PATH='@t6g_mb_lib.t6g(sch_1):page34_i44@pure_quanta.q_cap(chips)',
 PATH='I44',
 DRAWING='@T6G_MB_LIB.T6G(SCH_1):PAGE34',
 TOLERANCE='10%',
 MATERIAL='X7R',
 PHYS_PAGE='34',
 XY='(-7875,6025)',
 ROT='0',
 VER='1',
 PACK_TYPE='0402',
 LOCATION='C42',
 CDS_LIB='pure_quanta',
 CDS_PART_NAME='Q_CAP_0402-0.1UF,25V,10%,X7R,CH4104K1B00',
 VOLTAGE='25V',
 PART_NUMBER='CH4104K1B00',
 VALUE='0.1UF',
 PRIM_FILE='./archive_libs/logical/q_cap/chips/chips.prt';

PART_NAME
 C43 'Q_CAP_0402-0.1UF,25V,10%,X7R,CH4104K1B00':;

SECTION_NUMBER 1
 '@T6G_MB_LIB.T6G(SCH_1):PAGE34_I47@PURE_QUANTA.Q_CAP(CHIPS)':
 C_PATH='@t6g_mb_lib.t6g(sch_1):page34_i47@pure_quanta.q_cap(chips)',
 P_PATH='@t6g_mb_lib.t6g(sch_1):page34_i47@pure_quanta.q_cap(chips)',
 PATH='I47',
 DRAWING='@T6G_MB_LIB.T6G(SCH_1):PAGE34',
 TOLERANCE='10%',
 MATERIAL='X7R',
 PHYS_PAGE='34',
 XY='(-6550,6025)',
 ROT='0',
 VER='1',
 PACK_TYPE='0402',
 LOCATION='C43',
 CDS_LIB='pure_quanta',
 CDS_PART_NAME='Q_CAP_0402-0.1UF,25V,10%,X7R,CH4104K1B00',
 VOLTAGE='25V',
 PART_NUMBER='CH4104K1B00',
 VALUE='0.1UF',
 PRIM_FILE='./archive_libs/logical/q_cap/chips/chips.prt';

PART_NAME
 C44 'Q_CAP_DIFFBUS_C0201-DIFF BUS_0.22UF,6.3V,20%,X6S,SA':;

SECTION_NUMBER 1
 '@T6G_MB_LIB.T6G(SCH_1):PAGE353_I259@PURE_QUANTA.Q_CAP_DIFFBUS(CHIPS)':
 C_PATH='@t6g_mb_lib.t6g(sch_1):page353_i259@pure_quanta.q_cap_diffbus(chips)',
 P_PATH='@t6g_mb_lib.t6g(sch_1):page65_i259@pure_quanta.q_cap_diffbus(chips)',
 PATH='I259',
 DRAWING='@T6G_MB_LIB.T6G(SCH_1):PAGE353',
 PIN_NAMES_ROTATE='TRUE',
 TOLERANCE='20%',
 MATERIAL='X6S',
 PHYS_PAGE='65',
 XY='(-925,2125)',
 ROT='2',
 VER='2',
 PACK_TYPE='C0201',
 LOCATION='C44',
 CDS_LIB='pure_quanta',
 CDS_PART_NAME='Q_CAP_DIFFBUS_C0201-DIFF BUS_0.22UF,6.3V,20%,X6S,SA',
 VOLTAGE='6.3V',
 PART_NUMBER='SP_CH4221MEE01',
 VALUE='DIFF BUS_0.22UF',
 PRIM_FILE='./archive_libs/logical/q_cap_diffbus/chips/chips.prt';

PART_NAME
 C45 'Q_CAP_C0402-1UF,25V,10%,X6S,CH5104KEB02':;

SECTION_NUMBER 1
 '@T6G_MB_LIB.T6G(SCH_1):PAGE156_I107@PURE_QUANTA.Q_CAP(CHIPS)':
 C_PATH='@t6g_mb_lib.t6g(sch_1):page156_i107@pure_quanta.q_cap(chips)',
 P_PATH='@t6g_mb_lib.t6g(sch_1):page187_i107@pure_quanta.q_cap(chips)',
 PATH='I107',
 DRAWING='@T6G_MB_LIB.T6G(SCH_1):PAGE156',
 TOLERANCE='10%',
 MATERIAL='X6S',
 PHYS_PAGE='187',
 XY='(-5425,6775)',
 ROT='2',
 VER='1',
 PACK_TYPE='C0402',
 LOCATION='C45',
 CDS_LIB='pure_quanta',
 CDS_PART_NAME='Q_CAP_C0402-1UF,25V,10%,X6S,CH5104KEB02',
 VOLTAGE='25V',
 PART_NUMBER='CH5104KEB02',
 VALUE='1UF',
 PRIM_FILE='./archive_libs/logical/q_cap/chips/chips.prt';

PART_NAME
 C46 'Q_CAP_DIFFBUS_C0201-DIFF BUS_0.22UF,6.3V,20%,X6S,SA':;

SECTION_NUMBER 1
 '@T6G_MB_LIB.T6G(SCH_1):PAGE353_I242@PURE_QUANTA.Q_CAP_DIFFBUS(CHIPS)':
 C_PATH='@t6g_mb_lib.t6g(sch_1):page353_i242@pure_quanta.q_cap_diffbus(chips)',
 P_PATH='@t6g_mb_lib.t6g(sch_1):page65_i242@pure_quanta.q_cap_diffbus(chips)',
 PATH='I242',
 DRAWING='@T6G_MB_LIB.T6G(SCH_1):PAGE353',
 PIN_NAMES_ROTATE='TRUE',
 TOLERANCE='20%',
 MATERIAL='X6S',
 PHYS_PAGE='65',
 XY='(-925,1600)',
 ROT='2',
 VER='2',
 PACK_TYPE='C0201',
 LOCATION='C46',
 CDS_LIB='pure_quanta',
 CDS_PART_NAME='Q_CAP_DIFFBUS_C0201-DIFF BUS_0.22UF,6.3V,20%,X6S,SA',
 VOLTAGE='6.3V',
 PART_NUMBER='SP_CH4221MEE01',
 VALUE='DIFF BUS_0.22UF',
 PRIM_FILE='./archive_libs/logical/q_cap_diffbus/chips/chips.prt';

PART_NAME
 C47 'Q_CAP_DIFFBUS_C0201-DIFF BUS_0.22UF,6.3V,20%,X6S,SA':;

SECTION_NUMBER 1
 '@T6G_MB_LIB.T6G(SCH_1):PAGE353_I239@PURE_QUANTA.Q_CAP_DIFFBUS(CHIPS)':
 C_PATH='@t6g_mb_lib.t6g(sch_1):page353_i239@pure_quanta.q_cap_diffbus(chips)',
 P_PATH='@t6g_mb_lib.t6g(sch_1):page65_i239@pure_quanta.q_cap_diffbus(chips)',
 PATH='I239',
 DRAWING='@T6G_MB_LIB.T6G(SCH_1):PAGE353',
 PIN_NAMES_ROTATE='TRUE',
 TOLERANCE='20%',
 MATERIAL='X6S',
 PHYS_PAGE='65',
 XY='(-925,1350)',
 ROT='2',
 VER='2',
 PACK_TYPE='C0201',
 LOCATION='C47',
 CDS_LIB='pure_quanta',
 CDS_PART_NAME='Q_CAP_DIFFBUS_C0201-DIFF BUS_0.22UF,6.3V,20%,X6S,SA',
 VOLTAGE='6.3V',
 PART_NUMBER='SP_CH4221MEE01',
 VALUE='DIFF BUS_0.22UF',
 PRIM_FILE='./archive_libs/logical/q_cap_diffbus/chips/chips.prt';

PART_NAME
 C48 'Q_CAP_DIFFBUS_C0201-DIFF BUS_0.22UF,6.3V,20%,X6S,SA':;

SECTION_NUMBER 1
 '@T6G_MB_LIB.T6G(SCH_1):PAGE355_I119@PURE_QUANTA.Q_CAP_DIFFBUS(CHIPS)':
 C_PATH='@t6g_mb_lib.t6g(sch_1):page355_i119@pure_quanta.q_cap_diffbus(chips)',
 P_PATH='@t6g_mb_lib.t6g(sch_1):page67_i119@pure_quanta.q_cap_diffbus(chips)',
 PATH='I119',
 DRAWING='@T6G_MB_LIB.T6G(SCH_1):PAGE355',
 PIN_NAMES_ROTATE='TRUE',
 TOLERANCE='20%',
 MATERIAL='X6S',
 PHYS_PAGE='67',
 XY='(-1500,4500)',
 ROT='2',
 VER='2',
 PACK_TYPE='C0201',
 LOCATION='C48',
 CDS_LIB='pure_quanta',
 CDS_PART_NAME='Q_CAP_DIFFBUS_C0201-DIFF BUS_0.22UF,6.3V,20%,X6S,SA',
 VOLTAGE='6.3V',
 PART_NUMBER='SP_CH4221MEE01',
 VALUE='DIFF BUS_0.22UF',
 PRIM_FILE='./archive_libs/logical/q_cap_diffbus/chips/chips.prt';

PART_NAME
 C49 'Q_CAP_DIFFBUS_C0201-DIFF BUS_0.22UF,6.3V,20%,X6S,SA':;

SECTION_NUMBER 1
 '@T6G_MB_LIB.T6G(SCH_1):PAGE355_I120@PURE_QUANTA.Q_CAP_DIFFBUS(CHIPS)':
 C_PATH='@t6g_mb_lib.t6g(sch_1):page355_i120@pure_quanta.q_cap_diffbus(chips)',
 P_PATH='@t6g_mb_lib.t6g(sch_1):page67_i120@pure_quanta.q_cap_diffbus(chips)',
 PATH='I120',
 DRAWING='@T6G_MB_LIB.T6G(SCH_1):PAGE355',
 PIN_NAMES_ROTATE='TRUE',
 TOLERANCE='20%',
 MATERIAL='X6S',
 PHYS_PAGE='67',
 XY='(-1500,4450)',
 ROT='2',
 VER='2',
 PACK_TYPE='C0201',
 LOCATION='C49',
 CDS_LIB='pure_quanta',
 CDS_PART_NAME='Q_CAP_DIFFBUS_C0201-DIFF BUS_0.22UF,6.3V,20%,X6S,SA',
 VOLTAGE='6.3V',
 PART_NUMBER='SP_CH4221MEE01',
 VALUE='DIFF BUS_0.22UF',
 PRIM_FILE='./archive_libs/logical/q_cap_diffbus/chips/chips.prt';

PART_NAME
 C50 'Q_CAP_DIFFBUS_C0201-DIFF BUS_0.22UF,6.3V,20%,X6S,SA':;

SECTION_NUMBER 1
 '@T6G_MB_LIB.T6G(SCH_1):PAGE355_I118@PURE_QUANTA.Q_CAP_DIFFBUS(CHIPS)':
 C_PATH='@t6g_mb_lib.t6g(sch_1):page355_i118@pure_quanta.q_cap_diffbus(chips)',
 P_PATH='@t6g_mb_lib.t6g(sch_1):page67_i118@pure_quanta.q_cap_diffbus(chips)',
 PATH='I118',
 DRAWING='@T6G_MB_LIB.T6G(SCH_1):PAGE355',
 PIN_NAMES_ROTATE='TRUE',
 TOLERANCE='20%',
 MATERIAL='X6S',
 PHYS_PAGE='67',
 XY='(-1500,4300)',
 ROT='2',
 VER='2',
 PACK_TYPE='C0201',
 LOCATION='C50',
 CDS_LIB='pure_quanta',
 CDS_PART_NAME='Q_CAP_DIFFBUS_C0201-DIFF BUS_0.22UF,6.3V,20%,X6S,SA',
 VOLTAGE='6.3V',
 PART_NUMBER='SP_CH4221MEE01',
 VALUE='DIFF BUS_0.22UF',
 PRIM_FILE='./archive_libs/logical/q_cap_diffbus/chips/chips.prt';

PART_NAME
 C51 'Q_CAP_DIFFBUS_C0201-DIFF BUS_0.22UF,6.3V,20%,X6S,SA':;

SECTION_NUMBER 1
 '@T6G_MB_LIB.T6G(SCH_1):PAGE355_I117@PURE_QUANTA.Q_CAP_DIFFBUS(CHIPS)':
 C_PATH='@t6g_mb_lib.t6g(sch_1):page355_i117@pure_quanta.q_cap_diffbus(chips)',
 P_PATH='@t6g_mb_lib.t6g(sch_1):page67_i117@pure_quanta.q_cap_diffbus(chips)',
 PATH='I117',
 DRAWING='@T6G_MB_LIB.T6G(SCH_1):PAGE355',
 PIN_NAMES_ROTATE='TRUE',
 TOLERANCE='20%',
 MATERIAL='X6S',
 PHYS_PAGE='67',
 XY='(-1500,4250)',
 ROT='2',
 VER='2',
 PACK_TYPE='C0201',
 LOCATION='C51',
 CDS_LIB='pure_quanta',
 CDS_PART_NAME='Q_CAP_DIFFBUS_C0201-DIFF BUS_0.22UF,6.3V,20%,X6S,SA',
 VOLTAGE='6.3V',
 PART_NUMBER='SP_CH4221MEE01',
 VALUE='DIFF BUS_0.22UF',
 PRIM_FILE='./archive_libs/logical/q_cap_diffbus/chips/chips.prt';

PART_NAME
 C52 'Q_CAP_DIFFBUS_C0201-DIFF BUS_0.22UF,6.3V,20%,X6S,SA':;

SECTION_NUMBER 1
 '@T6G_MB_LIB.T6G(SCH_1):PAGE355_I116@PURE_QUANTA.Q_CAP_DIFFBUS(CHIPS)':
 C_PATH='@t6g_mb_lib.t6g(sch_1):page355_i116@pure_quanta.q_cap_diffbus(chips)',
 P_PATH='@t6g_mb_lib.t6g(sch_1):page67_i116@pure_quanta.q_cap_diffbus(chips)',
 PATH='I116',
 DRAWING='@T6G_MB_LIB.T6G(SCH_1):PAGE355',
 PIN_NAMES_ROTATE='TRUE',
 TOLERANCE='20%',
 MATERIAL='X6S',
 PHYS_PAGE='67',
 XY='(-1500,4100)',
 ROT='2',
 VER='2',
 PACK_TYPE='C0201',
 LOCATION='C52',
 CDS_LIB='pure_quanta',
 CDS_PART_NAME='Q_CAP_DIFFBUS_C0201-DIFF BUS_0.22UF,6.3V,20%,X6S,SA',
 VOLTAGE='6.3V',
 PART_NUMBER='SP_CH4221MEE01',
 VALUE='DIFF BUS_0.22UF',
 PRIM_FILE='./archive_libs/logical/q_cap_diffbus/chips/chips.prt';

PART_NAME
 C53 'Q_CAP_DIFFBUS_C0201-DIFF BUS_0.22UF,6.3V,20%,X6S,SA':;

SECTION_NUMBER 1
 '@T6G_MB_LIB.T6G(SCH_1):PAGE355_I107@PURE_QUANTA.Q_CAP_DIFFBUS(CHIPS)':
 C_PATH='@t6g_mb_lib.t6g(sch_1):page355_i107@pure_quanta.q_cap_diffbus(chips)',
 P_PATH='@t6g_mb_lib.t6g(sch_1):page67_i107@pure_quanta.q_cap_diffbus(chips)',
 PATH='I107',
 DRAWING='@T6G_MB_LIB.T6G(SCH_1):PAGE355',
 PIN_NAMES_ROTATE='TRUE',
 TOLERANCE='20%',
 MATERIAL='X6S',
 PHYS_PAGE='67',
 XY='(-1500,4050)',
 ROT='2',
 VER='2',
 PACK_TYPE='C0201',
 LOCATION='C53',
 CDS_LIB='pure_quanta',
 CDS_PART_NAME='Q_CAP_DIFFBUS_C0201-DIFF BUS_0.22UF,6.3V,20%,X6S,SA',
 VOLTAGE='6.3V',
 PART_NUMBER='SP_CH4221MEE01',
 VALUE='DIFF BUS_0.22UF',
 PRIM_FILE='./archive_libs/logical/q_cap_diffbus/chips/chips.prt';

PART_NAME
 C54 'Q_CAP_DIFFBUS_C0201-DIFF BUS_0.22UF,6.3V,20%,X6S,SA':;

SECTION_NUMBER 1
 '@T6G_MB_LIB.T6G(SCH_1):PAGE355_I86@PURE_QUANTA.Q_CAP_DIFFBUS(CHIPS)':
 C_PATH='@t6g_mb_lib.t6g(sch_1):page355_i86@pure_quanta.q_cap_diffbus(chips)',
 P_PATH='@t6g_mb_lib.t6g(sch_1):page67_i86@pure_quanta.q_cap_diffbus(chips)',
 PATH='I86',
 DRAWING='@T6G_MB_LIB.T6G(SCH_1):PAGE355',
 PIN_NAMES_ROTATE='TRUE',
 TOLERANCE='20%',
 MATERIAL='X6S',
 PHYS_PAGE='67',
 XY='(-1500,3900)',
 ROT='2',
 VER='2',
 PACK_TYPE='C0201',
 LOCATION='C54',
 CDS_LIB='pure_quanta',
 CDS_PART_NAME='Q_CAP_DIFFBUS_C0201-DIFF BUS_0.22UF,6.3V,20%,X6S,SA',
 VOLTAGE='6.3V',
 PART_NUMBER='SP_CH4221MEE01',
 VALUE='DIFF BUS_0.22UF',
 PRIM_FILE='./archive_libs/logical/q_cap_diffbus/chips/chips.prt';

PART_NAME
 C55 'Q_CAP_DIFFBUS_C0201-DIFF BUS_0.22UF,6.3V,20%,X6S,SA':;

SECTION_NUMBER 1
 '@T6G_MB_LIB.T6G(SCH_1):PAGE355_I85@PURE_QUANTA.Q_CAP_DIFFBUS(CHIPS)':
 C_PATH='@t6g_mb_lib.t6g(sch_1):page355_i85@pure_quanta.q_cap_diffbus(chips)',
 P_PATH='@t6g_mb_lib.t6g(sch_1):page67_i85@pure_quanta.q_cap_diffbus(chips)',
 PATH='I85',
 DRAWING='@T6G_MB_LIB.T6G(SCH_1):PAGE355',
 PIN_NAMES_ROTATE='TRUE',
 TOLERANCE='20%',
 MATERIAL='X6S',
 PHYS_PAGE='67',
 XY='(-1500,3850)',
 ROT='2',
 VER='2',
 PACK_TYPE='C0201',
 LOCATION='C55',
 CDS_LIB='pure_quanta',
 CDS_PART_NAME='Q_CAP_DIFFBUS_C0201-DIFF BUS_0.22UF,6.3V,20%,X6S,SA',
 VOLTAGE='6.3V',
 PART_NUMBER='SP_CH4221MEE01',
 VALUE='DIFF BUS_0.22UF',
 PRIM_FILE='./archive_libs/logical/q_cap_diffbus/chips/chips.prt';

PART_NAME
 C56 'Q_CAP_DIFFBUS_C0201-DIFF BUS_0.22UF,6.3V,20%,X6S,SA':;

SECTION_NUMBER 1
 '@T6G_MB_LIB.T6G(SCH_1):PAGE355_I216@PURE_QUANTA.Q_CAP_DIFFBUS(CHIPS)':
 C_PATH='@t6g_mb_lib.t6g(sch_1):page355_i216@pure_quanta.q_cap_diffbus(chips)',
 P_PATH='@t6g_mb_lib.t6g(sch_1):page67_i216@pure_quanta.q_cap_diffbus(chips)',
 PATH='I216',
 DRAWING='@T6G_MB_LIB.T6G(SCH_1):PAGE355',
 PIN_NAMES_ROTATE='TRUE',
 TOLERANCE='20%',
 MATERIAL='X6S',
 PHYS_PAGE='67',
 XY='(3125,3050)',
 ROT='2',
 VER='2',
 PACK_TYPE='C0201',
 LOCATION='C56',
 CDS_LIB='pure_quanta',
 CDS_PART_NAME='Q_CAP_DIFFBUS_C0201-DIFF BUS_0.22UF,6.3V,20%,X6S,SA',
 VOLTAGE='6.3V',
 PART_NUMBER='SP_CH4221MEE01',
 VALUE='DIFF BUS_0.22UF',
 PRIM_FILE='./archive_libs/logical/q_cap_diffbus/chips/chips.prt';

PART_NAME
 C57 'Q_CAP_C0805-10UF,16V,10%,EMPTY,CH6103KEA00':
 REUSE_ID='8';

SECTION_NUMBER 1
 '@T6G_MB_LIB.T6G(SCH_1):PAGE273_I20@PURE_QUANTA.Q_CAP(CHIPS)':
 C_PATH='@t6g_mb_lib.t6g(sch_1):page273_i20@pure_quanta.q_cap(chips)',
 P_PATH='@t6g_mb_lib.t6g(sch_1):page188_i20@pure_quanta.q_cap(chips)',
 PATH='I20',
 DRAWING='@T6G_MB_LIB.T6G(SCH_1):PAGE273',
 BOM_COST='VR_SYSTEM ',
 TOLERANCE='10%',
 MATERIAL='EMPTY',
 PHYS_PAGE='188',
 XY='(-5325,7575)',
 ROT='2',
 VER='1',
 PACK_TYPE='C0805',
 LOCATION='C57',
 CDS_LIB='pure_quanta',
 CDS_PART_NAME='Q_CAP_C0805-10UF,16V,10%,EMPTY,CH6103KEA00',
 REUSE_ID='8',
 VOLTAGE='16V',
 PART_NUMBER='CH6103KEA00',
 VALUE='10UF',
 PRIM_FILE='./archive_libs/logical/q_cap/chips/chips.prt';

PART_NAME
 C58 'Q_CAP_0402-0.1UF,25V,10%,X7R,CH4104K1B00':;

SECTION_NUMBER 1
 '@T6G_MB_LIB.T6G(SCH_1):PAGE379_I34@PURE_QUANTA.Q_CAP(CHIPS)':
 C_PATH='@t6g_mb_lib.t6g(sch_1):page379_i34@pure_quanta.q_cap(chips)',
 P_PATH='@t6g_mb_lib.t6g(sch_1):page183_i34@pure_quanta.q_cap(chips)',
 PATH='I34',
 DRAWING='@T6G_MB_LIB.T6G(SCH_1):PAGE379',
 TOLERANCE='10%',
 MATERIAL='X7R',
 PHYS_PAGE='183',
 XY='(-4250,5300)',
 ROT='0',
 VER='1',
 PACK_TYPE='0402',
 LOCATION='C58',
 CDS_LIB='pure_quanta',
 CDS_PART_NAME='Q_CAP_0402-0.1UF,25V,10%,X7R,CH4104K1B00',
 VOLTAGE='25V',
 PART_NUMBER='CH4104K1B00',
 VALUE='0.1UF',
 PRIM_FILE='./archive_libs/logical/q_cap/chips/chips.prt';

PART_NAME
 C59 'Q_CAP_0402-100PF,50V,5%,EMPTY,CH11006JB18':
 ROOM='ADC_MAM_BOM2';

SECTION_NUMBER 1
 '@T6G_MB_LIB.T6G(SCH_1):PAGE369_I87@PURE_QUANTA.Q_CAP(CHIPS)':
 C_PATH='@t6g_mb_lib.t6g(sch_1):page369_i87@pure_quanta.q_cap(chips)',
 P_PATH='@t6g_mb_lib.t6g(sch_1):page257_i87@pure_quanta.q_cap(chips)',
 PATH='I87',
 DRAWING='@T6G_MB_LIB.T6G(SCH_1):PAGE369',
 TOLERANCE='5%',
 MATERIAL='EMPTY',
 PHYS_PAGE='257',
 XY='(-4950,4875)',
 ROT='0',
 VER='1',
 PACK_TYPE='0402',
 LOCATION='C59',
 CDS_LIB='pure_quanta',
 CDS_PART_NAME='Q_CAP_0402-100PF,50V,5%,EMPTY,CH11006JB18',
 VOLTAGE='50V',
 ROOM='ADC_MAM_BOM2',
 PART_NUMBER='CH11006JB18',
 VALUE='100PF',
 PRIM_FILE='./archive_libs/logical/q_cap/chips/chips.prt';

PART_NAME
 C60 'Q_CAP_C0805-10UF,16V,10%,EMPTY,CH6103KEA00':;

SECTION_NUMBER 1
 '@T6G_MB_LIB.T6G(SCH_1):PAGE273_I51@PURE_QUANTA.Q_CAP(CHIPS)':
 C_PATH='@t6g_mb_lib.t6g(sch_1):page273_i51@pure_quanta.q_cap(chips)',
 P_PATH='@t6g_mb_lib.t6g(sch_1):page188_i51@pure_quanta.q_cap(chips)',
 PATH='I51',
 DRAWING='@T6G_MB_LIB.T6G(SCH_1):PAGE273',
 BOM_COST='VR_SYSTEM ',
 TOLERANCE='10%',
 MATERIAL='EMPTY',
 PHYS_PAGE='188',
 XY='(-500,5700)',
 ROT='2',
 VER='1',
 PACK_TYPE='C0805',
 LOCATION='C60',
 CDS_LIB='pure_quanta',
 CDS_PART_NAME='Q_CAP_C0805-10UF,16V,10%,EMPTY,CH6103KEA00',
 VOLTAGE='16V',
 PART_NUMBER='CH6103KEA00',
 VALUE='10UF',
 PRIM_FILE='./archive_libs/logical/q_cap/chips/chips.prt';

PART_NAME
 C61 'Q_CAP_C0402-100NF,50V,10%,X7R,CH4106K1B01':;

SECTION_NUMBER 1
 '@T6G_MB_LIB.T6G(SCH_1):PAGE273_I59@PURE_QUANTA.Q_CAP(CHIPS)':
 C_PATH='@t6g_mb_lib.t6g(sch_1):page273_i59@pure_quanta.q_cap(chips)',
 P_PATH='@t6g_mb_lib.t6g(sch_1):page188_i59@pure_quanta.q_cap(chips)',
 PATH='I59',
 DRAWING='@T6G_MB_LIB.T6G(SCH_1):PAGE273',
 BOM_COST='VR_SYSTEM ',
 TOLERANCE='10%',
 MATERIAL='X7R',
 PHYS_PAGE='188',
 XY='(725,5700)',
 ROT='0',
 VER='1',
 PACK_TYPE='C0402',
 LOCATION='C61',
 CDS_LIB='pure_quanta',
 CDS_PART_NAME='Q_CAP_C0402-100NF,50V,10%,X7R,CH4106K1B01',
 VOLTAGE='50V',
 PART_NUMBER='CH4106K1B01',
 VALUE='100NF',
 PRIM_FILE='./archive_libs/logical/q_cap/chips/chips.prt';

PART_NAME
 C62 'Q_CAP_C0402-220PF,50V,5%,C0G,CH12206JB00':;

SECTION_NUMBER 1
 '@T6G_MB_LIB.T6G(SCH_1):PAGE349_I69@PURE_QUANTA.Q_CAP(CHIPS)':
 C_PATH='@t6g_mb_lib.t6g(sch_1):page349_i69@pure_quanta.q_cap(chips)',
 P_PATH='@t6g_mb_lib.t6g(sch_1):page151_i69@pure_quanta.q_cap(chips)',
 PATH='I69',
 DRAWING='@T6G_MB_LIB.T6G(SCH_1):PAGE349',
 TOLERANCE='5%',
 MATERIAL='C0G',
 PHYS_PAGE='151',
 XY='(4050,1275)',
 ROT='0',
 VER='1',
 PACK_TYPE='C0402',
 LOCATION='C62',
 CDS_LIB='pure_quanta',
 CDS_PART_NAME='Q_CAP_C0402-220PF,50V,5%,C0G,CH12206JB00',
 VOLTAGE='50V',
 PART_NUMBER='CH12206JB00',
 VALUE='220PF',
 PRIM_FILE='./archive_libs/logical/q_cap/chips/chips.prt';

PART_NAME
 C63 'Q_CAP_C0402-220PF,50V,5%,C0G,CH12206JB00':;

SECTION_NUMBER 1
 '@T6G_MB_LIB.T6G(SCH_1):PAGE349_I112@PURE_QUANTA.Q_CAP(CHIPS)':
 C_PATH='@t6g_mb_lib.t6g(sch_1):page349_i112@pure_quanta.q_cap(chips)',
 P_PATH='@t6g_mb_lib.t6g(sch_1):page151_i112@pure_quanta.q_cap(chips)',
 PATH='I112',
 DRAWING='@T6G_MB_LIB.T6G(SCH_1):PAGE349',
 TOLERANCE='5%',
 MATERIAL='C0G',
 PHYS_PAGE='151',
 XY='(4250,1275)',
 ROT='0',
 VER='1',
 PACK_TYPE='C0402',
 LOCATION='C63',
 CDS_LIB='pure_quanta',
 CDS_PART_NAME='Q_CAP_C0402-220PF,50V,5%,C0G,CH12206JB00',
 VOLTAGE='50V',
 PART_NUMBER='CH12206JB00',
 VALUE='220PF',
 PRIM_FILE='./archive_libs/logical/q_cap/chips/chips.prt';

PART_NAME
 C64 'Q_CAP_0402-0.1UF,25V,10%,EMPTY,CH4104K1B00':;

SECTION_NUMBER 1
 '@T6G_MB_LIB.T6G(SCH_1):PAGE363_I453@PURE_QUANTA.Q_CAP(CHIPS)':
 C_PATH='@t6g_mb_lib.t6g(sch_1):page363_i453@pure_quanta.q_cap(chips)',
 P_PATH='@t6g_mb_lib.t6g(sch_1):page240_i453@pure_quanta.q_cap(chips)',
 PATH='I453',
 DRAWING='@T6G_MB_LIB.T6G(SCH_1):PAGE363',
 TOLERANCE='10%',
 MATERIAL='EMPTY',
 PHYS_PAGE='240',
 XY='(200,-50)',
 ROT='0',
 VER='2',
 PACK_TYPE='0402',
 LOCATION='C64',
 CDS_LIB='pure_quanta',
 CDS_PART_NAME='Q_CAP_0402-0.1UF,25V,10%,EMPTY,CH4104K1B00',
 VOLTAGE='25V',
 PART_NUMBER='CH4104K1B00',
 VALUE='0.1UF',
 PRIM_FILE='./archive_libs/logical/q_cap/chips/chips.prt';

PART_NAME
 C65 'Q_CAP_0402-0.1UF,25V,10%,EMPTY,CH4104K1B00':;

SECTION_NUMBER 1
 '@T6G_MB_LIB.T6G(SCH_1):PAGE363_I454@PURE_QUANTA.Q_CAP(CHIPS)':
 C_PATH='@t6g_mb_lib.t6g(sch_1):page363_i454@pure_quanta.q_cap(chips)',
 P_PATH='@t6g_mb_lib.t6g(sch_1):page240_i454@pure_quanta.q_cap(chips)',
 PATH='I454',
 DRAWING='@T6G_MB_LIB.T6G(SCH_1):PAGE363',
 TOLERANCE='10%',
 MATERIAL='EMPTY',
 PHYS_PAGE='240',
 XY='(200,-200)',
 ROT='0',
 VER='2',
 PACK_TYPE='0402',
 LOCATION='C65',
 CDS_LIB='pure_quanta',
 CDS_PART_NAME='Q_CAP_0402-0.1UF,25V,10%,EMPTY,CH4104K1B00',
 VOLTAGE='25V',
 PART_NUMBER='CH4104K1B00',
 VALUE='0.1UF',
 PRIM_FILE='./archive_libs/logical/q_cap/chips/chips.prt';

PART_NAME
 C66 'Q_CAP_0402-0.1UF,25V,10%,EMPTY,CH4104K1B00':;

SECTION_NUMBER 1
 '@T6G_MB_LIB.T6G(SCH_1):PAGE363_I455@PURE_QUANTA.Q_CAP(CHIPS)':
 C_PATH='@t6g_mb_lib.t6g(sch_1):page363_i455@pure_quanta.q_cap(chips)',
 P_PATH='@t6g_mb_lib.t6g(sch_1):page240_i455@pure_quanta.q_cap(chips)',
 PATH='I455',
 DRAWING='@T6G_MB_LIB.T6G(SCH_1):PAGE363',
 TOLERANCE='10%',
 MATERIAL='EMPTY',
 PHYS_PAGE='240',
 XY='(200,-350)',
 ROT='0',
 VER='2',
 PACK_TYPE='0402',
 LOCATION='C66',
 CDS_LIB='pure_quanta',
 CDS_PART_NAME='Q_CAP_0402-0.1UF,25V,10%,EMPTY,CH4104K1B00',
 VOLTAGE='25V',
 PART_NUMBER='CH4104K1B00',
 VALUE='0.1UF',
 PRIM_FILE='./archive_libs/logical/q_cap/chips/chips.prt';

PART_NAME
 C67 'Q_CAP_0402-0.1UF,25V,10%,EMPTY,CH4104K1B00':;

SECTION_NUMBER 1
 '@T6G_MB_LIB.T6G(SCH_1):PAGE363_I456@PURE_QUANTA.Q_CAP(CHIPS)':
 C_PATH='@t6g_mb_lib.t6g(sch_1):page363_i456@pure_quanta.q_cap(chips)',
 P_PATH='@t6g_mb_lib.t6g(sch_1):page240_i456@pure_quanta.q_cap(chips)',
 PATH='I456',
 DRAWING='@T6G_MB_LIB.T6G(SCH_1):PAGE363',
 TOLERANCE='10%',
 MATERIAL='EMPTY',
 PHYS_PAGE='240',
 XY='(200,-500)',
 ROT='0',
 VER='2',
 PACK_TYPE='0402',
 LOCATION='C67',
 CDS_LIB='pure_quanta',
 CDS_PART_NAME='Q_CAP_0402-0.1UF,25V,10%,EMPTY,CH4104K1B00',
 VOLTAGE='25V',
 PART_NUMBER='CH4104K1B00',
 VALUE='0.1UF',
 PRIM_FILE='./archive_libs/logical/q_cap/chips/chips.prt';

PART_NAME
 C68 'Q_CAP_0402-0.1UF,25V,10%,X7R,CH4104K1B00':;

SECTION_NUMBER 1
 '@T6G_MB_LIB.T6G(SCH_1):PAGE379_I24@PURE_QUANTA.Q_CAP(CHIPS)':
 C_PATH='@t6g_mb_lib.t6g(sch_1):page379_i24@pure_quanta.q_cap(chips)',
 P_PATH='@t6g_mb_lib.t6g(sch_1):page183_i24@pure_quanta.q_cap(chips)',
 PATH='I24',
 DRAWING='@T6G_MB_LIB.T6G(SCH_1):PAGE379',
 TOLERANCE='10%',
 MATERIAL='X7R',
 PHYS_PAGE='183',
 XY='(-6825,5650)',
 ROT='0',
 VER='1',
 PACK_TYPE='0402',
 LOCATION='C68',
 CDS_LIB='pure_quanta',
 CDS_PART_NAME='Q_CAP_0402-0.1UF,25V,10%,X7R,CH4104K1B00',
 VOLTAGE='25V',
 PART_NUMBER='CH4104K1B00',
 VALUE='0.1UF',
 PRIM_FILE='./archive_libs/logical/q_cap/chips/chips.prt';

PART_NAME
 C69 'Q_CAP_0402-0.1UF,25V,10%,X7R,CH4104K1B00':;

SECTION_NUMBER 1
 '@T6G_MB_LIB.T6G(SCH_1):PAGE364_I40@PURE_QUANTA.Q_CAP(CHIPS)':
 C_PATH='@t6g_mb_lib.t6g(sch_1):page364_i40@pure_quanta.q_cap(chips)',
 P_PATH='@t6g_mb_lib.t6g(sch_1):page241_i40@pure_quanta.q_cap(chips)',
 PATH='I40',
 DRAWING='@T6G_MB_LIB.T6G(SCH_1):PAGE364',
 TOLERANCE='10%',
 MATERIAL='X7R',
 PHYS_PAGE='241',
 XY='(1250,-350)',
 ROT='0',
 VER='1',
 PACK_TYPE='0402',
 LOCATION='C69',
 CDS_LIB='pure_quanta',
 CDS_PART_NAME='Q_CAP_0402-0.1UF,25V,10%,X7R,CH4104K1B00',
 VOLTAGE='25V',
 PART_NUMBER='CH4104K1B00',
 VALUE='0.1UF',
 PRIM_FILE='./archive_libs/logical/q_cap/chips/chips.prt';

PART_NAME
 C70 'Q_CAP_0402-0.1UF,25V,10%,X7R,CH4104K1B00':;

SECTION_NUMBER 1
 '@T6G_MB_LIB.T6G(SCH_1):PAGE364_I62@PURE_QUANTA.Q_CAP(CHIPS)':
 C_PATH='@t6g_mb_lib.t6g(sch_1):page364_i62@pure_quanta.q_cap(chips)',
 P_PATH='@t6g_mb_lib.t6g(sch_1):page241_i62@pure_quanta.q_cap(chips)',
 PATH='I62',
 DRAWING='@T6G_MB_LIB.T6G(SCH_1):PAGE364',
 TOLERANCE='10%',
 MATERIAL='X7R',
 PHYS_PAGE='241',
 XY='(1975,-1775)',
 ROT='0',
 VER='1',
 PACK_TYPE='0402',
 LOCATION='C70',
 CDS_LIB='pure_quanta',
 CDS_PART_NAME='Q_CAP_0402-0.1UF,25V,10%,X7R,CH4104K1B00',
 VOLTAGE='25V',
 PART_NUMBER='CH4104K1B00',
 VALUE='0.1UF',
 PRIM_FILE='./archive_libs/logical/q_cap/chips/chips.prt';

PART_NAME
 C71 'Q_CAP_C0402-4.7PF,50V,0.1P,NPO,CH-4716TB06':;

SECTION_NUMBER 1
 '@T6G_MB_LIB.T6G(SCH_1):PAGE232_I75@PURE_QUANTA.Q_CAP(CHIPS)':
 C_PATH='@t6g_mb_lib.t6g(sch_1):page232_i75@pure_quanta.q_cap(chips)',
 P_PATH='@t6g_mb_lib.t6g(sch_1):page233_i75@pure_quanta.q_cap(chips)',
 PATH='I75',
 DRAWING='@T6G_MB_LIB.T6G(SCH_1):PAGE232',
 TOLERANCE='0.1P',
 MATERIAL='NPO',
 PHYS_PAGE='233',
 XY='(-7250,3900)',
 ROT='2',
 VER='1',
 PACK_TYPE='C0402',
 LOCATION='C71',
 CDS_LIB='pure_quanta',
 CDS_PART_NAME='Q_CAP_C0402-4.7PF,50V,0.1P,NPO,CH-4716TB06',
 VOLTAGE='50V',
 PART_NUMBER='CH-4716TB06',
 VALUE='4.7PF',
 PRIM_FILE='./archive_libs/logical/q_cap/chips/chips.prt';

PART_NAME
 C72 'Q_CAP_0402-0.1UF,25V,10%,X7R,CH4104K1B00':;

SECTION_NUMBER 1
 '@T6G_MB_LIB.T6G(SCH_1):PAGE337_I40@PURE_QUANTA.Q_CAP(CHIPS)':
 C_PATH='@t6g_mb_lib.t6g(sch_1):page337_i40@pure_quanta.q_cap(chips)',
 P_PATH='@t6g_mb_lib.t6g(sch_1):page133_i40@pure_quanta.q_cap(chips)',
 PATH='I40',
 DRAWING='@T6G_MB_LIB.T6G(SCH_1):PAGE337',
 TOLERANCE='10%',
 MATERIAL='X7R',
 PHYS_PAGE='133',
 XY='(-6575,6200)',
 ROT='0',
 VER='1',
 PACK_TYPE='0402',
 LOCATION='C72',
 CDS_LIB='pure_quanta',
 CDS_PART_NAME='Q_CAP_0402-0.1UF,25V,10%,X7R,CH4104K1B00',
 VOLTAGE='25V',
 PART_NUMBER='CH4104K1B00',
 VALUE='0.1UF',
 PRIM_FILE='./archive_libs/logical/q_cap/chips/chips.prt';

PART_NAME
 C73 'Q_CAP_0402-0.1UF,25V,10%,X7R,CH4104K1B00':;

SECTION_NUMBER 1
 '@T6G_MB_LIB.T6G(SCH_1):PAGE359_I104@PURE_QUANTA.Q_CAP(CHIPS)':
 C_PATH='@t6g_mb_lib.t6g(sch_1):page359_i104@pure_quanta.q_cap(chips)',
 P_PATH='@t6g_mb_lib.t6g(sch_1):page235_i104@pure_quanta.q_cap(chips)',
 PATH='I104',
 DRAWING='@T6G_MB_LIB.T6G(SCH_1):PAGE359',
 TOLERANCE='10%',
 MATERIAL='X7R',
 PHYS_PAGE='235',
 XY='(2550,475)',
 ROT='2',
 VER='1',
 PACK_TYPE='0402',
 LOCATION='C73',
 CDS_LIB='pure_quanta',
 CDS_PART_NAME='Q_CAP_0402-0.1UF,25V,10%,X7R,CH4104K1B00',
 VOLTAGE='25V',
 PART_NUMBER='CH4104K1B00',
 VALUE='0.1UF',
 PRIM_FILE='./archive_libs/logical/q_cap/chips/chips.prt';

PART_NAME
 C74 'Q_CAP_0402-0.1UF,25V,10%,EMPTY,CH4104K1B00':;

SECTION_NUMBER 1
 '@T6G_MB_LIB.T6G(SCH_1):PAGE363_I452@PURE_QUANTA.Q_CAP(CHIPS)':
 C_PATH='@t6g_mb_lib.t6g(sch_1):page363_i452@pure_quanta.q_cap(chips)',
 P_PATH='@t6g_mb_lib.t6g(sch_1):page240_i452@pure_quanta.q_cap(chips)',
 PATH='I452',
 DRAWING='@T6G_MB_LIB.T6G(SCH_1):PAGE363',
 TOLERANCE='10%',
 MATERIAL='EMPTY',
 PHYS_PAGE='240',
 XY='(200,100)',
 ROT='0',
 VER='2',
 PACK_TYPE='0402',
 LOCATION='C74',
 CDS_LIB='pure_quanta',
 CDS_PART_NAME='Q_CAP_0402-0.1UF,25V,10%,EMPTY,CH4104K1B00',
 VOLTAGE='25V',
 PART_NUMBER='CH4104K1B00',
 VALUE='0.1UF',
 PRIM_FILE='./archive_libs/logical/q_cap/chips/chips.prt';

PART_NAME
 C75 'Q_CAP_0402-0.1UF,25V,10%,X7R,CH4104K1B00':;

SECTION_NUMBER 1
 '@T6G_MB_LIB.T6G(SCH_1):PAGE379_I60@PURE_QUANTA.Q_CAP(CHIPS)':
 C_PATH='@t6g_mb_lib.t6g(sch_1):page379_i60@pure_quanta.q_cap(chips)',
 P_PATH='@t6g_mb_lib.t6g(sch_1):page183_i60@pure_quanta.q_cap(chips)',
 PATH='I60',
 DRAWING='@T6G_MB_LIB.T6G(SCH_1):PAGE379',
 TOLERANCE='10%',
 MATERIAL='X7R',
 PHYS_PAGE='183',
 XY='(-3225,5300)',
 ROT='0',
 VER='1',
 PACK_TYPE='0402',
 LOCATION='C75',
 CDS_LIB='pure_quanta',
 CDS_PART_NAME='Q_CAP_0402-0.1UF,25V,10%,X7R,CH4104K1B00',
 VOLTAGE='25V',
 PART_NUMBER='CH4104K1B00',
 VALUE='0.1UF',
 PRIM_FILE='./archive_libs/logical/q_cap/chips/chips.prt';

PART_NAME
 C76 'Q_CAP_C0402-10UF,6.3V,20%,X6S,CH6101MEB01':;

SECTION_NUMBER 1
 '@T6G_MB_LIB.T6G(SCH_1):PAGE160_I69@PURE_QUANTA.Q_CAP(CHIPS)':
 C_PATH='@t6g_mb_lib.t6g(sch_1):page160_i69@pure_quanta.q_cap(chips)',
 P_PATH='@t6g_mb_lib.t6g(sch_1):page182_i69@pure_quanta.q_cap(chips)',
 PATH='I69',
 DRAWING='@T6G_MB_LIB.T6G(SCH_1):PAGE160',
 TOLERANCE='20%',
 MATERIAL='X6S',
 PHYS_PAGE='182',
 XY='(-7500,5875)',
 ROT='0',
 VER='1',
 PACK_TYPE='C0402',
 LOCATION='C76',
 CDS_LIB='pure_quanta',
 CDS_PART_NAME='Q_CAP_C0402-10UF,6.3V,20%,X6S,CH6101MEB01',
 VOLTAGE='6.3V',
 PART_NUMBER='CH6101MEB01',
 VALUE='10UF',
 PRIM_FILE='./archive_libs/logical/q_cap/chips/chips.prt';

PART_NAME
 C77 'Q_CAP_C0402-10UF,6.3V,20%,X6S,CH6101MEB01':;

SECTION_NUMBER 1
 '@T6G_MB_LIB.T6G(SCH_1):PAGE160_I70@PURE_QUANTA.Q_CAP(CHIPS)':
 C_PATH='@t6g_mb_lib.t6g(sch_1):page160_i70@pure_quanta.q_cap(chips)',
 P_PATH='@t6g_mb_lib.t6g(sch_1):page182_i70@pure_quanta.q_cap(chips)',
 PATH='I70',
 DRAWING='@T6G_MB_LIB.T6G(SCH_1):PAGE160',
 TOLERANCE='20%',
 MATERIAL='X6S',
 PHYS_PAGE='182',
 XY='(-7475,5075)',
 ROT='0',
 VER='1',
 PACK_TYPE='C0402',
 LOCATION='C77',
 CDS_LIB='pure_quanta',
 CDS_PART_NAME='Q_CAP_C0402-10UF,6.3V,20%,X6S,CH6101MEB01',
 VOLTAGE='6.3V',
 PART_NUMBER='CH6101MEB01',
 VALUE='10UF',
 PRIM_FILE='./archive_libs/logical/q_cap/chips/chips.prt';

PART_NAME
 C78 'Q_CAP_0402-0.1UF,25V,10%,X7R,CH4104K1B00':;

SECTION_NUMBER 1
 '@T6G_MB_LIB.T6G(SCH_1):PAGE160_I18@PURE_QUANTA.Q_CAP(CHIPS)':
 C_PATH='@t6g_mb_lib.t6g(sch_1):page160_i18@pure_quanta.q_cap(chips)',
 P_PATH='@t6g_mb_lib.t6g(sch_1):page182_i18@pure_quanta.q_cap(chips)',
 PATH='I18',
 DRAWING='@T6G_MB_LIB.T6G(SCH_1):PAGE160',
 TOLERANCE='10%',
 MATERIAL='X7R',
 PHYS_PAGE='182',
 XY='(-7125,5075)',
 ROT='0',
 VER='1',
 PACK_TYPE='0402',
 LOCATION='C78',
 CDS_LIB='pure_quanta',
 CDS_PART_NAME='Q_CAP_0402-0.1UF,25V,10%,X7R,CH4104K1B00',
 VOLTAGE='25V',
 PART_NUMBER='CH4104K1B00',
 VALUE='0.1UF',
 PRIM_FILE='./archive_libs/logical/q_cap/chips/chips.prt';

PART_NAME
 C79 'Q_CAP_0402-0.1UF,25V,10%,X7R,CH4104K1B00':;

SECTION_NUMBER 1
 '@T6G_MB_LIB.T6G(SCH_1):PAGE160_I41@PURE_QUANTA.Q_CAP(CHIPS)':
 C_PATH='@t6g_mb_lib.t6g(sch_1):page160_i41@pure_quanta.q_cap(chips)',
 P_PATH='@t6g_mb_lib.t6g(sch_1):page182_i41@pure_quanta.q_cap(chips)',
 PATH='I41',
 DRAWING='@T6G_MB_LIB.T6G(SCH_1):PAGE160',
 TOLERANCE='10%',
 MATERIAL='X7R',
 PHYS_PAGE='182',
 XY='(-4325,5525)',
 ROT='0',
 VER='1',
 PACK_TYPE='0402',
 LOCATION='C79',
 CDS_LIB='pure_quanta',
 CDS_PART_NAME='Q_CAP_0402-0.1UF,25V,10%,X7R,CH4104K1B00',
 VOLTAGE='25V',
 PART_NUMBER='CH4104K1B00',
 VALUE='0.1UF',
 PRIM_FILE='./archive_libs/logical/q_cap/chips/chips.prt';

PART_NAME
 C80 'Q_CAP_0402-0.1UF,25V,10%,X7R,CH4104K1B00':;

SECTION_NUMBER 1
 '@T6G_MB_LIB.T6G(SCH_1):PAGE160_I44@PURE_QUANTA.Q_CAP(CHIPS)':
 C_PATH='@t6g_mb_lib.t6g(sch_1):page160_i44@pure_quanta.q_cap(chips)',
 P_PATH='@t6g_mb_lib.t6g(sch_1):page182_i44@pure_quanta.q_cap(chips)',
 PATH='I44',
 DRAWING='@T6G_MB_LIB.T6G(SCH_1):PAGE160',
 TOLERANCE='10%',
 MATERIAL='X7R',
 PHYS_PAGE='182',
 XY='(-4075,5525)',
 ROT='0',
 VER='1',
 PACK_TYPE='0402',
 LOCATION='C80',
 CDS_LIB='pure_quanta',
 CDS_PART_NAME='Q_CAP_0402-0.1UF,25V,10%,X7R,CH4104K1B00',
 VOLTAGE='25V',
 PART_NUMBER='CH4104K1B00',
 VALUE='0.1UF',
 PRIM_FILE='./archive_libs/logical/q_cap/chips/chips.prt';

PART_NAME
 C81 'Q_CAP_0402-0.1UF,25V,10%,X7R,CH4104K1B00':;

SECTION_NUMBER 1
 '@T6G_MB_LIB.T6G(SCH_1):PAGE160_I45@PURE_QUANTA.Q_CAP(CHIPS)':
 C_PATH='@t6g_mb_lib.t6g(sch_1):page160_i45@pure_quanta.q_cap(chips)',
 P_PATH='@t6g_mb_lib.t6g(sch_1):page182_i45@pure_quanta.q_cap(chips)',
 PATH='I45',
 DRAWING='@T6G_MB_LIB.T6G(SCH_1):PAGE160',
 TOLERANCE='10%',
 MATERIAL='X7R',
 PHYS_PAGE='182',
 XY='(-3825,5525)',
 ROT='0',
 VER='1',
 PACK_TYPE='0402',
 LOCATION='C81',
 CDS_LIB='pure_quanta',
 CDS_PART_NAME='Q_CAP_0402-0.1UF,25V,10%,X7R,CH4104K1B00',
 VOLTAGE='25V',
 PART_NUMBER='CH4104K1B00',
 VALUE='0.1UF',
 PRIM_FILE='./archive_libs/logical/q_cap/chips/chips.prt';

PART_NAME
 C82 'Q_CAP_C0402-10UF,6.3V,20%,X6S,CH6101MEB01':;

SECTION_NUMBER 1
 '@T6G_MB_LIB.T6G(SCH_1):PAGE379_I77@PURE_QUANTA.Q_CAP(CHIPS)':
 C_PATH='@t6g_mb_lib.t6g(sch_1):page379_i77@pure_quanta.q_cap(chips)',
 P_PATH='@t6g_mb_lib.t6g(sch_1):page183_i77@pure_quanta.q_cap(chips)',
 PATH='I77',
 DRAWING='@T6G_MB_LIB.T6G(SCH_1):PAGE379',
 TOLERANCE='20%',
 MATERIAL='X6S',
 PHYS_PAGE='183',
 XY='(-7175,5650)',
 ROT='0',
 VER='1',
 PACK_TYPE='C0402',
 LOCATION='C82',
 CDS_LIB='pure_quanta',
 CDS_PART_NAME='Q_CAP_C0402-10UF,6.3V,20%,X6S,CH6101MEB01',
 VOLTAGE='6.3V',
 PART_NUMBER='CH6101MEB01',
 VALUE='10UF',
 PRIM_FILE='./archive_libs/logical/q_cap/chips/chips.prt';

PART_NAME
 C83 'Q_CAP_C0402-10UF,6.3V,20%,X6S,CH6101MEB01':;

SECTION_NUMBER 1
 '@T6G_MB_LIB.T6G(SCH_1):PAGE379_I78@PURE_QUANTA.Q_CAP(CHIPS)':
 C_PATH='@t6g_mb_lib.t6g(sch_1):page379_i78@pure_quanta.q_cap(chips)',
 P_PATH='@t6g_mb_lib.t6g(sch_1):page183_i78@pure_quanta.q_cap(chips)',
 PATH='I78',
 DRAWING='@T6G_MB_LIB.T6G(SCH_1):PAGE379',
 TOLERANCE='20%',
 MATERIAL='X6S',
 PHYS_PAGE='183',
 XY='(-7150,4850)',
 ROT='0',
 VER='1',
 PACK_TYPE='C0402',
 LOCATION='C83',
 CDS_LIB='pure_quanta',
 CDS_PART_NAME='Q_CAP_C0402-10UF,6.3V,20%,X6S,CH6101MEB01',
 VOLTAGE='6.3V',
 PART_NUMBER='CH6101MEB01',
 VALUE='10UF',
 PRIM_FILE='./archive_libs/logical/q_cap/chips/chips.prt';

PART_NAME
 C84 'Q_CAP_0402-0.1UF,25V,10%,X7R,CH4104K1B00':;

SECTION_NUMBER 1
 '@T6G_MB_LIB.T6G(SCH_1):PAGE379_I26@PURE_QUANTA.Q_CAP(CHIPS)':
 C_PATH='@t6g_mb_lib.t6g(sch_1):page379_i26@pure_quanta.q_cap(chips)',
 P_PATH='@t6g_mb_lib.t6g(sch_1):page183_i26@pure_quanta.q_cap(chips)',
 PATH='I26',
 DRAWING='@T6G_MB_LIB.T6G(SCH_1):PAGE379',
 TOLERANCE='10%',
 MATERIAL='X7R',
 PHYS_PAGE='183',
 XY='(-6800,4850)',
 ROT='0',
 VER='1',
 PACK_TYPE='0402',
 LOCATION='C84',
 CDS_LIB='pure_quanta',
 CDS_PART_NAME='Q_CAP_0402-0.1UF,25V,10%,X7R,CH4104K1B00',
 VOLTAGE='25V',
 PART_NUMBER='CH4104K1B00',
 VALUE='0.1UF',
 PRIM_FILE='./archive_libs/logical/q_cap/chips/chips.prt';

PART_NAME
 C85 'Q_CAP_C0402-0.001UF,50V,10%,X7R,CH30106KB19':;

SECTION_NUMBER 1
 '@T6G_MB_LIB.T6G(SCH_1):PAGE149_I152@PURE_QUANTA.Q_CAP(CHIPS)':
 C_PATH='@t6g_mb_lib.t6g(sch_1):page149_i152@pure_quanta.q_cap(chips)',
 P_PATH='@t6g_mb_lib.t6g(sch_1):page172_i152@pure_quanta.q_cap(chips)',
 PATH='I152',
 DRAWING='@T6G_MB_LIB.T6G(SCH_1):PAGE149',
 TOLERANCE='10%',
 MATERIAL='X7R',
 PHYS_PAGE='172',
 XY='(-7000,5375)',
 ROT='0',
 VER='1',
 PACK_TYPE='C0402',
 LOCATION='C85',
 CDS_LIB='pure_quanta',
 CDS_PART_NAME='Q_CAP_C0402-0.001UF,50V,10%,X7R,CH30106KB19',
 VOLTAGE='50V',
 PART_NUMBER='CH30106KB19',
 VALUE='0.001UF',
 PRIM_FILE='./archive_libs/logical/q_cap/chips/chips.prt';

PART_NAME
 C86 'Q_CAP_C0402-0.01UF,50V,10%,EMPTY,CH31006KB18':;

SECTION_NUMBER 1
 '@T6G_MB_LIB.T6G(SCH_1):PAGE149_I161@PURE_QUANTA.Q_CAP(CHIPS)':
 C_PATH='@t6g_mb_lib.t6g(sch_1):page149_i161@pure_quanta.q_cap(chips)',
 P_PATH='@t6g_mb_lib.t6g(sch_1):page172_i161@pure_quanta.q_cap(chips)',
 PATH='I161',
 DRAWING='@T6G_MB_LIB.T6G(SCH_1):PAGE149',
 TOLERANCE='10%',
 MATERIAL='EMPTY',
 PHYS_PAGE='172',
 XY='(-5125,4425)',
 ROT='0',
 VER='1',
 PACK_TYPE='C0402',
 LOCATION='C86',
 CDS_LIB='pure_quanta',
 CDS_PART_NAME='Q_CAP_C0402-0.01UF,50V,10%,EMPTY,CH31006KB18',
 VOLTAGE='50V',
 PART_NUMBER='CH31006KB18',
 VALUE='0.01UF',
 PRIM_FILE='./archive_libs/logical/q_cap/chips/chips.prt';

PART_NAME
 C87 'Q_CAP_C0402-0.001UF,50V,10%,X7R,CH30106KB19':;

SECTION_NUMBER 1
 '@T6G_MB_LIB.T6G(SCH_1):PAGE149_I134@PURE_QUANTA.Q_CAP(CHIPS)':
 C_PATH='@t6g_mb_lib.t6g(sch_1):page149_i134@pure_quanta.q_cap(chips)',
 P_PATH='@t6g_mb_lib.t6g(sch_1):page172_i134@pure_quanta.q_cap(chips)',
 PATH='I134',
 DRAWING='@T6G_MB_LIB.T6G(SCH_1):PAGE149',
 TOLERANCE='10%',
 MATERIAL='X7R',
 PHYS_PAGE='172',
 XY='(-2350,5325)',
 ROT='0',
 VER='1',
 PACK_TYPE='C0402',
 LOCATION='C87',
 CDS_LIB='pure_quanta',
 CDS_PART_NAME='Q_CAP_C0402-0.001UF,50V,10%,X7R,CH30106KB19',
 VOLTAGE='50V',
 PART_NUMBER='CH30106KB19',
 VALUE='0.001UF',
 PRIM_FILE='./archive_libs/logical/q_cap/chips/chips.prt';

PART_NAME
 C88 'Q_CAP_0402-0.1UF,25V,10%,X7R,CH4104K1B00':;

SECTION_NUMBER 1
 '@T6G_MB_LIB.T6G(SCH_1):PAGE85_I523@PURE_QUANTA.Q_CAP(CHIPS)':
 C_PATH='@t6g_mb_lib.t6g(sch_1):page85_i523@pure_quanta.q_cap(chips)',
 P_PATH='@t6g_mb_lib.t6g(sch_1):page86_i523@pure_quanta.q_cap(chips)',
 PATH='I523',
 DRAWING='@T6G_MB_LIB.T6G(SCH_1):PAGE85',
 BOM_COST='MEM',
 TOLERANCE='10%',
 MATERIAL='X7R',
 PHYS_PAGE='86',
 XY='(-9000,3225)',
 ROT='2',
 VER='1',
 PACK_TYPE='0402',
 LOCATION='C88',
 CDS_LIB='pure_quanta',
 CDS_PART_NAME='Q_CAP_0402-0.1UF,25V,10%,X7R,CH4104K1B00',
 VOLTAGE='25V',
 PART_NUMBER='CH4104K1B00',
 VALUE='0.1UF',
 PRIM_FILE='./archive_libs/logical/q_cap/chips/chips.prt';

PART_NAME
 C89 'Q_CAP_C0805-10UF,25V,10%,X6S,CH6104KEA00':
 ROOM='';

SECTION_NUMBER 1
 '@T6G_MB_LIB.T6G(SCH_1):PAGE85_I519@PURE_QUANTA.Q_CAP(CHIPS)':
 C_PATH='@t6g_mb_lib.t6g(sch_1):page85_i519@pure_quanta.q_cap(chips)',
 P_PATH='@t6g_mb_lib.t6g(sch_1):page86_i519@pure_quanta.q_cap(chips)',
 PATH='I519',
 DRAWING='@T6G_MB_LIB.T6G(SCH_1):PAGE85',
 BOM_COST='MEM',
 TOLERANCE='10%',
 MATERIAL='X6S',
 PHYS_PAGE='86',
 XY='(-2950,6050)',
 ROT='2',
 VER='1',
 PACK_TYPE='C0805',
 LOCATION='C89',
 CDS_LIB='pure_quanta',
 CDS_PART_NAME='Q_CAP_C0805-10UF,25V,10%,X6S,CH6104KEA00',
 VOLTAGE='25V',
 ROOM='',
 PART_NUMBER='CH6104KEA00',
 VALUE='10UF',
 PRIM_FILE='./archive_libs/logical/q_cap/chips/chips.prt';

PART_NAME
 C90 'Q_CAP_0402-0.1UF,25V,10%,X7R,CH4104K1B00':;

SECTION_NUMBER 1
 '@T6G_MB_LIB.T6G(SCH_1):PAGE379_I35@PURE_QUANTA.Q_CAP(CHIPS)':
 C_PATH='@t6g_mb_lib.t6g(sch_1):page379_i35@pure_quanta.q_cap(chips)',
 P_PATH='@t6g_mb_lib.t6g(sch_1):page183_i35@pure_quanta.q_cap(chips)',
 PATH='I35',
 DRAWING='@T6G_MB_LIB.T6G(SCH_1):PAGE379',
 TOLERANCE='10%',
 MATERIAL='X7R',
 PHYS_PAGE='183',
 XY='(-4000,5300)',
 ROT='0',
 VER='1',
 PACK_TYPE='0402',
 LOCATION='C90',
 CDS_LIB='pure_quanta',
 CDS_PART_NAME='Q_CAP_0402-0.1UF,25V,10%,X7R,CH4104K1B00',
 VOLTAGE='25V',
 PART_NUMBER='CH4104K1B00',
 VALUE='0.1UF',
 PRIM_FILE='./archive_libs/logical/q_cap/chips/chips.prt';

PART_NAME
 C91 'Q_CAP_C0402-12PF,50V,5%,C0G,CH01206JB05':
 ROOM='USB3_HUB1_CYP';

SECTION_NUMBER 1
 '@T6G_MB_LIB.T6G(SCH_1):PAGE153_I92@PURE_QUANTA.Q_CAP(CHIPS)':
 C_PATH='@t6g_mb_lib.t6g(sch_1):page153_i92@pure_quanta.q_cap(chips)',
 P_PATH='@t6g_mb_lib.t6g(sch_1):page176_i92@pure_quanta.q_cap(chips)',
 PATH='I92',
 DRAWING='@T6G_MB_LIB.T6G(SCH_1):PAGE153',
 TOLERANCE='5%',
 MATERIAL='C0G',
 PHYS_PAGE='176',
 XY='(-6350,1500)',
 ROT='0',
 VER='1',
 PACK_TYPE='C0402',
 LOCATION='C91',
 CDS_LIB='pure_quanta',
 CDS_PART_NAME='Q_CAP_C0402-12PF,50V,5%,C0G,CH01206JB05',
 VOLTAGE='50V',
 ROOM='USB3_HUB1_CYP',
 PART_NUMBER='CH01206JB05',
 VALUE='12PF',
 PRIM_FILE='./archive_libs/logical/q_cap/chips/chips.prt';

PART_NAME
 C92 'Q_CAP_0402-0.1UF,25V,10%,X7R,CH4104K1B00':
 ROOM='';

SECTION_NUMBER 1
 '@T6G_MB_LIB.T6G(SCH_1):PAGE86_I362@PURE_QUANTA.Q_CAP(CHIPS)':
 C_PATH='@t6g_mb_lib.t6g(sch_1):page86_i362@pure_quanta.q_cap(chips)',
 P_PATH='@t6g_mb_lib.t6g(sch_1):page87_i362@pure_quanta.q_cap(chips)',
 PATH='I362',
 DRAWING='@T6G_MB_LIB.T6G(SCH_1):PAGE86',
 BOM_COST='MEM',
 TOLERANCE='10%',
 MATERIAL='X7R',
 PHYS_PAGE='87',
 XY='(-9050,3325)',
 ROT='2',
 VER='1',
 PACK_TYPE='0402',
 LOCATION='C92',
 CDS_LIB='pure_quanta',
 CDS_PART_NAME='Q_CAP_0402-0.1UF,25V,10%,X7R,CH4104K1B00',
 VOLTAGE='25V',
 ROOM='',
 PART_NUMBER='CH4104K1B00',
 VALUE='0.1UF',
 PRIM_FILE='./archive_libs/logical/q_cap/chips/chips.prt';

PART_NAME
 C93 'Q_CAP_0402-15PF,50V,5%,C0G,CH01506JB06':
 ROOM='USB3_HUB1_CYP';

SECTION_NUMBER 1
 '@T6G_MB_LIB.T6G(SCH_1):PAGE153_I91@PURE_QUANTA.Q_CAP(CHIPS)':
 C_PATH='@t6g_mb_lib.t6g(sch_1):page153_i91@pure_quanta.q_cap(chips)',
 P_PATH='@t6g_mb_lib.t6g(sch_1):page176_i91@pure_quanta.q_cap(chips)',
 PATH='I91',
 DRAWING='@T6G_MB_LIB.T6G(SCH_1):PAGE153',
 TOLERANCE='5%',
 MATERIAL='C0G',
 PHYS_PAGE='176',
 XY='(-8000,1550)',
 ROT='0',
 VER='1',
 PACK_TYPE='0402',
 LOCATION='C93',
 CDS_LIB='pure_quanta',
 CDS_PART_NAME='Q_CAP_0402-15PF,50V,5%,C0G,CH01506JB06',
 VOLTAGE='50V',
 ROOM='USB3_HUB1_CYP',
 PART_NUMBER='CH01506JB06',
 VALUE='15PF',
 PRIM_FILE='./archive_libs/logical/q_cap/chips/chips.prt';

PART_NAME
 C94 'Q_CAP_C0402-4.7PF,50V,0.1P,NPO,CH-4716TB06':;

SECTION_NUMBER 1
 '@T6G_MB_LIB.T6G(SCH_1):PAGE232_I76@PURE_QUANTA.Q_CAP(CHIPS)':
 C_PATH='@t6g_mb_lib.t6g(sch_1):page232_i76@pure_quanta.q_cap(chips)',
 P_PATH='@t6g_mb_lib.t6g(sch_1):page233_i76@pure_quanta.q_cap(chips)',
 PATH='I76',
 DRAWING='@T6G_MB_LIB.T6G(SCH_1):PAGE232',
 TOLERANCE='0.1P',
 MATERIAL='NPO',
 PHYS_PAGE='233',
 XY='(-6375,3900)',
 ROT='0',
 VER='1',
 PACK_TYPE='C0402',
 LOCATION='C94',
 CDS_LIB='pure_quanta',
 CDS_PART_NAME='Q_CAP_C0402-4.7PF,50V,0.1P,NPO,CH-4716TB06',
 VOLTAGE='50V',
 PART_NUMBER='CH-4716TB06',
 VALUE='4.7PF',
 PRIM_FILE='./archive_libs/logical/q_cap/chips/chips.prt';

PART_NAME
 C95 'Q_CAP_0402-0.1UF,25V,10%,X7R,CH4104K1B00':;

SECTION_NUMBER 1
 '@T6G_MB_LIB.T6G(SCH_1):PAGE232_I42@PURE_QUANTA.Q_CAP(CHIPS)':
 C_PATH='@t6g_mb_lib.t6g(sch_1):page232_i42@pure_quanta.q_cap(chips)',
 P_PATH='@t6g_mb_lib.t6g(sch_1):page233_i42@pure_quanta.q_cap(chips)',
 PATH='I42',
 DRAWING='@T6G_MB_LIB.T6G(SCH_1):PAGE232',
 TOLERANCE='10%',
 MATERIAL='X7R',
 PHYS_PAGE='233',
 XY='(-4500,5200)',
 ROT='0',
 VER='1',
 PACK_TYPE='0402',
 LOCATION='C95',
 CDS_LIB='pure_quanta',
 CDS_PART_NAME='Q_CAP_0402-0.1UF,25V,10%,X7R,CH4104K1B00',
 VOLTAGE='25V',
 PART_NUMBER='CH4104K1B00',
 VALUE='0.1UF',
 PRIM_FILE='./archive_libs/logical/q_cap/chips/chips.prt';

PART_NAME
 C96 'Q_CAP_0402-0.1UF,25V,10%,X7R,CH4104K1B00':
 ROOM='';

SECTION_NUMBER 1
 '@T6G_MB_LIB.T6G(SCH_1):PAGE87_I362@PURE_QUANTA.Q_CAP(CHIPS)':
 C_PATH='@t6g_mb_lib.t6g(sch_1):page87_i362@pure_quanta.q_cap(chips)',
 P_PATH='@t6g_mb_lib.t6g(sch_1):page88_i362@pure_quanta.q_cap(chips)',
 PATH='I362',
 DRAWING='@T6G_MB_LIB.T6G(SCH_1):PAGE87',
 BOM_COST='MEM',
 TOLERANCE='10%',
 MATERIAL='X7R',
 PHYS_PAGE='88',
 XY='(-8925,3525)',
 ROT='2',
 VER='1',
 PACK_TYPE='0402',
 LOCATION='C96',
 CDS_LIB='pure_quanta',
 CDS_PART_NAME='Q_CAP_0402-0.1UF,25V,10%,X7R,CH4104K1B00',
 VOLTAGE='25V',
 ROOM='',
 PART_NUMBER='CH4104K1B00',
 VALUE='0.1UF',
 PRIM_FILE='./archive_libs/logical/q_cap/chips/chips.prt';

PART_NAME
 C97 'Q_CAP_0402-0.1UF,25V,10%,X7R,CH4104K1B00':;

SECTION_NUMBER 1
 '@T6G_MB_LIB.T6G(SCH_1):PAGE232_I69@PURE_QUANTA.Q_CAP(CHIPS)':
 C_PATH='@t6g_mb_lib.t6g(sch_1):page232_i69@pure_quanta.q_cap(chips)',
 P_PATH='@t6g_mb_lib.t6g(sch_1):page233_i69@pure_quanta.q_cap(chips)',
 PATH='I69',
 DRAWING='@T6G_MB_LIB.T6G(SCH_1):PAGE232',
 TOLERANCE='10%',
 MATERIAL='X7R',
 PHYS_PAGE='233',
 XY='(-3625,5175)',
 ROT='0',
 VER='1',
 PACK_TYPE='0402',
 LOCATION='C97',
 CDS_LIB='pure_quanta',
 CDS_PART_NAME='Q_CAP_0402-0.1UF,25V,10%,X7R,CH4104K1B00',
 VOLTAGE='25V',
 PART_NUMBER='CH4104K1B00',
 VALUE='0.1UF',
 PRIM_FILE='./archive_libs/logical/q_cap/chips/chips.prt';

PART_NAME
 C98 'Q_CAP_0402-0.1UF,25V,10%,X7R,CH4104K1B00':;

SECTION_NUMBER 1
 '@T6G_MB_LIB.T6G(SCH_1):PAGE379_I36@PURE_QUANTA.Q_CAP(CHIPS)':
 C_PATH='@t6g_mb_lib.t6g(sch_1):page379_i36@pure_quanta.q_cap(chips)',
 P_PATH='@t6g_mb_lib.t6g(sch_1):page183_i36@pure_quanta.q_cap(chips)',
 PATH='I36',
 DRAWING='@T6G_MB_LIB.T6G(SCH_1):PAGE379',
 TOLERANCE='10%',
 MATERIAL='X7R',
 PHYS_PAGE='183',
 XY='(-3750,5300)',
 ROT='0',
 VER='1',
 PACK_TYPE='0402',
 LOCATION='C98',
 CDS_LIB='pure_quanta',
 CDS_PART_NAME='Q_CAP_0402-0.1UF,25V,10%,X7R,CH4104K1B00',
 VOLTAGE='25V',
 PART_NUMBER='CH4104K1B00',
 VALUE='0.1UF',
 PRIM_FILE='./archive_libs/logical/q_cap/chips/chips.prt';

PART_NAME
 C99 'Q_CAP_0402-0.1UF,25V,10%,X7R,CH4104K1B00':;

SECTION_NUMBER 1
 '@T6G_MB_LIB.T6G(SCH_1):PAGE379_I58@PURE_QUANTA.Q_CAP(CHIPS)':
 C_PATH='@t6g_mb_lib.t6g(sch_1):page379_i58@pure_quanta.q_cap(chips)',
 P_PATH='@t6g_mb_lib.t6g(sch_1):page183_i58@pure_quanta.q_cap(chips)',
 PATH='I58',
 DRAWING='@T6G_MB_LIB.T6G(SCH_1):PAGE379',
 TOLERANCE='10%',
 MATERIAL='X7R',
 PHYS_PAGE='183',
 XY='(-3500,5300)',
 ROT='0',
 VER='1',
 PACK_TYPE='0402',
 LOCATION='C99',
 CDS_LIB='pure_quanta',
 CDS_PART_NAME='Q_CAP_0402-0.1UF,25V,10%,X7R,CH4104K1B00',
 VOLTAGE='25V',
 PART_NUMBER='CH4104K1B00',
 VALUE='0.1UF',
 PRIM_FILE='./archive_libs/logical/q_cap/chips/chips.prt';

PART_NAME
 C100 'Q_CAP_0402-0.1UF,25V,10%,X7R,CH4104K1B00':
 ROOM='';

SECTION_NUMBER 1
 '@T6G_MB_LIB.T6G(SCH_1):PAGE88_I362@PURE_QUANTA.Q_CAP(CHIPS)':
 C_PATH='@t6g_mb_lib.t6g(sch_1):page88_i362@pure_quanta.q_cap(chips)',
 P_PATH='@t6g_mb_lib.t6g(sch_1):page89_i362@pure_quanta.q_cap(chips)',
 PATH='I362',
 DRAWING='@T6G_MB_LIB.T6G(SCH_1):PAGE88',
 BOM_COST='MEM',
 TOLERANCE='10%',
 MATERIAL='X7R',
 PHYS_PAGE='89',
 XY='(-8600,3375)',
 ROT='2',
 VER='1',
 PACK_TYPE='0402',
 LOCATION='C100',
 CDS_LIB='pure_quanta',
 CDS_PART_NAME='Q_CAP_0402-0.1UF,25V,10%,X7R,CH4104K1B00',
 VOLTAGE='25V',
 ROOM='',
 PART_NUMBER='CH4104K1B00',
 VALUE='0.1UF',
 PRIM_FILE='./archive_libs/logical/q_cap/chips/chips.prt';

PART_NAME
 C101 'Q_CAP_0402-1000PF,50V,5%,EMPTY,TMP_QCH21006JB10':;

SECTION_NUMBER 1
 '@T6G_MB_LIB.T6G(SCH_1):PAGE475_I118@PURE_QUANTA.Q_CAP(CHIPS)':
 C_PATH='@t6g_mb_lib.t6g(sch_1):page475_i118@pure_quanta.q_cap(chips)',
 P_PATH='@t6g_mb_lib.t6g(sch_1):page362_i118@pure_quanta.q_cap(chips)',
 PATH='I118',
 DRAWING='@T6G_MB_LIB.T6G(SCH_1):PAGE475',
 SEC_TYPE='0402',
 TOLERANCE='5%',
 MATERIAL='EMPTY',
 PHYS_PAGE='362',
 XY='(-8450,8025)',
 ROT='0',
 VER='2',
 PACK_TYPE='0402',
 LOCATION='C101',
 SEC='1',
 CDS_LIB='pure_quanta',
 CDS_PART_NAME='Q_CAP_0402-1000PF,50V,5%,EMPTY,TMP_QCH21006JB10',
 VOLTAGE='50V',
 PART_NUMBER='TMP_QCH21006JB10',
 VALUE='1000PF',
 PRIM_FILE='./archive_libs/logical/q_cap/chips/chips.prt';

PART_NAME
 C102 'Q_CAP_C0805-100UF,4V,20%,X6S,CH710KMEA01':;

SECTION_NUMBER 1
 '@T6G_MB_LIB.T6G(SCH_1):PAGE443_I16@PURE_QUANTA.Q_CAP(CHIPS)':
 C_PATH='@t6g_mb_lib.t6g(sch_1):page443_i16@pure_quanta.q_cap(chips)',
 P_PATH='@t6g_mb_lib.t6g(sch_1):page334_i16@pure_quanta.q_cap(chips)',
 PATH='I16',
 DRAWING='@T6G_MB_LIB.T6G(SCH_1):PAGE443',
 TOLERANCE='20%',
 MATERIAL='X6S',
 PHYS_PAGE='334',
 XY='(-7075,4825)',
 ROT='0',
 VER='1',
 PACK_TYPE='C0805',
 LOCATION='C102',
 CDS_LIB='pure_quanta',
 CDS_PART_NAME='Q_CAP_C0805-100UF,4V,20%,X6S,CH710KMEA01',
 VOLTAGE='4V',
 PART_NUMBER='CH710KMEA01',
 VALUE='100UF',
 PRIM_FILE='./archive_libs/logical/q_cap/chips/chips.prt';

PART_NAME
 C103 'Q_CAP_C0805-100UF,4V,20%,X6S,CH710KMEA01':;

SECTION_NUMBER 1
 '@T6G_MB_LIB.T6G(SCH_1):PAGE443_I13@PURE_QUANTA.Q_CAP(CHIPS)':
 C_PATH='@t6g_mb_lib.t6g(sch_1):page443_i13@pure_quanta.q_cap(chips)',
 P_PATH='@t6g_mb_lib.t6g(sch_1):page334_i13@pure_quanta.q_cap(chips)',
 PATH='I13',
 DRAWING='@T6G_MB_LIB.T6G(SCH_1):PAGE443',
 TOLERANCE='20%',
 MATERIAL='X6S',
 PHYS_PAGE='334',
 XY='(-7225,4000)',
 ROT='0',
 VER='1',
 PACK_TYPE='C0805',
 LOCATION='C103',
 CDS_LIB='pure_quanta',
 CDS_PART_NAME='Q_CAP_C0805-100UF,4V,20%,X6S,CH710KMEA01',
 VOLTAGE='4V',
 PART_NUMBER='CH710KMEA01',
 VALUE='100UF',
 PRIM_FILE='./archive_libs/logical/q_cap/chips/chips.prt';

PART_NAME
 C104 'Q_CAP_0402-0.1UF,25V,10%,X7R,CH4104K1B00':
 ROOM='';

SECTION_NUMBER 1
 '@T6G_MB_LIB.T6G(SCH_1):PAGE89_I360@PURE_QUANTA.Q_CAP(CHIPS)':
 C_PATH='@t6g_mb_lib.t6g(sch_1):page89_i360@pure_quanta.q_cap(chips)',
 P_PATH='@t6g_mb_lib.t6g(sch_1):page90_i360@pure_quanta.q_cap(chips)',
 PATH='I360',
 DRAWING='@T6G_MB_LIB.T6G(SCH_1):PAGE89',
 BOM_COST='MEM',
 TOLERANCE='10%',
 MATERIAL='X7R',
 PHYS_PAGE='90',
 XY='(-8875,3400)',
 ROT='2',
 VER='1',
 PACK_TYPE='0402',
 LOCATION='C104',
 CDS_LIB='pure_quanta',
 CDS_PART_NAME='Q_CAP_0402-0.1UF,25V,10%,X7R,CH4104K1B00',
 VOLTAGE='25V',
 ROOM='',
 PART_NUMBER='CH4104K1B00',
 VALUE='0.1UF',
 PRIM_FILE='./archive_libs/logical/q_cap/chips/chips.prt';

PART_NAME
 C105 'Q_CAP_0402-0.1UF,25V,10%,EMPTY,CH4104K1B00':;

SECTION_NUMBER 1
 '@T6G_MB_LIB.T6G(SCH_1):PAGE470_I5@PURE_QUANTA.Q_CAP(CHIPS)':
 C_PATH='@t6g_mb_lib.t6g(sch_1):page470_i5@pure_quanta.q_cap(chips)',
 P_PATH='@t6g_mb_lib.t6g(sch_1):page361_i5@pure_quanta.q_cap(chips)',
 PATH='I5',
 DRAWING='@T6G_MB_LIB.T6G(SCH_1):PAGE470',
 TOLERANCE='10%',
 MATERIAL='EMPTY',
 PHYS_PAGE='361',
 XY='(-8500,3250)',
 ROT='2',
 VER='1',
 PACK_TYPE='0402',
 LOCATION='C105',
 CDS_LIB='pure_quanta',
 CDS_PART_NAME='Q_CAP_0402-0.1UF,25V,10%,EMPTY,CH4104K1B00',
 VOLTAGE='25V',
 PART_NUMBER='CH4104K1B00',
 VALUE='0.1UF',
 PRIM_FILE='./archive_libs/logical/q_cap/chips/chips.prt';

PART_NAME
 C106 'Q_CAP_0402-0.1UF,25V,10%,X7R,CH4104K1B00':;

SECTION_NUMBER 1
 '@T6G_MB_LIB.T6G(SCH_1):PAGE252_I34@PURE_QUANTA.Q_CAP(CHIPS)':
 C_PATH='@t6g_mb_lib.t6g(sch_1):page252_i34@pure_quanta.q_cap(chips)',
 P_PATH='@t6g_mb_lib.t6g(sch_1):page250_i34@pure_quanta.q_cap(chips)',
 PATH='I34',
 DRAWING='@T6G_MB_LIB.T6G(SCH_1):PAGE252',
 TOLERANCE='10%',
 MATERIAL='X7R',
 PHYS_PAGE='250',
 XY='(-4800,5300)',
 ROT='0',
 VER='1',
 PACK_TYPE='0402',
 LOCATION='C106',
 CDS_LIB='pure_quanta',
 CDS_PART_NAME='Q_CAP_0402-0.1UF,25V,10%,X7R,CH4104K1B00',
 VOLTAGE='25V',
 PART_NUMBER='CH4104K1B00',
 VALUE='0.1UF',
 PRIM_FILE='./archive_libs/logical/q_cap/chips/chips.prt';

PART_NAME
 C107 'Q_CAP_0402-1000PF,50V,5%,EMPTY,TMP_QCH21006JB10':;

SECTION_NUMBER 1
 '@T6G_MB_LIB.T6G(SCH_1):PAGE477_I45@PURE_QUANTA.Q_CAP(CHIPS)':
 C_PATH='@t6g_mb_lib.t6g(sch_1):page477_i45@pure_quanta.q_cap(chips)',
 P_PATH='@t6g_mb_lib.t6g(sch_1):page364_i45@pure_quanta.q_cap(chips)',
 PATH='I45',
 DRAWING='@T6G_MB_LIB.T6G(SCH_1):PAGE477',
 TOLERANCE='5%',
 MATERIAL='EMPTY',
 PHYS_PAGE='364',
 XY='(-5650,6325)',
 ROT='0',
 VER='2',
 PACK_TYPE='0402',
 LOCATION='C107',
 CDS_LIB='pure_quanta',
 CDS_PART_NAME='Q_CAP_0402-1000PF,50V,5%,EMPTY,TMP_QCH21006JB10',
 VOLTAGE='50V',
 PART_NUMBER='TMP_QCH21006JB10',
 VALUE='1000PF',
 PRIM_FILE='./archive_libs/logical/q_cap/chips/chips.prt';

PART_NAME
 C108 'Q_CAP_0402-0.1UF,25V,10%,X7R,CH4104K1B00':
 ROOM='';

SECTION_NUMBER 1
 '@T6G_MB_LIB.T6G(SCH_1):PAGE90_I361@PURE_QUANTA.Q_CAP(CHIPS)':
 C_PATH='@t6g_mb_lib.t6g(sch_1):page90_i361@pure_quanta.q_cap(chips)',
 P_PATH='@t6g_mb_lib.t6g(sch_1):page91_i361@pure_quanta.q_cap(chips)',
 PATH='I361',
 DRAWING='@T6G_MB_LIB.T6G(SCH_1):PAGE90',
 BOM_COST='MEM',
 TOLERANCE='10%',
 MATERIAL='X7R',
 PHYS_PAGE='91',
 XY='(-8650,3575)',
 ROT='2',
 VER='1',
 PACK_TYPE='0402',
 LOCATION='C108',
 CDS_LIB='pure_quanta',
 CDS_PART_NAME='Q_CAP_0402-0.1UF,25V,10%,X7R,CH4104K1B00',
 VOLTAGE='25V',
 ROOM='',
 PART_NUMBER='CH4104K1B00',
 VALUE='0.1UF',
 PRIM_FILE='./archive_libs/logical/q_cap/chips/chips.prt';

PART_NAME
 C109 'Q_CAP_0402-1000PF,50V,5%,X7R,TMP_QCH21006JB10':;

SECTION_NUMBER 1
 '@T6G_MB_LIB.T6G(SCH_1):PAGE470_I39@PURE_QUANTA.Q_CAP(CHIPS)':
 C_PATH='@t6g_mb_lib.t6g(sch_1):page470_i39@pure_quanta.q_cap(chips)',
 P_PATH='@t6g_mb_lib.t6g(sch_1):page361_i39@pure_quanta.q_cap(chips)',
 PATH='I39',
 DRAWING='@T6G_MB_LIB.T6G(SCH_1):PAGE470',
 TOLERANCE='5%',
 MATERIAL='X7R',
 PHYS_PAGE='361',
 XY='(-2775,3800)',
 ROT='0',
 VER='1',
 PACK_TYPE='0402',
 LOCATION='C109',
 CDS_LIB='pure_quanta',
 CDS_PART_NAME='Q_CAP_0402-1000PF,50V,5%,X7R,TMP_QCH21006JB10',
 VOLTAGE='50V',
 PART_NUMBER='TMP_QCH21006JB10',
 VALUE='1000PF',
 PRIM_FILE='./archive_libs/logical/q_cap/chips/chips.prt';

PART_NAME
 C110 'Q_CAP_C0402-22UF,4V,20%,X6S,CH622KMEB02':;

SECTION_NUMBER 1
 '@T6G_MB_LIB.T6G(SCH_1):PAGE443_I24@PURE_QUANTA.Q_CAP(CHIPS)':
 C_PATH='@t6g_mb_lib.t6g(sch_1):page443_i24@pure_quanta.q_cap(chips)',
 P_PATH='@t6g_mb_lib.t6g(sch_1):page334_i24@pure_quanta.q_cap(chips)',
 PATH='I24',
 DRAWING='@T6G_MB_LIB.T6G(SCH_1):PAGE443',
 TOLERANCE='20%',
 MATERIAL='X6S',
 PHYS_PAGE='334',
 XY='(-6825,4825)',
 ROT='0',
 VER='1',
 PACK_TYPE='C0402',
 LOCATION='C110',
 CDS_LIB='pure_quanta',
 CDS_PART_NAME='Q_CAP_C0402-22UF,4V,20%,X6S,CH622KMEB02',
 VOLTAGE='4V',
 PART_NUMBER='CH622KMEB02',
 VALUE='22UF',
 PRIM_FILE='./archive_libs/logical/q_cap/chips/chips.prt';

PART_NAME
 C111 'Q_CAP_C0402-22UF,4V,20%,X6S,CH622KMEB02':;

SECTION_NUMBER 1
 '@T6G_MB_LIB.T6G(SCH_1):PAGE443_I14@PURE_QUANTA.Q_CAP(CHIPS)':
 C_PATH='@t6g_mb_lib.t6g(sch_1):page443_i14@pure_quanta.q_cap(chips)',
 P_PATH='@t6g_mb_lib.t6g(sch_1):page334_i14@pure_quanta.q_cap(chips)',
 PATH='I14',
 DRAWING='@T6G_MB_LIB.T6G(SCH_1):PAGE443',
 TOLERANCE='20%',
 MATERIAL='X6S',
 PHYS_PAGE='334',
 XY='(-7000,4000)',
 ROT='0',
 VER='1',
 PACK_TYPE='C0402',
 LOCATION='C111',
 CDS_LIB='pure_quanta',
 CDS_PART_NAME='Q_CAP_C0402-22UF,4V,20%,X6S,CH622KMEB02',
 VOLTAGE='4V',
 PART_NUMBER='CH622KMEB02',
 VALUE='22UF',
 PRIM_FILE='./archive_libs/logical/q_cap/chips/chips.prt';

PART_NAME
 C112 'Q_CAP_0402-0.1UF,25V,10%,X7R,CH4104K1B00':
 ROOM='';

SECTION_NUMBER 1
 '@T6G_MB_LIB.T6G(SCH_1):PAGE91_I183@PURE_QUANTA.Q_CAP(CHIPS)':
 C_PATH='@t6g_mb_lib.t6g(sch_1):page91_i183@pure_quanta.q_cap(chips)',
 P_PATH='@t6g_mb_lib.t6g(sch_1):page92_i183@pure_quanta.q_cap(chips)',
 PATH='I183',
 DRAWING='@T6G_MB_LIB.T6G(SCH_1):PAGE91',
 BOM_COST='MEM',
 TOLERANCE='10%',
 MATERIAL='X7R',
 PHYS_PAGE='92',
 XY='(-8500,3225)',
 ROT='2',
 VER='1',
 PACK_TYPE='0402',
 LOCATION='C112',
 CDS_LIB='pure_quanta',
 CDS_PART_NAME='Q_CAP_0402-0.1UF,25V,10%,X7R,CH4104K1B00',
 VOLTAGE='25V',
 ROOM='',
 PART_NUMBER='CH4104K1B00',
 VALUE='0.1UF',
 PRIM_FILE='./archive_libs/logical/q_cap/chips/chips.prt';

PART_NAME
 C113 'Q_CAP_C0805-100UF,4V,20%,X6S,CH710KMEA01':;

SECTION_NUMBER 1
 '@T6G_MB_LIB.T6G(SCH_1):PAGE398_I12@PURE_QUANTA.Q_CAP(CHIPS)':
 C_PATH='@t6g_mb_lib.t6g(sch_1):page398_i12@pure_quanta.q_cap(chips)',
 P_PATH='@t6g_mb_lib.t6g(sch_1):page323_i12@pure_quanta.q_cap(chips)',
 PATH='I12',
 DRAWING='@T6G_MB_LIB.T6G(SCH_1):PAGE398',
 TOLERANCE='20%',
 MATERIAL='X6S',
 PHYS_PAGE='323',
 XY='(-7325,5300)',
 ROT='0',
 VER='1',
 PACK_TYPE='C0805',
 LOCATION='C113',
 CDS_LIB='pure_quanta',
 CDS_PART_NAME='Q_CAP_C0805-100UF,4V,20%,X6S,CH710KMEA01',
 VOLTAGE='4V',
 PART_NUMBER='CH710KMEA01',
 VALUE='100UF',
 PRIM_FILE='./archive_libs/logical/q_cap/chips/chips.prt';

PART_NAME
 C114 'Q_CAP_C0805-100UF,4V,20%,X6S,CH710KMEA01':;

SECTION_NUMBER 1
 '@T6G_MB_LIB.T6G(SCH_1):PAGE398_I4@PURE_QUANTA.Q_CAP(CHIPS)':
 C_PATH='@t6g_mb_lib.t6g(sch_1):page398_i4@pure_quanta.q_cap(chips)',
 P_PATH='@t6g_mb_lib.t6g(sch_1):page323_i4@pure_quanta.q_cap(chips)',
 PATH='I4',
 DRAWING='@T6G_MB_LIB.T6G(SCH_1):PAGE398',
 TOLERANCE='20%',
 MATERIAL='X6S',
 PHYS_PAGE='323',
 XY='(-7475,4475)',
 ROT='0',
 VER='1',
 PACK_TYPE='C0805',
 LOCATION='C114',
 CDS_LIB='pure_quanta',
 CDS_PART_NAME='Q_CAP_C0805-100UF,4V,20%,X6S,CH710KMEA01',
 VOLTAGE='4V',
 PART_NUMBER='CH710KMEA01',
 VALUE='100UF',
 PRIM_FILE='./archive_libs/logical/q_cap/chips/chips.prt';

PART_NAME
 C115 'Q_CAP_C0402-22UF,4V,20%,X6S,CH622KMEB02':;

SECTION_NUMBER 1
 '@T6G_MB_LIB.T6G(SCH_1):PAGE398_I21@PURE_QUANTA.Q_CAP(CHIPS)':
 C_PATH='@t6g_mb_lib.t6g(sch_1):page398_i21@pure_quanta.q_cap(chips)',
 P_PATH='@t6g_mb_lib.t6g(sch_1):page323_i21@pure_quanta.q_cap(chips)',
 PATH='I21',
 DRAWING='@T6G_MB_LIB.T6G(SCH_1):PAGE398',
 TOLERANCE='20%',
 MATERIAL='X6S',
 PHYS_PAGE='323',
 XY='(-7075,5300)',
 ROT='0',
 VER='1',
 PACK_TYPE='C0402',
 LOCATION='C115',
 CDS_LIB='pure_quanta',
 CDS_PART_NAME='Q_CAP_C0402-22UF,4V,20%,X6S,CH622KMEB02',
 VOLTAGE='4V',
 PART_NUMBER='CH622KMEB02',
 VALUE='22UF',
 PRIM_FILE='./archive_libs/logical/q_cap/chips/chips.prt';

PART_NAME
 C116 'Q_CAP_0402-0.1UF,25V,10%,X7R,CH4104K1B00':
 ROOM='';

SECTION_NUMBER 1
 '@T6G_MB_LIB.T6G(SCH_1):PAGE92_I186@PURE_QUANTA.Q_CAP(CHIPS)':
 C_PATH='@t6g_mb_lib.t6g(sch_1):page92_i186@pure_quanta.q_cap(chips)',
 P_PATH='@t6g_mb_lib.t6g(sch_1):page93_i186@pure_quanta.q_cap(chips)',
 PATH='I186',
 DRAWING='@T6G_MB_LIB.T6G(SCH_1):PAGE92',
 BOM_COST='MEM',
 TOLERANCE='10%',
 MATERIAL='X7R',
 PHYS_PAGE='93',
 XY='(-8650,3175)',
 ROT='2',
 VER='1',
 PACK_TYPE='0402',
 LOCATION='C116',
 CDS_LIB='pure_quanta',
 CDS_PART_NAME='Q_CAP_0402-0.1UF,25V,10%,X7R,CH4104K1B00',
 VOLTAGE='25V',
 ROOM='',
 PART_NUMBER='CH4104K1B00',
 VALUE='0.1UF',
 PRIM_FILE='./archive_libs/logical/q_cap/chips/chips.prt';

PART_NAME
 C117 'Q_CAP_C0402-22UF,4V,20%,X6S,CH622KMEB02':;

SECTION_NUMBER 1
 '@T6G_MB_LIB.T6G(SCH_1):PAGE398_I5@PURE_QUANTA.Q_CAP(CHIPS)':
 C_PATH='@t6g_mb_lib.t6g(sch_1):page398_i5@pure_quanta.q_cap(chips)',
 P_PATH='@t6g_mb_lib.t6g(sch_1):page323_i5@pure_quanta.q_cap(chips)',
 PATH='I5',
 DRAWING='@T6G_MB_LIB.T6G(SCH_1):PAGE398',
 TOLERANCE='20%',
 MATERIAL='X6S',
 PHYS_PAGE='323',
 XY='(-7250,4475)',
 ROT='0',
 VER='1',
 PACK_TYPE='C0402',
 LOCATION='C117',
 CDS_LIB='pure_quanta',
 CDS_PART_NAME='Q_CAP_C0402-22UF,4V,20%,X6S,CH622KMEB02',
 VOLTAGE='4V',
 PART_NUMBER='CH622KMEB02',
 VALUE='22UF',
 PRIM_FILE='./archive_libs/logical/q_cap/chips/chips.prt';

PART_NAME
 C118 'Q_CAP_C0402-10UF,6.3V,20%,X6S,CH6101MEB01':;

SECTION_NUMBER 1
 '@T6G_MB_LIB.T6G(SCH_1):PAGE398_I14@PURE_QUANTA.Q_CAP(CHIPS)':
 C_PATH='@t6g_mb_lib.t6g(sch_1):page398_i14@pure_quanta.q_cap(chips)',
 P_PATH='@t6g_mb_lib.t6g(sch_1):page323_i14@pure_quanta.q_cap(chips)',
 PATH='I14',
 DRAWING='@T6G_MB_LIB.T6G(SCH_1):PAGE398',
 TOLERANCE='20%',
 MATERIAL='X6S',
 PHYS_PAGE='323',
 XY='(-6825,5275)',
 ROT='0',
 VER='1',
 PACK_TYPE='C0402',
 LOCATION='C118',
 CDS_LIB='pure_quanta',
 CDS_PART_NAME='Q_CAP_C0402-10UF,6.3V,20%,X6S,CH6101MEB01',
 VOLTAGE='6.3V',
 PART_NUMBER='CH6101MEB01',
 VALUE='10UF',
 PRIM_FILE='./archive_libs/logical/q_cap/chips/chips.prt';

PART_NAME
 C119 'Q_CAP_C0402-10UF,6.3V,20%,X6S,CH6101MEB01':;

SECTION_NUMBER 1
 '@T6G_MB_LIB.T6G(SCH_1):PAGE398_I20@PURE_QUANTA.Q_CAP(CHIPS)':
 C_PATH='@t6g_mb_lib.t6g(sch_1):page398_i20@pure_quanta.q_cap(chips)',
 P_PATH='@t6g_mb_lib.t6g(sch_1):page323_i20@pure_quanta.q_cap(chips)',
 PATH='I20',
 DRAWING='@T6G_MB_LIB.T6G(SCH_1):PAGE398',
 TOLERANCE='20%',
 MATERIAL='X6S',
 PHYS_PAGE='323',
 XY='(-7050,4475)',
 ROT='0',
 VER='1',
 PACK_TYPE='C0402',
 LOCATION='C119',
 CDS_LIB='pure_quanta',
 CDS_PART_NAME='Q_CAP_C0402-10UF,6.3V,20%,X6S,CH6101MEB01',
 VOLTAGE='6.3V',
 PART_NUMBER='CH6101MEB01',
 VALUE='10UF',
 PRIM_FILE='./archive_libs/logical/q_cap/chips/chips.prt';

PART_NAME
 C120 'Q_CAP_0402-0.1UF,25V,10%,X7R,CH4104K1B00':
 ROOM='';

SECTION_NUMBER 1
 '@T6G_MB_LIB.T6G(SCH_1):PAGE93_I185@PURE_QUANTA.Q_CAP(CHIPS)':
 C_PATH='@t6g_mb_lib.t6g(sch_1):page93_i185@pure_quanta.q_cap(chips)',
 P_PATH='@t6g_mb_lib.t6g(sch_1):page94_i185@pure_quanta.q_cap(chips)',
 PATH='I185',
 DRAWING='@T6G_MB_LIB.T6G(SCH_1):PAGE93',
 BOM_COST='MEM',
 TOLERANCE='10%',
 MATERIAL='X7R',
 PHYS_PAGE='94',
 XY='(-8650,3275)',
 ROT='2',
 VER='1',
 PACK_TYPE='0402',
 LOCATION='C120',
 CDS_LIB='pure_quanta',
 CDS_PART_NAME='Q_CAP_0402-0.1UF,25V,10%,X7R,CH4104K1B00',
 VOLTAGE='25V',
 ROOM='',
 PART_NUMBER='CH4104K1B00',
 VALUE='0.1UF',
 PRIM_FILE='./archive_libs/logical/q_cap/chips/chips.prt';

PART_NAME
 C121 'Q_CAP_0402-4.7UF,6.3V,20%,X6S,CH5471MEB01':;

SECTION_NUMBER 1
 '@T6G_MB_LIB.T6G(SCH_1):PAGE398_I7@PURE_QUANTA.Q_CAP(CHIPS)':
 C_PATH='@t6g_mb_lib.t6g(sch_1):page398_i7@pure_quanta.q_cap(chips)',
 P_PATH='@t6g_mb_lib.t6g(sch_1):page323_i7@pure_quanta.q_cap(chips)',
 PATH='I7',
 DRAWING='@T6G_MB_LIB.T6G(SCH_1):PAGE398',
 TOLERANCE='20%',
 MATERIAL='X6S',
 PHYS_PAGE='323',
 XY='(-6850,4475)',
 ROT='0',
 VER='1',
 PACK_TYPE='0402',
 LOCATION='C121',
 CDS_LIB='pure_quanta',
 CDS_PART_NAME='Q_CAP_0402-4.7UF,6.3V,20%,X6S,CH5471MEB01',
 VOLTAGE='6.3V',
 PART_NUMBER='CH5471MEB01',
 VALUE='4.7UF',
 PRIM_FILE='./archive_libs/logical/q_cap/chips/chips.prt';

PART_NAME
 C122 'Q_CAP_0402-4.7UF,6.3V,20%,X6S,CH5471MEB01':;

SECTION_NUMBER 1
 '@T6G_MB_LIB.T6G(SCH_1):PAGE398_I15@PURE_QUANTA.Q_CAP(CHIPS)':
 C_PATH='@t6g_mb_lib.t6g(sch_1):page398_i15@pure_quanta.q_cap(chips)',
 P_PATH='@t6g_mb_lib.t6g(sch_1):page323_i15@pure_quanta.q_cap(chips)',
 PATH='I15',
 DRAWING='@T6G_MB_LIB.T6G(SCH_1):PAGE398',
 TOLERANCE='20%',
 MATERIAL='X6S',
 PHYS_PAGE='323',
 XY='(-6575,5275)',
 ROT='0',
 VER='1',
 PACK_TYPE='0402',
 LOCATION='C122',
 CDS_LIB='pure_quanta',
 CDS_PART_NAME='Q_CAP_0402-4.7UF,6.3V,20%,X6S,CH5471MEB01',
 VOLTAGE='6.3V',
 PART_NUMBER='CH5471MEB01',
 VALUE='4.7UF',
 PRIM_FILE='./archive_libs/logical/q_cap/chips/chips.prt';

PART_NAME
 C123 'Q_CAP_0201-1UF,4V,20%,X6S,CH-10KMEE00':;

SECTION_NUMBER 1
 '@T6G_MB_LIB.T6G(SCH_1):PAGE398_I18@PURE_QUANTA.Q_CAP(CHIPS)':
 C_PATH='@t6g_mb_lib.t6g(sch_1):page398_i18@pure_quanta.q_cap(chips)',
 P_PATH='@t6g_mb_lib.t6g(sch_1):page323_i18@pure_quanta.q_cap(chips)',
 PATH='I18',
 DRAWING='@T6G_MB_LIB.T6G(SCH_1):PAGE398',
 TOLERANCE='20%',
 MATERIAL='X6S',
 PHYS_PAGE='323',
 XY='(-6625,4475)',
 ROT='0',
 VER='1',
 PACK_TYPE='0201',
 LOCATION='C123',
 CDS_LIB='pure_quanta',
 CDS_PART_NAME='Q_CAP_0201-1UF,4V,20%,X6S,CH-10KMEE00',
 VOLTAGE='4V',
 PART_NUMBER='CH-10KMEE00',
 VALUE='1UF',
 PRIM_FILE='./archive_libs/logical/q_cap/chips/chips.prt';

PART_NAME
 C124 'Q_CAP_0402-0.1UF,25V,10%,X7R,CH4104K1B00':
 ROOM='';

SECTION_NUMBER 1
 '@T6G_MB_LIB.T6G(SCH_1):PAGE94_I185@PURE_QUANTA.Q_CAP(CHIPS)':
 C_PATH='@t6g_mb_lib.t6g(sch_1):page94_i185@pure_quanta.q_cap(chips)',
 P_PATH='@t6g_mb_lib.t6g(sch_1):page95_i185@pure_quanta.q_cap(chips)',
 PATH='I185',
 DRAWING='@T6G_MB_LIB.T6G(SCH_1):PAGE94',
 BOM_COST='MEM',
 TOLERANCE='10%',
 MATERIAL='X7R',
 PHYS_PAGE='95',
 XY='(-8550,3175)',
 ROT='2',
 VER='1',
 PACK_TYPE='0402',
 LOCATION='C124',
 CDS_LIB='pure_quanta',
 CDS_PART_NAME='Q_CAP_0402-0.1UF,25V,10%,X7R,CH4104K1B00',
 VOLTAGE='25V',
 ROOM='',
 PART_NUMBER='CH4104K1B00',
 VALUE='0.1UF',
 PRIM_FILE='./archive_libs/logical/q_cap/chips/chips.prt';

PART_NAME
 C125 'Q_CAP_0201-1UF,4V,20%,X6S,CH-10KMEE00':;

SECTION_NUMBER 1
 '@T6G_MB_LIB.T6G(SCH_1):PAGE398_I19@PURE_QUANTA.Q_CAP(CHIPS)':
 C_PATH='@t6g_mb_lib.t6g(sch_1):page398_i19@pure_quanta.q_cap(chips)',
 P_PATH='@t6g_mb_lib.t6g(sch_1):page323_i19@pure_quanta.q_cap(chips)',
 PATH='I19',
 DRAWING='@T6G_MB_LIB.T6G(SCH_1):PAGE398',
 TOLERANCE='20%',
 MATERIAL='X6S',
 PHYS_PAGE='323',
 XY='(-7050,3400)',
 ROT='0',
 VER='1',
 PACK_TYPE='0201',
 LOCATION='C125',
 CDS_LIB='pure_quanta',
 CDS_PART_NAME='Q_CAP_0201-1UF,4V,20%,X6S,CH-10KMEE00',
 VOLTAGE='4V',
 PART_NUMBER='CH-10KMEE00',
 VALUE='1UF',
 PRIM_FILE='./archive_libs/logical/q_cap/chips/chips.prt';

PART_NAME
 C126 'Q_CAP_0201-1UF,4V,20%,X6S,CH-10KMEE00':;

SECTION_NUMBER 1
 '@T6G_MB_LIB.T6G(SCH_1):PAGE398_I9@PURE_QUANTA.Q_CAP(CHIPS)':
 C_PATH='@t6g_mb_lib.t6g(sch_1):page398_i9@pure_quanta.q_cap(chips)',
 P_PATH='@t6g_mb_lib.t6g(sch_1):page323_i9@pure_quanta.q_cap(chips)',
 PATH='I9',
 DRAWING='@T6G_MB_LIB.T6G(SCH_1):PAGE398',
 TOLERANCE='20%',
 MATERIAL='X6S',
 PHYS_PAGE='323',
 XY='(-6425,4475)',
 ROT='0',
 VER='1',
 PACK_TYPE='0201',
 LOCATION='C126',
 CDS_LIB='pure_quanta',
 CDS_PART_NAME='Q_CAP_0201-1UF,4V,20%,X6S,CH-10KMEE00',
 VOLTAGE='4V',
 PART_NUMBER='CH-10KMEE00',
 VALUE='1UF',
 PRIM_FILE='./archive_libs/logical/q_cap/chips/chips.prt';

PART_NAME
 C127 'Q_CAP_C0402-10UF,6.3V,20%,X6S,CH6101MEB01':;

SECTION_NUMBER 1
 '@T6G_MB_LIB.T6G(SCH_1):PAGE443_I25@PURE_QUANTA.Q_CAP(CHIPS)':
 C_PATH='@t6g_mb_lib.t6g(sch_1):page443_i25@pure_quanta.q_cap(chips)',
 P_PATH='@t6g_mb_lib.t6g(sch_1):page334_i25@pure_quanta.q_cap(chips)',
 PATH='I25',
 DRAWING='@T6G_MB_LIB.T6G(SCH_1):PAGE443',
 TOLERANCE='20%',
 MATERIAL='X6S',
 PHYS_PAGE='334',
 XY='(-6575,4800)',
 ROT='0',
 VER='1',
 PACK_TYPE='C0402',
 LOCATION='C127',
 CDS_LIB='pure_quanta',
 CDS_PART_NAME='Q_CAP_C0402-10UF,6.3V,20%,X6S,CH6101MEB01',
 VOLTAGE='6.3V',
 PART_NUMBER='CH6101MEB01',
 VALUE='10UF',
 PRIM_FILE='./archive_libs/logical/q_cap/chips/chips.prt';

PART_NAME
 C128 'Q_CAP_0402-0.1UF,25V,10%,X7R,CH4104K1B00':
 ROOM='';

SECTION_NUMBER 1
 '@T6G_MB_LIB.T6G(SCH_1):PAGE95_I185@PURE_QUANTA.Q_CAP(CHIPS)':
 C_PATH='@t6g_mb_lib.t6g(sch_1):page95_i185@pure_quanta.q_cap(chips)',
 P_PATH='@t6g_mb_lib.t6g(sch_1):page96_i185@pure_quanta.q_cap(chips)',
 PATH='I185',
 DRAWING='@T6G_MB_LIB.T6G(SCH_1):PAGE95',
 BOM_COST='MEM',
 TOLERANCE='10%',
 MATERIAL='X7R',
 PHYS_PAGE='96',
 XY='(-8600,3200)',
 ROT='2',
 VER='1',
 PACK_TYPE='0402',
 LOCATION='C128',
 CDS_LIB='pure_quanta',
 CDS_PART_NAME='Q_CAP_0402-0.1UF,25V,10%,X7R,CH4104K1B00',
 VOLTAGE='25V',
 ROOM='',
 PART_NUMBER='CH4104K1B00',
 VALUE='0.1UF',
 PRIM_FILE='./archive_libs/logical/q_cap/chips/chips.prt';

PART_NAME
 C129 'Q_CAP_C0201-0.1UF,10V,10%,X7S,CH4102K6E00':;

SECTION_NUMBER 1
 '@T6G_MB_LIB.T6G(SCH_1):PAGE398_I23@PURE_QUANTA.Q_CAP(CHIPS)':
 C_PATH='@t6g_mb_lib.t6g(sch_1):page398_i23@pure_quanta.q_cap(chips)',
 P_PATH='@t6g_mb_lib.t6g(sch_1):page323_i23@pure_quanta.q_cap(chips)',
 PATH='I23',
 DRAWING='@T6G_MB_LIB.T6G(SCH_1):PAGE398',
 TOLERANCE='10%',
 MATERIAL='X7S',
 PHYS_PAGE='323',
 XY='(-6200,4475)',
 ROT='0',
 VER='1',
 PACK_TYPE='C0201',
 LOCATION='C129',
 CDS_LIB='pure_quanta',
 CDS_PART_NAME='Q_CAP_C0201-0.1UF,10V,10%,X7S,CH4102K6E00',
 VOLTAGE='10V',
 PART_NUMBER='CH4102K6E00',
 VALUE='0.1UF',
 PRIM_FILE='./archive_libs/logical/q_cap/chips/chips.prt';

PART_NAME
 C130 'Q_CAP_C0201-0.1UF,10V,10%,X7S,CH4102K6E00':;

SECTION_NUMBER 1
 '@T6G_MB_LIB.T6G(SCH_1):PAGE398_I27@PURE_QUANTA.Q_CAP(CHIPS)':
 C_PATH='@t6g_mb_lib.t6g(sch_1):page398_i27@pure_quanta.q_cap(chips)',
 P_PATH='@t6g_mb_lib.t6g(sch_1):page323_i27@pure_quanta.q_cap(chips)',
 PATH='I27',
 DRAWING='@T6G_MB_LIB.T6G(SCH_1):PAGE398',
 TOLERANCE='10%',
 MATERIAL='X7S',
 PHYS_PAGE='323',
 XY='(-6775,3375)',
 ROT='0',
 VER='1',
 PACK_TYPE='C0201',
 LOCATION='C130',
 CDS_LIB='pure_quanta',
 CDS_PART_NAME='Q_CAP_C0201-0.1UF,10V,10%,X7S,CH4102K6E00',
 VOLTAGE='10V',
 PART_NUMBER='CH4102K6E00',
 VALUE='0.1UF',
 PRIM_FILE='./archive_libs/logical/q_cap/chips/chips.prt';

PART_NAME
 C131 'Q_CAP_C0201-0.1UF,10V,10%,X7S,CH4102K6E00':;

SECTION_NUMBER 1
 '@T6G_MB_LIB.T6G(SCH_1):PAGE398_I24@PURE_QUANTA.Q_CAP(CHIPS)':
 C_PATH='@t6g_mb_lib.t6g(sch_1):page398_i24@pure_quanta.q_cap(chips)',
 P_PATH='@t6g_mb_lib.t6g(sch_1):page323_i24@pure_quanta.q_cap(chips)',
 PATH='I24',
 DRAWING='@T6G_MB_LIB.T6G(SCH_1):PAGE398',
 TOLERANCE='10%',
 MATERIAL='X7S',
 PHYS_PAGE='323',
 XY='(-5950,4475)',
 ROT='0',
 VER='1',
 PACK_TYPE='C0201',
 LOCATION='C131',
 CDS_LIB='pure_quanta',
 CDS_PART_NAME='Q_CAP_C0201-0.1UF,10V,10%,X7S,CH4102K6E00',
 VOLTAGE='10V',
 PART_NUMBER='CH4102K6E00',
 VALUE='0.1UF',
 PRIM_FILE='./archive_libs/logical/q_cap/chips/chips.prt';

PART_NAME
 C132 'Q_CAP_0402-0.1UF,25V,10%,X7R,CH4104K1B00':
 ROOM='';

SECTION_NUMBER 1
 '@T6G_MB_LIB.T6G(SCH_1):PAGE96_I185@PURE_QUANTA.Q_CAP(CHIPS)':
 C_PATH='@t6g_mb_lib.t6g(sch_1):page96_i185@pure_quanta.q_cap(chips)',
 P_PATH='@t6g_mb_lib.t6g(sch_1):page97_i185@pure_quanta.q_cap(chips)',
 PATH='I185',
 DRAWING='@T6G_MB_LIB.T6G(SCH_1):PAGE96',
 BOM_COST='MEM',
 TOLERANCE='10%',
 MATERIAL='X7R',
 PHYS_PAGE='97',
 XY='(-8600,2900)',
 ROT='2',
 VER='1',
 PACK_TYPE='0402',
 LOCATION='C132',
 CDS_LIB='pure_quanta',
 CDS_PART_NAME='Q_CAP_0402-0.1UF,25V,10%,X7R,CH4104K1B00',
 VOLTAGE='25V',
 ROOM='',
 PART_NUMBER='CH4104K1B00',
 VALUE='0.1UF',
 PRIM_FILE='./archive_libs/logical/q_cap/chips/chips.prt';

PART_NAME
 C133 'Q_CAP_C0201-0.1UF,10V,10%,X7S,CH4102K6E00':;

SECTION_NUMBER 1
 '@T6G_MB_LIB.T6G(SCH_1):PAGE398_I25@PURE_QUANTA.Q_CAP(CHIPS)':
 C_PATH='@t6g_mb_lib.t6g(sch_1):page398_i25@pure_quanta.q_cap(chips)',
 P_PATH='@t6g_mb_lib.t6g(sch_1):page323_i25@pure_quanta.q_cap(chips)',
 PATH='I25',
 DRAWING='@T6G_MB_LIB.T6G(SCH_1):PAGE398',
 TOLERANCE='10%',
 MATERIAL='X7S',
 PHYS_PAGE='323',
 XY='(-5700,4475)',
 ROT='0',
 VER='1',
 PACK_TYPE='C0201',
 LOCATION='C133',
 CDS_LIB='pure_quanta',
 CDS_PART_NAME='Q_CAP_C0201-0.1UF,10V,10%,X7S,CH4102K6E00',
 VOLTAGE='10V',
 PART_NUMBER='CH4102K6E00',
 VALUE='0.1UF',
 PRIM_FILE='./archive_libs/logical/q_cap/chips/chips.prt';

PART_NAME
 C134 'Q_CAP_C0201-0.1UF,10V,10%,X7S,CH4102K6E00':;

SECTION_NUMBER 1
 '@T6G_MB_LIB.T6G(SCH_1):PAGE398_I26@PURE_QUANTA.Q_CAP(CHIPS)':
 C_PATH='@t6g_mb_lib.t6g(sch_1):page398_i26@pure_quanta.q_cap(chips)',
 P_PATH='@t6g_mb_lib.t6g(sch_1):page323_i26@pure_quanta.q_cap(chips)',
 PATH='I26',
 DRAWING='@T6G_MB_LIB.T6G(SCH_1):PAGE398',
 TOLERANCE='10%',
 MATERIAL='X7S',
 PHYS_PAGE='323',
 XY='(-5425,4475)',
 ROT='0',
 VER='1',
 PACK_TYPE='C0201',
 LOCATION='C134',
 CDS_LIB='pure_quanta',
 CDS_PART_NAME='Q_CAP_C0201-0.1UF,10V,10%,X7S,CH4102K6E00',
 VOLTAGE='10V',
 PART_NUMBER='CH4102K6E00',
 VALUE='0.1UF',
 PRIM_FILE='./archive_libs/logical/q_cap/chips/chips.prt';

PART_NAME
 C135 'Q_CAP_0201-1UF,4V,20%,X6S,CH-10KMEE00':;

SECTION_NUMBER 1
 '@T6G_MB_LIB.T6G(SCH_1):PAGE398_I46@PURE_QUANTA.Q_CAP(CHIPS)':
 C_PATH='@t6g_mb_lib.t6g(sch_1):page398_i46@pure_quanta.q_cap(chips)',
 P_PATH='@t6g_mb_lib.t6g(sch_1):page323_i46@pure_quanta.q_cap(chips)',
 PATH='I46',
 DRAWING='@T6G_MB_LIB.T6G(SCH_1):PAGE398',
 TOLERANCE='20%',
 MATERIAL='X6S',
 PHYS_PAGE='323',
 XY='(-3525,3225)',
 ROT='0',
 VER='1',
 PACK_TYPE='0201',
 LOCATION='C135',
 CDS_LIB='pure_quanta',
 CDS_PART_NAME='Q_CAP_0201-1UF,4V,20%,X6S,CH-10KMEE00',
 VOLTAGE='4V',
 PART_NUMBER='CH-10KMEE00',
 VALUE='1UF',
 PRIM_FILE='./archive_libs/logical/q_cap/chips/chips.prt';

PART_NAME
 C136 'Q_CAP_0402-0.1UF,25V,10%,X7R,CH4104K1B00':
 ROOM='';

SECTION_NUMBER 1
 '@T6G_MB_LIB.T6G(SCH_1):PAGE97_I185@PURE_QUANTA.Q_CAP(CHIPS)':
 C_PATH='@t6g_mb_lib.t6g(sch_1):page97_i185@pure_quanta.q_cap(chips)',
 P_PATH='@t6g_mb_lib.t6g(sch_1):page98_i185@pure_quanta.q_cap(chips)',
 PATH='I185',
 DRAWING='@T6G_MB_LIB.T6G(SCH_1):PAGE97',
 BOM_COST='MEM',
 TOLERANCE='10%',
 MATERIAL='X7R',
 PHYS_PAGE='98',
 XY='(-8600,3325)',
 ROT='2',
 VER='1',
 PACK_TYPE='0402',
 LOCATION='C136',
 CDS_LIB='pure_quanta',
 CDS_PART_NAME='Q_CAP_0402-0.1UF,25V,10%,X7R,CH4104K1B00',
 VOLTAGE='25V',
 ROOM='',
 PART_NUMBER='CH4104K1B00',
 VALUE='0.1UF',
 PRIM_FILE='./archive_libs/logical/q_cap/chips/chips.prt';

PART_NAME
 C137 'Q_CAP_C0201-0.1UF,10V,10%,X7S,CH4102K6E00':;

SECTION_NUMBER 1
 '@T6G_MB_LIB.T6G(SCH_1):PAGE398_I78@PURE_QUANTA.Q_CAP(CHIPS)':
 C_PATH='@t6g_mb_lib.t6g(sch_1):page398_i78@pure_quanta.q_cap(chips)',
 P_PATH='@t6g_mb_lib.t6g(sch_1):page323_i78@pure_quanta.q_cap(chips)',
 PATH='I78',
 DRAWING='@T6G_MB_LIB.T6G(SCH_1):PAGE398',
 TOLERANCE='10%',
 MATERIAL='X7S',
 PHYS_PAGE='323',
 XY='(-2200,5700)',
 ROT='0',
 VER='1',
 PACK_TYPE='C0201',
 LOCATION='C137',
 CDS_LIB='pure_quanta',
 CDS_PART_NAME='Q_CAP_C0201-0.1UF,10V,10%,X7S,CH4102K6E00',
 VOLTAGE='10V',
 PART_NUMBER='CH4102K6E00',
 VALUE='0.1UF',
 PRIM_FILE='./archive_libs/logical/q_cap/chips/chips.prt';

PART_NAME
 C138 'Q_CAP_0201-1UF,4V,20%,X6S,CH-10KMEE00':;

SECTION_NUMBER 1
 '@T6G_MB_LIB.T6G(SCH_1):PAGE398_I48@PURE_QUANTA.Q_CAP(CHIPS)':
 C_PATH='@t6g_mb_lib.t6g(sch_1):page398_i48@pure_quanta.q_cap(chips)',
 P_PATH='@t6g_mb_lib.t6g(sch_1):page323_i48@pure_quanta.q_cap(chips)',
 PATH='I48',
 DRAWING='@T6G_MB_LIB.T6G(SCH_1):PAGE398',
 TOLERANCE='20%',
 MATERIAL='X6S',
 PHYS_PAGE='323',
 XY='(-3050,3225)',
 ROT='0',
 VER='1',
 PACK_TYPE='0201',
 LOCATION='C138',
 CDS_LIB='pure_quanta',
 CDS_PART_NAME='Q_CAP_0201-1UF,4V,20%,X6S,CH-10KMEE00',
 VOLTAGE='4V',
 PART_NUMBER='CH-10KMEE00',
 VALUE='1UF',
 PRIM_FILE='./archive_libs/logical/q_cap/chips/chips.prt';

PART_NAME
 C139 'Q_CAP_C0201-0.1UF,10V,10%,X7S,CH4102K6E00':;

SECTION_NUMBER 1
 '@T6G_MB_LIB.T6G(SCH_1):PAGE398_I77@PURE_QUANTA.Q_CAP(CHIPS)':
 C_PATH='@t6g_mb_lib.t6g(sch_1):page398_i77@pure_quanta.q_cap(chips)',
 P_PATH='@t6g_mb_lib.t6g(sch_1):page323_i77@pure_quanta.q_cap(chips)',
 PATH='I77',
 DRAWING='@T6G_MB_LIB.T6G(SCH_1):PAGE398',
 TOLERANCE='10%',
 MATERIAL='X7S',
 PHYS_PAGE='323',
 XY='(-1925,5700)',
 ROT='0',
 VER='1',
 PACK_TYPE='C0201',
 LOCATION='C139',
 CDS_LIB='pure_quanta',
 CDS_PART_NAME='Q_CAP_C0201-0.1UF,10V,10%,X7S,CH4102K6E00',
 VOLTAGE='10V',
 PART_NUMBER='CH4102K6E00',
 VALUE='0.1UF',
 PRIM_FILE='./archive_libs/logical/q_cap/chips/chips.prt';

PART_NAME
 C140 'Q_CAP_0402-0.1UF,25V,10%,X7R,CH4104K1B00':
 ROOM='';

SECTION_NUMBER 1
 '@T6G_MB_LIB.T6G(SCH_1):PAGE98_I185@PURE_QUANTA.Q_CAP(CHIPS)':
 C_PATH='@t6g_mb_lib.t6g(sch_1):page98_i185@pure_quanta.q_cap(chips)',
 P_PATH='@t6g_mb_lib.t6g(sch_1):page99_i185@pure_quanta.q_cap(chips)',
 PATH='I185',
 DRAWING='@T6G_MB_LIB.T6G(SCH_1):PAGE98',
 BOM_COST='MEM',
 TOLERANCE='10%',
 MATERIAL='X7R',
 PHYS_PAGE='99',
 XY='(-8725,3325)',
 ROT='2',
 VER='1',
 PACK_TYPE='0402',
 LOCATION='C140',
 CDS_LIB='pure_quanta',
 CDS_PART_NAME='Q_CAP_0402-0.1UF,25V,10%,X7R,CH4104K1B00',
 VOLTAGE='25V',
 ROOM='',
 PART_NUMBER='CH4104K1B00',
 VALUE='0.1UF',
 PRIM_FILE='./archive_libs/logical/q_cap/chips/chips.prt';

PART_NAME
 C141 'Q_CAP_C0201-0.1UF,10V,10%,X7S,CH4102K6E00':;

SECTION_NUMBER 1
 '@T6G_MB_LIB.T6G(SCH_1):PAGE398_I82@PURE_QUANTA.Q_CAP(CHIPS)':
 C_PATH='@t6g_mb_lib.t6g(sch_1):page398_i82@pure_quanta.q_cap(chips)',
 P_PATH='@t6g_mb_lib.t6g(sch_1):page323_i82@pure_quanta.q_cap(chips)',
 PATH='I82',
 DRAWING='@T6G_MB_LIB.T6G(SCH_1):PAGE398',
 TOLERANCE='10%',
 MATERIAL='X7S',
 PHYS_PAGE='323',
 XY='(-3475,2525)',
 ROT='0',
 VER='1',
 PACK_TYPE='C0201',
 LOCATION='C141',
 CDS_LIB='pure_quanta',
 CDS_PART_NAME='Q_CAP_C0201-0.1UF,10V,10%,X7S,CH4102K6E00',
 VOLTAGE='10V',
 PART_NUMBER='CH4102K6E00',
 VALUE='0.1UF',
 PRIM_FILE='./archive_libs/logical/q_cap/chips/chips.prt';

PART_NAME
 C142 'Q_CAP_C0805-10UF,25V,10%,X6S,CH6104KEA00':
 ROOM='';

SECTION_NUMBER 1
 '@T6G_MB_LIB.T6G(SCH_1):PAGE85_I534@PURE_QUANTA.Q_CAP(CHIPS)':
 C_PATH='@t6g_mb_lib.t6g(sch_1):page85_i534@pure_quanta.q_cap(chips)',
 P_PATH='@t6g_mb_lib.t6g(sch_1):page86_i534@pure_quanta.q_cap(chips)',
 PATH='I534',
 DRAWING='@T6G_MB_LIB.T6G(SCH_1):PAGE85',
 BOM_COST='MEM',
 TOLERANCE='10%',
 MATERIAL='X6S',
 PHYS_PAGE='86',
 XY='(-2375,6050)',
 ROT='2',
 VER='1',
 PACK_TYPE='C0805',
 LOCATION='C142',
 CDS_LIB='pure_quanta',
 CDS_PART_NAME='Q_CAP_C0805-10UF,25V,10%,X6S,CH6104KEA00',
 VOLTAGE='25V',
 ROOM='',
 PART_NUMBER='CH6104KEA00',
 VALUE='10UF',
 PRIM_FILE='./archive_libs/logical/q_cap/chips/chips.prt';

PART_NAME
 C143 'Q_CAP_C0805-10UF,25V,10%,X6S,CH6104KEA00':
 ROOM='';

SECTION_NUMBER 1
 '@T6G_MB_LIB.T6G(SCH_1):PAGE86_I369@PURE_QUANTA.Q_CAP(CHIPS)':
 C_PATH='@t6g_mb_lib.t6g(sch_1):page86_i369@pure_quanta.q_cap(chips)',
 P_PATH='@t6g_mb_lib.t6g(sch_1):page87_i369@pure_quanta.q_cap(chips)',
 PATH='I369',
 DRAWING='@T6G_MB_LIB.T6G(SCH_1):PAGE86',
 BOM_COST='MEM',
 TOLERANCE='10%',
 MATERIAL='X6S',
 PHYS_PAGE='87',
 XY='(-2825,5575)',
 ROT='2',
 VER='1',
 PACK_TYPE='C0805',
 LOCATION='C143',
 CDS_LIB='pure_quanta',
 CDS_PART_NAME='Q_CAP_C0805-10UF,25V,10%,X6S,CH6104KEA00',
 VOLTAGE='25V',
 ROOM='',
 PART_NUMBER='CH6104KEA00',
 VALUE='10UF',
 PRIM_FILE='./archive_libs/logical/q_cap/chips/chips.prt';

PART_NAME
 C144 'Q_CAP_0402-0.1UF,25V,10%,X7R,CH4104K1B00':
 ROOM='';

SECTION_NUMBER 1
 '@T6G_MB_LIB.T6G(SCH_1):PAGE99_I185@PURE_QUANTA.Q_CAP(CHIPS)':
 C_PATH='@t6g_mb_lib.t6g(sch_1):page99_i185@pure_quanta.q_cap(chips)',
 P_PATH='@t6g_mb_lib.t6g(sch_1):page100_i185@pure_quanta.q_cap(chips)',
 PATH='I185',
 DRAWING='@T6G_MB_LIB.T6G(SCH_1):PAGE99',
 BOM_COST='MEM',
 TOLERANCE='10%',
 MATERIAL='X7R',
 PHYS_PAGE='100',
 XY='(-8775,3225)',
 ROT='2',
 VER='1',
 PACK_TYPE='0402',
 LOCATION='C144',
 CDS_LIB='pure_quanta',
 CDS_PART_NAME='Q_CAP_0402-0.1UF,25V,10%,X7R,CH4104K1B00',
 VOLTAGE='25V',
 ROOM='',
 PART_NUMBER='CH4104K1B00',
 VALUE='0.1UF',
 PRIM_FILE='./archive_libs/logical/q_cap/chips/chips.prt';

PART_NAME
 C145 'Q_CAP_C0805-10UF,25V,10%,X6S,CH6104KEA00':
 ROOM='';

SECTION_NUMBER 1
 '@T6G_MB_LIB.T6G(SCH_1):PAGE86_I370@PURE_QUANTA.Q_CAP(CHIPS)':
 C_PATH='@t6g_mb_lib.t6g(sch_1):page86_i370@pure_quanta.q_cap(chips)',
 P_PATH='@t6g_mb_lib.t6g(sch_1):page87_i370@pure_quanta.q_cap(chips)',
 PATH='I370',
 DRAWING='@T6G_MB_LIB.T6G(SCH_1):PAGE86',
 BOM_COST='MEM',
 TOLERANCE='10%',
 MATERIAL='X6S',
 PHYS_PAGE='87',
 XY='(-2250,5575)',
 ROT='2',
 VER='1',
 PACK_TYPE='C0805',
 LOCATION='C145',
 CDS_LIB='pure_quanta',
 CDS_PART_NAME='Q_CAP_C0805-10UF,25V,10%,X6S,CH6104KEA00',
 VOLTAGE='25V',
 ROOM='',
 PART_NUMBER='CH6104KEA00',
 VALUE='10UF',
 PRIM_FILE='./archive_libs/logical/q_cap/chips/chips.prt';

PART_NAME
 C146 'Q_CAP_C0805-10UF,25V,10%,X6S,CH6104KEA00':
 ROOM='';

SECTION_NUMBER 1
 '@T6G_MB_LIB.T6G(SCH_1):PAGE87_I413@PURE_QUANTA.Q_CAP(CHIPS)':
 C_PATH='@t6g_mb_lib.t6g(sch_1):page87_i413@pure_quanta.q_cap(chips)',
 P_PATH='@t6g_mb_lib.t6g(sch_1):page88_i413@pure_quanta.q_cap(chips)',
 PATH='I413',
 DRAWING='@T6G_MB_LIB.T6G(SCH_1):PAGE87',
 BOM_COST='MEM',
 TOLERANCE='10%',
 MATERIAL='X6S',
 PHYS_PAGE='88',
 XY='(-3000,6150)',
 ROT='2',
 VER='1',
 PACK_TYPE='C0805',
 LOCATION='C146',
 CDS_LIB='pure_quanta',
 CDS_PART_NAME='Q_CAP_C0805-10UF,25V,10%,X6S,CH6104KEA00',
 VOLTAGE='25V',
 ROOM='',
 PART_NUMBER='CH6104KEA00',
 VALUE='10UF',
 PRIM_FILE='./archive_libs/logical/q_cap/chips/chips.prt';

PART_NAME
 C147 'Q_CAP_C0805-10UF,25V,10%,X6S,CH6104KEA00':
 ROOM='';

SECTION_NUMBER 1
 '@T6G_MB_LIB.T6G(SCH_1):PAGE87_I414@PURE_QUANTA.Q_CAP(CHIPS)':
 C_PATH='@t6g_mb_lib.t6g(sch_1):page87_i414@pure_quanta.q_cap(chips)',
 P_PATH='@t6g_mb_lib.t6g(sch_1):page88_i414@pure_quanta.q_cap(chips)',
 PATH='I414',
 DRAWING='@T6G_MB_LIB.T6G(SCH_1):PAGE87',
 BOM_COST='MEM',
 TOLERANCE='10%',
 MATERIAL='X6S',
 PHYS_PAGE='88',
 XY='(-2425,6150)',
 ROT='2',
 VER='1',
 PACK_TYPE='C0805',
 LOCATION='C147',
 CDS_LIB='pure_quanta',
 CDS_PART_NAME='Q_CAP_C0805-10UF,25V,10%,X6S,CH6104KEA00',
 VOLTAGE='25V',
 ROOM='',
 PART_NUMBER='CH6104KEA00',
 VALUE='10UF',
 PRIM_FILE='./archive_libs/logical/q_cap/chips/chips.prt';

PART_NAME
 C148 'Q_CAP_0402-0.1UF,25V,10%,X7R,CH4104K1B00':
 ROOM='';

SECTION_NUMBER 1
 '@T6G_MB_LIB.T6G(SCH_1):PAGE100_I185@PURE_QUANTA.Q_CAP(CHIPS)':
 C_PATH='@t6g_mb_lib.t6g(sch_1):page100_i185@pure_quanta.q_cap(chips)',
 P_PATH='@t6g_mb_lib.t6g(sch_1):page101_i185@pure_quanta.q_cap(chips)',
 PATH='I185',
 DRAWING='@T6G_MB_LIB.T6G(SCH_1):PAGE100',
 BOM_COST='MEM',
 TOLERANCE='10%',
 MATERIAL='X7R',
 PHYS_PAGE='101',
 XY='(-8750,3400)',
 ROT='2',
 VER='1',
 PACK_TYPE='0402',
 LOCATION='C148',
 CDS_LIB='pure_quanta',
 CDS_PART_NAME='Q_CAP_0402-0.1UF,25V,10%,X7R,CH4104K1B00',
 VOLTAGE='25V',
 ROOM='',
 PART_NUMBER='CH4104K1B00',
 VALUE='0.1UF',
 PRIM_FILE='./archive_libs/logical/q_cap/chips/chips.prt';

PART_NAME
 C149 'Q_CAP_C0805-10UF,25V,10%,X6S,CH6104KEA00':
 ROOM='';

SECTION_NUMBER 1
 '@T6G_MB_LIB.T6G(SCH_1):PAGE88_I417@PURE_QUANTA.Q_CAP(CHIPS)':
 C_PATH='@t6g_mb_lib.t6g(sch_1):page88_i417@pure_quanta.q_cap(chips)',
 P_PATH='@t6g_mb_lib.t6g(sch_1):page89_i417@pure_quanta.q_cap(chips)',
 PATH='I417',
 DRAWING='@T6G_MB_LIB.T6G(SCH_1):PAGE88',
 BOM_COST='MEM',
 TOLERANCE='10%',
 MATERIAL='X6S',
 PHYS_PAGE='89',
 XY='(-2950,5575)',
 ROT='2',
 VER='1',
 PACK_TYPE='C0805',
 LOCATION='C149',
 CDS_LIB='pure_quanta',
 CDS_PART_NAME='Q_CAP_C0805-10UF,25V,10%,X6S,CH6104KEA00',
 VOLTAGE='25V',
 ROOM='',
 PART_NUMBER='CH6104KEA00',
 VALUE='10UF',
 PRIM_FILE='./archive_libs/logical/q_cap/chips/chips.prt';

PART_NAME
 C150 'Q_CAP_C0805-10UF,25V,10%,X6S,CH6104KEA00':
 ROOM='';

SECTION_NUMBER 1
 '@T6G_MB_LIB.T6G(SCH_1):PAGE88_I418@PURE_QUANTA.Q_CAP(CHIPS)':
 C_PATH='@t6g_mb_lib.t6g(sch_1):page88_i418@pure_quanta.q_cap(chips)',
 P_PATH='@t6g_mb_lib.t6g(sch_1):page89_i418@pure_quanta.q_cap(chips)',
 PATH='I418',
 DRAWING='@T6G_MB_LIB.T6G(SCH_1):PAGE88',
 BOM_COST='MEM',
 TOLERANCE='10%',
 MATERIAL='X6S',
 PHYS_PAGE='89',
 XY='(-2375,5575)',
 ROT='2',
 VER='1',
 PACK_TYPE='C0805',
 LOCATION='C150',
 CDS_LIB='pure_quanta',
 CDS_PART_NAME='Q_CAP_C0805-10UF,25V,10%,X6S,CH6104KEA00',
 VOLTAGE='25V',
 ROOM='',
 PART_NUMBER='CH6104KEA00',
 VALUE='10UF',
 PRIM_FILE='./archive_libs/logical/q_cap/chips/chips.prt';

PART_NAME
 C151 'Q_CAP_C0805-10UF,25V,10%,X6S,CH6104KEA00':
 ROOM='';

SECTION_NUMBER 1
 '@T6G_MB_LIB.T6G(SCH_1):PAGE89_I412@PURE_QUANTA.Q_CAP(CHIPS)':
 C_PATH='@t6g_mb_lib.t6g(sch_1):page89_i412@pure_quanta.q_cap(chips)',
 P_PATH='@t6g_mb_lib.t6g(sch_1):page90_i412@pure_quanta.q_cap(chips)',
 PATH='I412',
 DRAWING='@T6G_MB_LIB.T6G(SCH_1):PAGE89',
 BOM_COST='MEM',
 TOLERANCE='10%',
 MATERIAL='X6S',
 PHYS_PAGE='90',
 XY='(-2975,6050)',
 ROT='2',
 VER='1',
 PACK_TYPE='C0805',
 LOCATION='C151',
 CDS_LIB='pure_quanta',
 CDS_PART_NAME='Q_CAP_C0805-10UF,25V,10%,X6S,CH6104KEA00',
 VOLTAGE='25V',
 ROOM='',
 PART_NUMBER='CH6104KEA00',
 VALUE='10UF',
 PRIM_FILE='./archive_libs/logical/q_cap/chips/chips.prt';

PART_NAME
 C152 'Q_CAP_0402-0.1UF,25V,10%,X7R,CH4104K1B00':
 ROOM='';

SECTION_NUMBER 1
 '@T6G_MB_LIB.T6G(SCH_1):PAGE101_I185@PURE_QUANTA.Q_CAP(CHIPS)':
 C_PATH='@t6g_mb_lib.t6g(sch_1):page101_i185@pure_quanta.q_cap(chips)',
 P_PATH='@t6g_mb_lib.t6g(sch_1):page102_i185@pure_quanta.q_cap(chips)',
 PATH='I185',
 DRAWING='@T6G_MB_LIB.T6G(SCH_1):PAGE101',
 BOM_COST='MEM',
 TOLERANCE='10%',
 MATERIAL='X7R',
 PHYS_PAGE='102',
 XY='(-8800,3475)',
 ROT='2',
 VER='1',
 PACK_TYPE='0402',
 LOCATION='C152',
 CDS_LIB='pure_quanta',
 CDS_PART_NAME='Q_CAP_0402-0.1UF,25V,10%,X7R,CH4104K1B00',
 VOLTAGE='25V',
 ROOM='',
 PART_NUMBER='CH4104K1B00',
 VALUE='0.1UF',
 PRIM_FILE='./archive_libs/logical/q_cap/chips/chips.prt';

PART_NAME
 C153 'Q_CAP_C0805-10UF,25V,10%,X6S,CH6104KEA00':
 ROOM='';

SECTION_NUMBER 1
 '@T6G_MB_LIB.T6G(SCH_1):PAGE89_I413@PURE_QUANTA.Q_CAP(CHIPS)':
 C_PATH='@t6g_mb_lib.t6g(sch_1):page89_i413@pure_quanta.q_cap(chips)',
 P_PATH='@t6g_mb_lib.t6g(sch_1):page90_i413@pure_quanta.q_cap(chips)',
 PATH='I413',
 DRAWING='@T6G_MB_LIB.T6G(SCH_1):PAGE89',
 BOM_COST='MEM',
 TOLERANCE='10%',
 MATERIAL='X6S',
 PHYS_PAGE='90',
 XY='(-2400,6050)',
 ROT='2',
 VER='1',
 PACK_TYPE='C0805',
 LOCATION='C153',
 CDS_LIB='pure_quanta',
 CDS_PART_NAME='Q_CAP_C0805-10UF,25V,10%,X6S,CH6104KEA00',
 VOLTAGE='25V',
 ROOM='',
 PART_NUMBER='CH6104KEA00',
 VALUE='10UF',
 PRIM_FILE='./archive_libs/logical/q_cap/chips/chips.prt';

PART_NAME
 C154 'Q_CAP_C0805-10UF,25V,10%,X6S,CH6104KEA00':
 ROOM='';

SECTION_NUMBER 1
 '@T6G_MB_LIB.T6G(SCH_1):PAGE90_I414@PURE_QUANTA.Q_CAP(CHIPS)':
 C_PATH='@t6g_mb_lib.t6g(sch_1):page90_i414@pure_quanta.q_cap(chips)',
 P_PATH='@t6g_mb_lib.t6g(sch_1):page91_i414@pure_quanta.q_cap(chips)',
 PATH='I414',
 DRAWING='@T6G_MB_LIB.T6G(SCH_1):PAGE90',
 BOM_COST='MEM',
 TOLERANCE='10%',
 MATERIAL='X6S',
 PHYS_PAGE='91',
 XY='(-2925,6150)',
 ROT='2',
 VER='1',
 PACK_TYPE='C0805',
 LOCATION='C154',
 CDS_LIB='pure_quanta',
 CDS_PART_NAME='Q_CAP_C0805-10UF,25V,10%,X6S,CH6104KEA00',
 VOLTAGE='25V',
 ROOM='',
 PART_NUMBER='CH6104KEA00',
 VALUE='10UF',
 PRIM_FILE='./archive_libs/logical/q_cap/chips/chips.prt';

PART_NAME
 C155 'Q_CAP_C0805-10UF,25V,10%,X6S,CH6104KEA00':
 ROOM='';

SECTION_NUMBER 1
 '@T6G_MB_LIB.T6G(SCH_1):PAGE90_I415@PURE_QUANTA.Q_CAP(CHIPS)':
 C_PATH='@t6g_mb_lib.t6g(sch_1):page90_i415@pure_quanta.q_cap(chips)',
 P_PATH='@t6g_mb_lib.t6g(sch_1):page91_i415@pure_quanta.q_cap(chips)',
 PATH='I415',
 DRAWING='@T6G_MB_LIB.T6G(SCH_1):PAGE90',
 BOM_COST='MEM',
 TOLERANCE='10%',
 MATERIAL='X6S',
 PHYS_PAGE='91',
 XY='(-2350,6150)',
 ROT='2',
 VER='1',
 PACK_TYPE='C0805',
 LOCATION='C155',
 CDS_LIB='pure_quanta',
 CDS_PART_NAME='Q_CAP_C0805-10UF,25V,10%,X6S,CH6104KEA00',
 VOLTAGE='25V',
 ROOM='',
 PART_NUMBER='CH6104KEA00',
 VALUE='10UF',
 PRIM_FILE='./archive_libs/logical/q_cap/chips/chips.prt';

PART_NAME
 C156 'Q_CAP_0402-0.1UF,25V,10%,X7R,CH4104K1B00':
 ROOM='';

SECTION_NUMBER 1
 '@T6G_MB_LIB.T6G(SCH_1):PAGE102_I185@PURE_QUANTA.Q_CAP(CHIPS)':
 C_PATH='@t6g_mb_lib.t6g(sch_1):page102_i185@pure_quanta.q_cap(chips)',
 P_PATH='@t6g_mb_lib.t6g(sch_1):page103_i185@pure_quanta.q_cap(chips)',
 PATH='I185',
 DRAWING='@T6G_MB_LIB.T6G(SCH_1):PAGE102',
 BOM_COST='MEM',
 TOLERANCE='10%',
 MATERIAL='X7R',
 PHYS_PAGE='103',
 XY='(-8675,3350)',
 ROT='2',
 VER='1',
 PACK_TYPE='0402',
 LOCATION='C156',
 CDS_LIB='pure_quanta',
 CDS_PART_NAME='Q_CAP_0402-0.1UF,25V,10%,X7R,CH4104K1B00',
 VOLTAGE='25V',
 ROOM='',
 PART_NUMBER='CH4104K1B00',
 VALUE='0.1UF',
 PRIM_FILE='./archive_libs/logical/q_cap/chips/chips.prt';

PART_NAME
 C157 'Q_CAP_C0805-10UF,25V,10%,X6S,CH6104KEA00':
 ROOM='';

SECTION_NUMBER 1
 '@T6G_MB_LIB.T6G(SCH_1):PAGE91_I238@PURE_QUANTA.Q_CAP(CHIPS)':
 C_PATH='@t6g_mb_lib.t6g(sch_1):page91_i238@pure_quanta.q_cap(chips)',
 P_PATH='@t6g_mb_lib.t6g(sch_1):page92_i238@pure_quanta.q_cap(chips)',
 PATH='I238',
 DRAWING='@T6G_MB_LIB.T6G(SCH_1):PAGE91',
 BOM_COST='MEM',
 TOLERANCE='10%',
 MATERIAL='X6S',
 PHYS_PAGE='92',
 XY='(-2675,5875)',
 ROT='2',
 VER='1',
 PACK_TYPE='C0805',
 LOCATION='C157',
 CDS_LIB='pure_quanta',
 CDS_PART_NAME='Q_CAP_C0805-10UF,25V,10%,X6S,CH6104KEA00',
 VOLTAGE='25V',
 ROOM='',
 PART_NUMBER='CH6104KEA00',
 VALUE='10UF',
 PRIM_FILE='./archive_libs/logical/q_cap/chips/chips.prt';

PART_NAME
 C158 'Q_CAP_C0805-10UF,25V,10%,X6S,CH6104KEA00':
 ROOM='';

SECTION_NUMBER 1
 '@T6G_MB_LIB.T6G(SCH_1):PAGE91_I239@PURE_QUANTA.Q_CAP(CHIPS)':
 C_PATH='@t6g_mb_lib.t6g(sch_1):page91_i239@pure_quanta.q_cap(chips)',
 P_PATH='@t6g_mb_lib.t6g(sch_1):page92_i239@pure_quanta.q_cap(chips)',
 PATH='I239',
 DRAWING='@T6G_MB_LIB.T6G(SCH_1):PAGE91',
 BOM_COST='MEM',
 TOLERANCE='10%',
 MATERIAL='X6S',
 PHYS_PAGE='92',
 XY='(-2100,5875)',
 ROT='2',
 VER='1',
 PACK_TYPE='C0805',
 LOCATION='C158',
 CDS_LIB='pure_quanta',
 CDS_PART_NAME='Q_CAP_C0805-10UF,25V,10%,X6S,CH6104KEA00',
 VOLTAGE='25V',
 ROOM='',
 PART_NUMBER='CH6104KEA00',
 VALUE='10UF',
 PRIM_FILE='./archive_libs/logical/q_cap/chips/chips.prt';

PART_NAME
 C159 'Q_CAP_C0805-10UF,25V,10%,X6S,CH6104KEA00':
 ROOM='';

SECTION_NUMBER 1
 '@T6G_MB_LIB.T6G(SCH_1):PAGE92_I239@PURE_QUANTA.Q_CAP(CHIPS)':
 C_PATH='@t6g_mb_lib.t6g(sch_1):page92_i239@pure_quanta.q_cap(chips)',
 P_PATH='@t6g_mb_lib.t6g(sch_1):page93_i239@pure_quanta.q_cap(chips)',
 PATH='I239',
 DRAWING='@T6G_MB_LIB.T6G(SCH_1):PAGE92',
 BOM_COST='MEM',
 TOLERANCE='10%',
 MATERIAL='X6S',
 PHYS_PAGE='93',
 XY='(-2900,6000)',
 ROT='2',
 VER='1',
 PACK_TYPE='C0805',
 LOCATION='C159',
 CDS_LIB='pure_quanta',
 CDS_PART_NAME='Q_CAP_C0805-10UF,25V,10%,X6S,CH6104KEA00',
 VOLTAGE='25V',
 ROOM='',
 PART_NUMBER='CH6104KEA00',
 VALUE='10UF',
 PRIM_FILE='./archive_libs/logical/q_cap/chips/chips.prt';

PART_NAME
 C160 'Q_CAP_0402-0.1UF,25V,10%,X7R,CH4104K1B00':
 ROOM='';

SECTION_NUMBER 1
 '@T6G_MB_LIB.T6G(SCH_1):PAGE103_I185@PURE_QUANTA.Q_CAP(CHIPS)':
 C_PATH='@t6g_mb_lib.t6g(sch_1):page103_i185@pure_quanta.q_cap(chips)',
 P_PATH='@t6g_mb_lib.t6g(sch_1):page104_i185@pure_quanta.q_cap(chips)',
 PATH='I185',
 DRAWING='@T6G_MB_LIB.T6G(SCH_1):PAGE103',
 BOM_COST='MEM',
 TOLERANCE='10%',
 MATERIAL='X7R',
 PHYS_PAGE='104',
 XY='(-8675,3200)',
 ROT='2',
 VER='1',
 PACK_TYPE='0402',
 LOCATION='C160',
 CDS_LIB='pure_quanta',
 CDS_PART_NAME='Q_CAP_0402-0.1UF,25V,10%,X7R,CH4104K1B00',
 VOLTAGE='25V',
 ROOM='',
 PART_NUMBER='CH4104K1B00',
 VALUE='0.1UF',
 PRIM_FILE='./archive_libs/logical/q_cap/chips/chips.prt';

PART_NAME
 C161 'Q_CAP_C0805-10UF,25V,10%,X6S,CH6104KEA00':
 ROOM='';

SECTION_NUMBER 1
 '@T6G_MB_LIB.T6G(SCH_1):PAGE92_I240@PURE_QUANTA.Q_CAP(CHIPS)':
 C_PATH='@t6g_mb_lib.t6g(sch_1):page92_i240@pure_quanta.q_cap(chips)',
 P_PATH='@t6g_mb_lib.t6g(sch_1):page93_i240@pure_quanta.q_cap(chips)',
 PATH='I240',
 DRAWING='@T6G_MB_LIB.T6G(SCH_1):PAGE92',
 BOM_COST='MEM',
 TOLERANCE='10%',
 MATERIAL='X6S',
 PHYS_PAGE='93',
 XY='(-2325,6000)',
 ROT='2',
 VER='1',
 PACK_TYPE='C0805',
 LOCATION='C161',
 CDS_LIB='pure_quanta',
 CDS_PART_NAME='Q_CAP_C0805-10UF,25V,10%,X6S,CH6104KEA00',
 VOLTAGE='25V',
 ROOM='',
 PART_NUMBER='CH6104KEA00',
 VALUE='10UF',
 PRIM_FILE='./archive_libs/logical/q_cap/chips/chips.prt';

PART_NAME
 C162 'Q_CAP_C0805-10UF,25V,10%,X6S,CH6104KEA00':
 ROOM='';

SECTION_NUMBER 1
 '@T6G_MB_LIB.T6G(SCH_1):PAGE93_I238@PURE_QUANTA.Q_CAP(CHIPS)':
 C_PATH='@t6g_mb_lib.t6g(sch_1):page93_i238@pure_quanta.q_cap(chips)',
 P_PATH='@t6g_mb_lib.t6g(sch_1):page94_i238@pure_quanta.q_cap(chips)',
 PATH='I238',
 DRAWING='@T6G_MB_LIB.T6G(SCH_1):PAGE93',
 BOM_COST='MEM',
 TOLERANCE='10%',
 MATERIAL='X6S',
 PHYS_PAGE='94',
 XY='(-2825,5900)',
 ROT='2',
 VER='1',
 PACK_TYPE='C0805',
 LOCATION='C162',
 CDS_LIB='pure_quanta',
 CDS_PART_NAME='Q_CAP_C0805-10UF,25V,10%,X6S,CH6104KEA00',
 VOLTAGE='25V',
 ROOM='',
 PART_NUMBER='CH6104KEA00',
 VALUE='10UF',
 PRIM_FILE='./archive_libs/logical/q_cap/chips/chips.prt';

PART_NAME
 C163 'Q_CAP_C0805-10UF,25V,10%,X6S,CH6104KEA00':
 ROOM='';

SECTION_NUMBER 1
 '@T6G_MB_LIB.T6G(SCH_1):PAGE93_I239@PURE_QUANTA.Q_CAP(CHIPS)':
 C_PATH='@t6g_mb_lib.t6g(sch_1):page93_i239@pure_quanta.q_cap(chips)',
 P_PATH='@t6g_mb_lib.t6g(sch_1):page94_i239@pure_quanta.q_cap(chips)',
 PATH='I239',
 DRAWING='@T6G_MB_LIB.T6G(SCH_1):PAGE93',
 BOM_COST='MEM',
 TOLERANCE='10%',
 MATERIAL='X6S',
 PHYS_PAGE='94',
 XY='(-2250,5900)',
 ROT='2',
 VER='1',
 PACK_TYPE='C0805',
 LOCATION='C163',
 CDS_LIB='pure_quanta',
 CDS_PART_NAME='Q_CAP_C0805-10UF,25V,10%,X6S,CH6104KEA00',
 VOLTAGE='25V',
 ROOM='',
 PART_NUMBER='CH6104KEA00',
 VALUE='10UF',
 PRIM_FILE='./archive_libs/logical/q_cap/chips/chips.prt';

PART_NAME
 C164 'Q_CAP_0402-0.1UF,25V,10%,X7R,CH4104K1B00':
 ROOM='';

SECTION_NUMBER 1
 '@T6G_MB_LIB.T6G(SCH_1):PAGE104_I185@PURE_QUANTA.Q_CAP(CHIPS)':
 C_PATH='@t6g_mb_lib.t6g(sch_1):page104_i185@pure_quanta.q_cap(chips)',
 P_PATH='@t6g_mb_lib.t6g(sch_1):page105_i185@pure_quanta.q_cap(chips)',
 PATH='I185',
 DRAWING='@T6G_MB_LIB.T6G(SCH_1):PAGE104',
 BOM_COST='MEM',
 TOLERANCE='10%',
 MATERIAL='X7R',
 PHYS_PAGE='105',
 XY='(-8575,3225)',
 ROT='2',
 VER='1',
 PACK_TYPE='0402',
 LOCATION='C164',
 CDS_LIB='pure_quanta',
 CDS_PART_NAME='Q_CAP_0402-0.1UF,25V,10%,X7R,CH4104K1B00',
 VOLTAGE='25V',
 ROOM='',
 PART_NUMBER='CH4104K1B00',
 VALUE='0.1UF',
 PRIM_FILE='./archive_libs/logical/q_cap/chips/chips.prt';

PART_NAME
 C165 'Q_CAP_C0805-10UF,25V,10%,X6S,CH6104KEA00':
 ROOM='';

SECTION_NUMBER 1
 '@T6G_MB_LIB.T6G(SCH_1):PAGE94_I238@PURE_QUANTA.Q_CAP(CHIPS)':
 C_PATH='@t6g_mb_lib.t6g(sch_1):page94_i238@pure_quanta.q_cap(chips)',
 P_PATH='@t6g_mb_lib.t6g(sch_1):page95_i238@pure_quanta.q_cap(chips)',
 PATH='I238',
 DRAWING='@T6G_MB_LIB.T6G(SCH_1):PAGE94',
 BOM_COST='MEM',
 TOLERANCE='10%',
 MATERIAL='X6S',
 PHYS_PAGE='95',
 XY='(-2750,5825)',
 ROT='2',
 VER='1',
 PACK_TYPE='C0805',
 LOCATION='C165',
 CDS_LIB='pure_quanta',
 CDS_PART_NAME='Q_CAP_C0805-10UF,25V,10%,X6S,CH6104KEA00',
 VOLTAGE='25V',
 ROOM='',
 PART_NUMBER='CH6104KEA00',
 VALUE='10UF',
 PRIM_FILE='./archive_libs/logical/q_cap/chips/chips.prt';

PART_NAME
 C166 'Q_CAP_C0805-10UF,25V,10%,X6S,CH6104KEA00':
 ROOM='';

SECTION_NUMBER 1
 '@T6G_MB_LIB.T6G(SCH_1):PAGE94_I239@PURE_QUANTA.Q_CAP(CHIPS)':
 C_PATH='@t6g_mb_lib.t6g(sch_1):page94_i239@pure_quanta.q_cap(chips)',
 P_PATH='@t6g_mb_lib.t6g(sch_1):page95_i239@pure_quanta.q_cap(chips)',
 PATH='I239',
 DRAWING='@T6G_MB_LIB.T6G(SCH_1):PAGE94',
 BOM_COST='MEM',
 TOLERANCE='10%',
 MATERIAL='X6S',
 PHYS_PAGE='95',
 XY='(-2175,5825)',
 ROT='2',
 VER='1',
 PACK_TYPE='C0805',
 LOCATION='C166',
 CDS_LIB='pure_quanta',
 CDS_PART_NAME='Q_CAP_C0805-10UF,25V,10%,X6S,CH6104KEA00',
 VOLTAGE='25V',
 ROOM='',
 PART_NUMBER='CH6104KEA00',
 VALUE='10UF',
 PRIM_FILE='./archive_libs/logical/q_cap/chips/chips.prt';

PART_NAME
 C167 'Q_CAP_C0805-10UF,25V,10%,X6S,CH6104KEA00':
 ROOM='';

SECTION_NUMBER 1
 '@T6G_MB_LIB.T6G(SCH_1):PAGE95_I238@PURE_QUANTA.Q_CAP(CHIPS)':
 C_PATH='@t6g_mb_lib.t6g(sch_1):page95_i238@pure_quanta.q_cap(chips)',
 P_PATH='@t6g_mb_lib.t6g(sch_1):page96_i238@pure_quanta.q_cap(chips)',
 PATH='I238',
 DRAWING='@T6G_MB_LIB.T6G(SCH_1):PAGE95',
 BOM_COST='MEM',
 TOLERANCE='10%',
 MATERIAL='X6S',
 PHYS_PAGE='96',
 XY='(-2825,6000)',
 ROT='2',
 VER='1',
 PACK_TYPE='C0805',
 LOCATION='C167',
 CDS_LIB='pure_quanta',
 CDS_PART_NAME='Q_CAP_C0805-10UF,25V,10%,X6S,CH6104KEA00',
 VOLTAGE='25V',
 ROOM='',
 PART_NUMBER='CH6104KEA00',
 VALUE='10UF',
 PRIM_FILE='./archive_libs/logical/q_cap/chips/chips.prt';

PART_NAME
 C168 'Q_CAP_0402-0.1UF,25V,10%,X7R,CH4104K1B00':
 ROOM='';

SECTION_NUMBER 1
 '@T6G_MB_LIB.T6G(SCH_1):PAGE105_I185@PURE_QUANTA.Q_CAP(CHIPS)':
 C_PATH='@t6g_mb_lib.t6g(sch_1):page105_i185@pure_quanta.q_cap(chips)',
 P_PATH='@t6g_mb_lib.t6g(sch_1):page106_i185@pure_quanta.q_cap(chips)',
 PATH='I185',
 DRAWING='@T6G_MB_LIB.T6G(SCH_1):PAGE105',
 BOM_COST='MEM',
 TOLERANCE='10%',
 MATERIAL='X7R',
 PHYS_PAGE='106',
 XY='(-8550,3175)',
 ROT='2',
 VER='1',
 PACK_TYPE='0402',
 LOCATION='C168',
 CDS_LIB='pure_quanta',
 CDS_PART_NAME='Q_CAP_0402-0.1UF,25V,10%,X7R,CH4104K1B00',
 VOLTAGE='25V',
 ROOM='',
 PART_NUMBER='CH4104K1B00',
 VALUE='0.1UF',
 PRIM_FILE='./archive_libs/logical/q_cap/chips/chips.prt';

PART_NAME
 C169 'Q_CAP_C0805-10UF,25V,10%,X6S,CH6104KEA00':
 ROOM='';

SECTION_NUMBER 1
 '@T6G_MB_LIB.T6G(SCH_1):PAGE95_I239@PURE_QUANTA.Q_CAP(CHIPS)':
 C_PATH='@t6g_mb_lib.t6g(sch_1):page95_i239@pure_quanta.q_cap(chips)',
 P_PATH='@t6g_mb_lib.t6g(sch_1):page96_i239@pure_quanta.q_cap(chips)',
 PATH='I239',
 DRAWING='@T6G_MB_LIB.T6G(SCH_1):PAGE95',
 BOM_COST='MEM',
 TOLERANCE='10%',
 MATERIAL='X6S',
 PHYS_PAGE='96',
 XY='(-2250,6000)',
 ROT='2',
 VER='1',
 PACK_TYPE='C0805',
 LOCATION='C169',
 CDS_LIB='pure_quanta',
 CDS_PART_NAME='Q_CAP_C0805-10UF,25V,10%,X6S,CH6104KEA00',
 VOLTAGE='25V',
 ROOM='',
 PART_NUMBER='CH6104KEA00',
 VALUE='10UF',
 PRIM_FILE='./archive_libs/logical/q_cap/chips/chips.prt';

PART_NAME
 C170 'Q_CAP_C0805-10UF,25V,10%,X6S,CH6104KEA00':
 ROOM='';

SECTION_NUMBER 1
 '@T6G_MB_LIB.T6G(SCH_1):PAGE96_I238@PURE_QUANTA.Q_CAP(CHIPS)':
 C_PATH='@t6g_mb_lib.t6g(sch_1):page96_i238@pure_quanta.q_cap(chips)',
 P_PATH='@t6g_mb_lib.t6g(sch_1):page97_i238@pure_quanta.q_cap(chips)',
 PATH='I238',
 DRAWING='@T6G_MB_LIB.T6G(SCH_1):PAGE96',
 BOM_COST='MEM',
 TOLERANCE='10%',
 MATERIAL='X6S',
 PHYS_PAGE='97',
 XY='(-2900,5600)',
 ROT='2',
 VER='1',
 PACK_TYPE='C0805',
 LOCATION='C170',
 CDS_LIB='pure_quanta',
 CDS_PART_NAME='Q_CAP_C0805-10UF,25V,10%,X6S,CH6104KEA00',
 VOLTAGE='25V',
 ROOM='',
 PART_NUMBER='CH6104KEA00',
 VALUE='10UF',
 PRIM_FILE='./archive_libs/logical/q_cap/chips/chips.prt';

PART_NAME
 C171 'Q_CAP_C0805-10UF,25V,10%,X6S,CH6104KEA00':
 ROOM='';

SECTION_NUMBER 1
 '@T6G_MB_LIB.T6G(SCH_1):PAGE96_I239@PURE_QUANTA.Q_CAP(CHIPS)':
 C_PATH='@t6g_mb_lib.t6g(sch_1):page96_i239@pure_quanta.q_cap(chips)',
 P_PATH='@t6g_mb_lib.t6g(sch_1):page97_i239@pure_quanta.q_cap(chips)',
 PATH='I239',
 DRAWING='@T6G_MB_LIB.T6G(SCH_1):PAGE96',
 BOM_COST='MEM',
 TOLERANCE='10%',
 MATERIAL='X6S',
 PHYS_PAGE='97',
 XY='(-2325,5600)',
 ROT='2',
 VER='1',
 PACK_TYPE='C0805',
 LOCATION='C171',
 CDS_LIB='pure_quanta',
 CDS_PART_NAME='Q_CAP_C0805-10UF,25V,10%,X6S,CH6104KEA00',
 VOLTAGE='25V',
 ROOM='',
 PART_NUMBER='CH6104KEA00',
 VALUE='10UF',
 PRIM_FILE='./archive_libs/logical/q_cap/chips/chips.prt';

PART_NAME
 C172 'Q_CAP_0402-0.1UF,25V,10%,X7R,CH4104K1B00':
 ROOM='';

SECTION_NUMBER 1
 '@T6G_MB_LIB.T6G(SCH_1):PAGE106_I185@PURE_QUANTA.Q_CAP(CHIPS)':
 C_PATH='@t6g_mb_lib.t6g(sch_1):page106_i185@pure_quanta.q_cap(chips)',
 P_PATH='@t6g_mb_lib.t6g(sch_1):page107_i185@pure_quanta.q_cap(chips)',
 PATH='I185',
 DRAWING='@T6G_MB_LIB.T6G(SCH_1):PAGE106',
 BOM_COST='MEM',
 TOLERANCE='10%',
 MATERIAL='X7R',
 PHYS_PAGE='107',
 XY='(-8525,3150)',
 ROT='2',
 VER='1',
 PACK_TYPE='0402',
 LOCATION='C172',
 CDS_LIB='pure_quanta',
 CDS_PART_NAME='Q_CAP_0402-0.1UF,25V,10%,X7R,CH4104K1B00',
 VOLTAGE='25V',
 ROOM='',
 PART_NUMBER='CH4104K1B00',
 VALUE='0.1UF',
 PRIM_FILE='./archive_libs/logical/q_cap/chips/chips.prt';

PART_NAME
 C173 'Q_CAP_C0805-10UF,25V,10%,X6S,CH6104KEA00':
 ROOM='';

SECTION_NUMBER 1
 '@T6G_MB_LIB.T6G(SCH_1):PAGE97_I240@PURE_QUANTA.Q_CAP(CHIPS)':
 C_PATH='@t6g_mb_lib.t6g(sch_1):page97_i240@pure_quanta.q_cap(chips)',
 P_PATH='@t6g_mb_lib.t6g(sch_1):page98_i240@pure_quanta.q_cap(chips)',
 PATH='I240',
 DRAWING='@T6G_MB_LIB.T6G(SCH_1):PAGE97',
 BOM_COST='MEM',
 TOLERANCE='10%',
 MATERIAL='X6S',
 PHYS_PAGE='98',
 XY='(-2800,6100)',
 ROT='2',
 VER='1',
 PACK_TYPE='C0805',
 LOCATION='C173',
 CDS_LIB='pure_quanta',
 CDS_PART_NAME='Q_CAP_C0805-10UF,25V,10%,X6S,CH6104KEA00',
 VOLTAGE='25V',
 ROOM='',
 PART_NUMBER='CH6104KEA00',
 VALUE='10UF',
 PRIM_FILE='./archive_libs/logical/q_cap/chips/chips.prt';

PART_NAME
 C174 'Q_CAP_C0805-10UF,25V,10%,X6S,CH6104KEA00':
 ROOM='';

SECTION_NUMBER 1
 '@T6G_MB_LIB.T6G(SCH_1):PAGE97_I241@PURE_QUANTA.Q_CAP(CHIPS)':
 C_PATH='@t6g_mb_lib.t6g(sch_1):page97_i241@pure_quanta.q_cap(chips)',
 P_PATH='@t6g_mb_lib.t6g(sch_1):page98_i241@pure_quanta.q_cap(chips)',
 PATH='I241',
 DRAWING='@T6G_MB_LIB.T6G(SCH_1):PAGE97',
 BOM_COST='MEM',
 TOLERANCE='10%',
 MATERIAL='X6S',
 PHYS_PAGE='98',
 XY='(-2225,6100)',
 ROT='2',
 VER='1',
 PACK_TYPE='C0805',
 LOCATION='C174',
 CDS_LIB='pure_quanta',
 CDS_PART_NAME='Q_CAP_C0805-10UF,25V,10%,X6S,CH6104KEA00',
 VOLTAGE='25V',
 ROOM='',
 PART_NUMBER='CH6104KEA00',
 VALUE='10UF',
 PRIM_FILE='./archive_libs/logical/q_cap/chips/chips.prt';

PART_NAME
 C175 'Q_CAP_C0805-10UF,25V,10%,X6S,CH6104KEA00':
 ROOM='';

SECTION_NUMBER 1
 '@T6G_MB_LIB.T6G(SCH_1):PAGE98_I238@PURE_QUANTA.Q_CAP(CHIPS)':
 C_PATH='@t6g_mb_lib.t6g(sch_1):page98_i238@pure_quanta.q_cap(chips)',
 P_PATH='@t6g_mb_lib.t6g(sch_1):page99_i238@pure_quanta.q_cap(chips)',
 PATH='I238',
 DRAWING='@T6G_MB_LIB.T6G(SCH_1):PAGE98',
 BOM_COST='MEM',
 TOLERANCE='10%',
 MATERIAL='X6S',
 PHYS_PAGE='99',
 XY='(-2875,5525)',
 ROT='2',
 VER='1',
 PACK_TYPE='C0805',
 LOCATION='C175',
 CDS_LIB='pure_quanta',
 CDS_PART_NAME='Q_CAP_C0805-10UF,25V,10%,X6S,CH6104KEA00',
 VOLTAGE='25V',
 ROOM='',
 PART_NUMBER='CH6104KEA00',
 VALUE='10UF',
 PRIM_FILE='./archive_libs/logical/q_cap/chips/chips.prt';

PART_NAME
 C176 'Q_CAP_0402-0.1UF,25V,10%,X7R,CH4104K1B00':
 ROOM='';

SECTION_NUMBER 1
 '@T6G_MB_LIB.T6G(SCH_1):PAGE107_I185@PURE_QUANTA.Q_CAP(CHIPS)':
 C_PATH='@t6g_mb_lib.t6g(sch_1):page107_i185@pure_quanta.q_cap(chips)',
 P_PATH='@t6g_mb_lib.t6g(sch_1):page108_i185@pure_quanta.q_cap(chips)',
 PATH='I185',
 DRAWING='@T6G_MB_LIB.T6G(SCH_1):PAGE107',
 BOM_COST='MEM',
 TOLERANCE='10%',
 MATERIAL='X7R',
 PHYS_PAGE='108',
 XY='(-8675,3150)',
 ROT='2',
 VER='1',
 PACK_TYPE='0402',
 LOCATION='C176',
 CDS_LIB='pure_quanta',
 CDS_PART_NAME='Q_CAP_0402-0.1UF,25V,10%,X7R,CH4104K1B00',
 VOLTAGE='25V',
 ROOM='',
 PART_NUMBER='CH4104K1B00',
 VALUE='0.1UF',
 PRIM_FILE='./archive_libs/logical/q_cap/chips/chips.prt';

PART_NAME
 C177 'Q_CAP_C0805-10UF,25V,10%,X6S,CH6104KEA00':
 ROOM='';

SECTION_NUMBER 1
 '@T6G_MB_LIB.T6G(SCH_1):PAGE98_I239@PURE_QUANTA.Q_CAP(CHIPS)':
 C_PATH='@t6g_mb_lib.t6g(sch_1):page98_i239@pure_quanta.q_cap(chips)',
 P_PATH='@t6g_mb_lib.t6g(sch_1):page99_i239@pure_quanta.q_cap(chips)',
 PATH='I239',
 DRAWING='@T6G_MB_LIB.T6G(SCH_1):PAGE98',
 BOM_COST='MEM',
 TOLERANCE='10%',
 MATERIAL='X6S',
 PHYS_PAGE='99',
 XY='(-2300,5525)',
 ROT='2',
 VER='1',
 PACK_TYPE='C0805',
 LOCATION='C177',
 CDS_LIB='pure_quanta',
 CDS_PART_NAME='Q_CAP_C0805-10UF,25V,10%,X6S,CH6104KEA00',
 VOLTAGE='25V',
 ROOM='',
 PART_NUMBER='CH6104KEA00',
 VALUE='10UF',
 PRIM_FILE='./archive_libs/logical/q_cap/chips/chips.prt';

PART_NAME
 C178 'Q_CAP_C0805-10UF,25V,10%,X6S,CH6104KEA00':
 ROOM='';

SECTION_NUMBER 1
 '@T6G_MB_LIB.T6G(SCH_1):PAGE99_I238@PURE_QUANTA.Q_CAP(CHIPS)':
 C_PATH='@t6g_mb_lib.t6g(sch_1):page99_i238@pure_quanta.q_cap(chips)',
 P_PATH='@t6g_mb_lib.t6g(sch_1):page100_i238@pure_quanta.q_cap(chips)',
 PATH='I238',
 DRAWING='@T6G_MB_LIB.T6G(SCH_1):PAGE99',
 BOM_COST='MEM',
 TOLERANCE='10%',
 MATERIAL='X6S',
 PHYS_PAGE='100',
 XY='(-2925,5875)',
 ROT='2',
 VER='1',
 PACK_TYPE='C0805',
 LOCATION='C178',
 CDS_LIB='pure_quanta',
 CDS_PART_NAME='Q_CAP_C0805-10UF,25V,10%,X6S,CH6104KEA00',
 VOLTAGE='25V',
 ROOM='',
 PART_NUMBER='CH6104KEA00',
 VALUE='10UF',
 PRIM_FILE='./archive_libs/logical/q_cap/chips/chips.prt';

PART_NAME
 C179 'Q_CAP_C0805-10UF,25V,10%,X6S,CH6104KEA00':
 ROOM='';

SECTION_NUMBER 1
 '@T6G_MB_LIB.T6G(SCH_1):PAGE99_I239@PURE_QUANTA.Q_CAP(CHIPS)':
 C_PATH='@t6g_mb_lib.t6g(sch_1):page99_i239@pure_quanta.q_cap(chips)',
 P_PATH='@t6g_mb_lib.t6g(sch_1):page100_i239@pure_quanta.q_cap(chips)',
 PATH='I239',
 DRAWING='@T6G_MB_LIB.T6G(SCH_1):PAGE99',
 BOM_COST='MEM',
 TOLERANCE='10%',
 MATERIAL='X6S',
 PHYS_PAGE='100',
 XY='(-2350,5875)',
 ROT='2',
 VER='1',
 PACK_TYPE='C0805',
 LOCATION='C179',
 CDS_LIB='pure_quanta',
 CDS_PART_NAME='Q_CAP_C0805-10UF,25V,10%,X6S,CH6104KEA00',
 VOLTAGE='25V',
 ROOM='',
 PART_NUMBER='CH6104KEA00',
 VALUE='10UF',
 PRIM_FILE='./archive_libs/logical/q_cap/chips/chips.prt';

PART_NAME
 C180 'Q_CAP_0402-0.1UF,25V,10%,X7R,CH4104K1B00':
 ROOM='';

SECTION_NUMBER 1
 '@T6G_MB_LIB.T6G(SCH_1):PAGE108_I185@PURE_QUANTA.Q_CAP(CHIPS)':
 C_PATH='@t6g_mb_lib.t6g(sch_1):page108_i185@pure_quanta.q_cap(chips)',
 P_PATH='@t6g_mb_lib.t6g(sch_1):page109_i185@pure_quanta.q_cap(chips)',
 PATH='I185',
 DRAWING='@T6G_MB_LIB.T6G(SCH_1):PAGE108',
 BOM_COST='MEM',
 TOLERANCE='10%',
 MATERIAL='X7R',
 PHYS_PAGE='109',
 XY='(-8575,3225)',
 ROT='2',
 VER='1',
 PACK_TYPE='0402',
 LOCATION='C180',
 CDS_LIB='pure_quanta',
 CDS_PART_NAME='Q_CAP_0402-0.1UF,25V,10%,X7R,CH4104K1B00',
 VOLTAGE='25V',
 ROOM='',
 PART_NUMBER='CH4104K1B00',
 VALUE='0.1UF',
 PRIM_FILE='./archive_libs/logical/q_cap/chips/chips.prt';

PART_NAME
 C181 'Q_CAP_C0805-10UF,25V,10%,X6S,CH6104KEA00':
 ROOM='';

SECTION_NUMBER 1
 '@T6G_MB_LIB.T6G(SCH_1):PAGE100_I238@PURE_QUANTA.Q_CAP(CHIPS)':
 C_PATH='@t6g_mb_lib.t6g(sch_1):page100_i238@pure_quanta.q_cap(chips)',
 P_PATH='@t6g_mb_lib.t6g(sch_1):page101_i238@pure_quanta.q_cap(chips)',
 PATH='I238',
 DRAWING='@T6G_MB_LIB.T6G(SCH_1):PAGE100',
 BOM_COST='MEM',
 TOLERANCE='10%',
 MATERIAL='X6S',
 PHYS_PAGE='101',
 XY='(-2900,5800)',
 ROT='2',
 VER='1',
 PACK_TYPE='C0805',
 LOCATION='C181',
 CDS_LIB='pure_quanta',
 CDS_PART_NAME='Q_CAP_C0805-10UF,25V,10%,X6S,CH6104KEA00',
 VOLTAGE='25V',
 ROOM='',
 PART_NUMBER='CH6104KEA00',
 VALUE='10UF',
 PRIM_FILE='./archive_libs/logical/q_cap/chips/chips.prt';

PART_NAME
 C182 'Q_CAP_C0805-10UF,25V,10%,X6S,CH6104KEA00':
 ROOM='';

SECTION_NUMBER 1
 '@T6G_MB_LIB.T6G(SCH_1):PAGE100_I239@PURE_QUANTA.Q_CAP(CHIPS)':
 C_PATH='@t6g_mb_lib.t6g(sch_1):page100_i239@pure_quanta.q_cap(chips)',
 P_PATH='@t6g_mb_lib.t6g(sch_1):page101_i239@pure_quanta.q_cap(chips)',
 PATH='I239',
 DRAWING='@T6G_MB_LIB.T6G(SCH_1):PAGE100',
 BOM_COST='MEM',
 TOLERANCE='10%',
 MATERIAL='X6S',
 PHYS_PAGE='101',
 XY='(-2325,5800)',
 ROT='2',
 VER='1',
 PACK_TYPE='C0805',
 LOCATION='C182',
 CDS_LIB='pure_quanta',
 CDS_PART_NAME='Q_CAP_C0805-10UF,25V,10%,X6S,CH6104KEA00',
 VOLTAGE='25V',
 ROOM='',
 PART_NUMBER='CH6104KEA00',
 VALUE='10UF',
 PRIM_FILE='./archive_libs/logical/q_cap/chips/chips.prt';

PART_NAME
 C183 'Q_CAP_C0805-10UF,25V,10%,X6S,CH6104KEA00':
 ROOM='';

SECTION_NUMBER 1
 '@T6G_MB_LIB.T6G(SCH_1):PAGE101_I238@PURE_QUANTA.Q_CAP(CHIPS)':
 C_PATH='@t6g_mb_lib.t6g(sch_1):page101_i238@pure_quanta.q_cap(chips)',
 P_PATH='@t6g_mb_lib.t6g(sch_1):page102_i238@pure_quanta.q_cap(chips)',
 PATH='I238',
 DRAWING='@T6G_MB_LIB.T6G(SCH_1):PAGE101',
 BOM_COST='MEM',
 TOLERANCE='10%',
 MATERIAL='X6S',
 PHYS_PAGE='102',
 XY='(-2875,6175)',
 ROT='2',
 VER='1',
 PACK_TYPE='C0805',
 LOCATION='C183',
 CDS_LIB='pure_quanta',
 CDS_PART_NAME='Q_CAP_C0805-10UF,25V,10%,X6S,CH6104KEA00',
 VOLTAGE='25V',
 ROOM='',
 PART_NUMBER='CH6104KEA00',
 VALUE='10UF',
 PRIM_FILE='./archive_libs/logical/q_cap/chips/chips.prt';

PART_NAME
 C184 'Q_CAP_C0201-0.1UF,10V,10%,X7S,CH4102K6E00':;

SECTION_NUMBER 1
 '@T6G_MB_LIB.T6G(SCH_1):PAGE398_I85@PURE_QUANTA.Q_CAP(CHIPS)':
 C_PATH='@t6g_mb_lib.t6g(sch_1):page398_i85@pure_quanta.q_cap(chips)',
 P_PATH='@t6g_mb_lib.t6g(sch_1):page323_i85@pure_quanta.q_cap(chips)',
 PATH='I85',
 DRAWING='@T6G_MB_LIB.T6G(SCH_1):PAGE398',
 TOLERANCE='10%',
 MATERIAL='X7S',
 PHYS_PAGE='323',
 XY='(-2175,2525)',
 ROT='0',
 VER='1',
 PACK_TYPE='C0201',
 LOCATION='C184',
 CDS_LIB='pure_quanta',
 CDS_PART_NAME='Q_CAP_C0201-0.1UF,10V,10%,X7S,CH4102K6E00',
 VOLTAGE='10V',
 PART_NUMBER='CH4102K6E00',
 VALUE='0.1UF',
 PRIM_FILE='./archive_libs/logical/q_cap/chips/chips.prt';

PART_NAME
 C185 'Q_CAP_0201-1UF,4V,20%,X6S,CH-10KMEE00':;

SECTION_NUMBER 1
 '@T6G_MB_LIB.T6G(SCH_1):PAGE398_I40@PURE_QUANTA.Q_CAP(CHIPS)':
 C_PATH='@t6g_mb_lib.t6g(sch_1):page398_i40@pure_quanta.q_cap(chips)',
 P_PATH='@t6g_mb_lib.t6g(sch_1):page323_i40@pure_quanta.q_cap(chips)',
 PATH='I40',
 DRAWING='@T6G_MB_LIB.T6G(SCH_1):PAGE398',
 TOLERANCE='20%',
 MATERIAL='X6S',
 PHYS_PAGE='323',
 XY='(-2500,5725)',
 ROT='0',
 VER='1',
 PACK_TYPE='0201',
 LOCATION='C185',
 CDS_LIB='pure_quanta',
 CDS_PART_NAME='Q_CAP_0201-1UF,4V,20%,X6S,CH-10KMEE00',
 VOLTAGE='4V',
 PART_NUMBER='CH-10KMEE00',
 VALUE='1UF',
 PRIM_FILE='./archive_libs/logical/q_cap/chips/chips.prt';

PART_NAME
 C186 'Q_CAP_0201-1UF,4V,20%,X6S,CH-10KMEE00':;

SECTION_NUMBER 1
 '@T6G_MB_LIB.T6G(SCH_1):PAGE398_I58@PURE_QUANTA.Q_CAP(CHIPS)':
 C_PATH='@t6g_mb_lib.t6g(sch_1):page398_i58@pure_quanta.q_cap(chips)',
 P_PATH='@t6g_mb_lib.t6g(sch_1):page323_i58@pure_quanta.q_cap(chips)',
 PATH='I58',
 DRAWING='@T6G_MB_LIB.T6G(SCH_1):PAGE398',
 TOLERANCE='20%',
 MATERIAL='X6S',
 PHYS_PAGE='323',
 XY='(-2375,3850)',
 ROT='0',
 VER='1',
 PACK_TYPE='0201',
 LOCATION='C186',
 CDS_LIB='pure_quanta',
 CDS_PART_NAME='Q_CAP_0201-1UF,4V,20%,X6S,CH-10KMEE00',
 VOLTAGE='4V',
 PART_NUMBER='CH-10KMEE00',
 VALUE='1UF',
 PRIM_FILE='./archive_libs/logical/q_cap/chips/chips.prt';

PART_NAME
 C187 'Q_CAP_0201-1UF,4V,20%,X6S,CH-10KMEE00':;

SECTION_NUMBER 1
 '@T6G_MB_LIB.T6G(SCH_1):PAGE398_I99@PURE_QUANTA.Q_CAP(CHIPS)':
 C_PATH='@t6g_mb_lib.t6g(sch_1):page398_i99@pure_quanta.q_cap(chips)',
 P_PATH='@t6g_mb_lib.t6g(sch_1):page323_i99@pure_quanta.q_cap(chips)',
 PATH='I99',
 DRAWING='@T6G_MB_LIB.T6G(SCH_1):PAGE398',
 TOLERANCE='20%',
 MATERIAL='X6S',
 PHYS_PAGE='323',
 XY='(-3300,1425)',
 ROT='0',
 VER='1',
 PACK_TYPE='0201',
 LOCATION='C187',
 CDS_LIB='pure_quanta',
 CDS_PART_NAME='Q_CAP_0201-1UF,4V,20%,X6S,CH-10KMEE00',
 VOLTAGE='4V',
 PART_NUMBER='CH-10KMEE00',
 VALUE='1UF',
 PRIM_FILE='./archive_libs/logical/q_cap/chips/chips.prt';

PART_NAME
 C188 'Q_CAP_0201-1UF,4V,20%,X6S,CH-10KMEE00':;

SECTION_NUMBER 1
 '@T6G_MB_LIB.T6G(SCH_1):PAGE398_I55@PURE_QUANTA.Q_CAP(CHIPS)':
 C_PATH='@t6g_mb_lib.t6g(sch_1):page398_i55@pure_quanta.q_cap(chips)',
 P_PATH='@t6g_mb_lib.t6g(sch_1):page323_i55@pure_quanta.q_cap(chips)',
 PATH='I55',
 DRAWING='@T6G_MB_LIB.T6G(SCH_1):PAGE398',
 TOLERANCE='20%',
 MATERIAL='X6S',
 PHYS_PAGE='323',
 XY='(-2575,3200)',
 ROT='0',
 VER='1',
 PACK_TYPE='0201',
 LOCATION='C188',
 CDS_LIB='pure_quanta',
 CDS_PART_NAME='Q_CAP_0201-1UF,4V,20%,X6S,CH-10KMEE00',
 VOLTAGE='4V',
 PART_NUMBER='CH-10KMEE00',
 VALUE='1UF',
 PRIM_FILE='./archive_libs/logical/q_cap/chips/chips.prt';

PART_NAME
 C189 'Q_CAP_C0201-0.1UF,10V,10%,X7S,CH4102K6E00':;

SECTION_NUMBER 1
 '@T6G_MB_LIB.T6G(SCH_1):PAGE398_I75@PURE_QUANTA.Q_CAP(CHIPS)':
 C_PATH='@t6g_mb_lib.t6g(sch_1):page398_i75@pure_quanta.q_cap(chips)',
 P_PATH='@t6g_mb_lib.t6g(sch_1):page323_i75@pure_quanta.q_cap(chips)',
 PATH='I75',
 DRAWING='@T6G_MB_LIB.T6G(SCH_1):PAGE398',
 TOLERANCE='10%',
 MATERIAL='X7S',
 PHYS_PAGE='323',
 XY='(-1400,5700)',
 ROT='0',
 VER='1',
 PACK_TYPE='C0201',
 LOCATION='C189',
 CDS_LIB='pure_quanta',
 CDS_PART_NAME='Q_CAP_C0201-0.1UF,10V,10%,X7S,CH4102K6E00',
 VOLTAGE='10V',
 PART_NUMBER='CH4102K6E00',
 VALUE='0.1UF',
 PRIM_FILE='./archive_libs/logical/q_cap/chips/chips.prt';

PART_NAME
 C190 'Q_CAP_0201-1UF,4V,20%,X6S,CH-10KMEE00':;

SECTION_NUMBER 1
 '@T6G_MB_LIB.T6G(SCH_1):PAGE398_I62@PURE_QUANTA.Q_CAP(CHIPS)':
 C_PATH='@t6g_mb_lib.t6g(sch_1):page398_i62@pure_quanta.q_cap(chips)',
 P_PATH='@t6g_mb_lib.t6g(sch_1):page323_i62@pure_quanta.q_cap(chips)',
 PATH='I62',
 DRAWING='@T6G_MB_LIB.T6G(SCH_1):PAGE398',
 TOLERANCE='20%',
 MATERIAL='X6S',
 PHYS_PAGE='323',
 XY='(-1925,3850)',
 ROT='0',
 VER='1',
 PACK_TYPE='0201',
 LOCATION='C190',
 CDS_LIB='pure_quanta',
 CDS_PART_NAME='Q_CAP_0201-1UF,4V,20%,X6S,CH-10KMEE00',
 VOLTAGE='4V',
 PART_NUMBER='CH-10KMEE00',
 VALUE='1UF',
 PRIM_FILE='./archive_libs/logical/q_cap/chips/chips.prt';

PART_NAME
 C191 'Q_CAP_C0201-0.1UF,10V,10%,X7S,CH4102K6E00':;

SECTION_NUMBER 1
 '@T6G_MB_LIB.T6G(SCH_1):PAGE398_I93@PURE_QUANTA.Q_CAP(CHIPS)':
 C_PATH='@t6g_mb_lib.t6g(sch_1):page398_i93@pure_quanta.q_cap(chips)',
 P_PATH='@t6g_mb_lib.t6g(sch_1):page323_i93@pure_quanta.q_cap(chips)',
 PATH='I93',
 DRAWING='@T6G_MB_LIB.T6G(SCH_1):PAGE398',
 TOLERANCE='10%',
 MATERIAL='X7S',
 PHYS_PAGE='323',
 XY='(-3050,1425)',
 ROT='0',
 VER='1',
 PACK_TYPE='C0201',
 LOCATION='C191',
 CDS_LIB='pure_quanta',
 CDS_PART_NAME='Q_CAP_C0201-0.1UF,10V,10%,X7S,CH4102K6E00',
 VOLTAGE='10V',
 PART_NUMBER='CH4102K6E00',
 VALUE='0.1UF',
 PRIM_FILE='./archive_libs/logical/q_cap/chips/chips.prt';

PART_NAME
 C192 'Q_CAP_C0201-0.1UF,10V,10%,X7S,CH4102K6E00':;

SECTION_NUMBER 1
 '@T6G_MB_LIB.T6G(SCH_1):PAGE398_I83@PURE_QUANTA.Q_CAP(CHIPS)':
 C_PATH='@t6g_mb_lib.t6g(sch_1):page398_i83@pure_quanta.q_cap(chips)',
 P_PATH='@t6g_mb_lib.t6g(sch_1):page323_i83@pure_quanta.q_cap(chips)',
 PATH='I83',
 DRAWING='@T6G_MB_LIB.T6G(SCH_1):PAGE398',
 TOLERANCE='10%',
 MATERIAL='X7S',
 PHYS_PAGE='323',
 XY='(-1650,2525)',
 ROT='0',
 VER='1',
 PACK_TYPE='C0201',
 LOCATION='C192',
 CDS_LIB='pure_quanta',
 CDS_PART_NAME='Q_CAP_C0201-0.1UF,10V,10%,X7S,CH4102K6E00',
 VOLTAGE='10V',
 PART_NUMBER='CH4102K6E00',
 VALUE='0.1UF',
 PRIM_FILE='./archive_libs/logical/q_cap/chips/chips.prt';

PART_NAME
 C193 'Q_CAP_C0402-100NF,50V,10%,X7R,CH4106K1B01':;

SECTION_NUMBER 1
 '@T6G_MB_LIB.T6G(SCH_1):PAGE156_I108@PURE_QUANTA.Q_CAP(CHIPS)':
 C_PATH='@t6g_mb_lib.t6g(sch_1):page156_i108@pure_quanta.q_cap(chips)',
 P_PATH='@t6g_mb_lib.t6g(sch_1):page187_i108@pure_quanta.q_cap(chips)',
 PATH='I108',
 DRAWING='@T6G_MB_LIB.T6G(SCH_1):PAGE156',
 TOLERANCE='10%',
 MATERIAL='X7R',
 PHYS_PAGE='187',
 XY='(-5250,6800)',
 ROT='2',
 VER='1',
 PACK_TYPE='C0402',
 LOCATION='C193',
 CDS_LIB='pure_quanta',
 CDS_PART_NAME='Q_CAP_C0402-100NF,50V,10%,X7R,CH4106K1B01',
 VOLTAGE='50V',
 PART_NUMBER='CH4106K1B01',
 VALUE='100NF',
 PRIM_FILE='./archive_libs/logical/q_cap/chips/chips.prt';

PART_NAME
 C194 'Q_CAP_C0402-0.1UF,16V,10%,X7R,CH4103K1B08':;

SECTION_NUMBER 1
 '@T6G_MB_LIB.T6G(SCH_1):PAGE148_I299@PURE_QUANTA.Q_CAP(CHIPS)':
 C_PATH='@t6g_mb_lib.t6g(sch_1):page148_i299@pure_quanta.q_cap(chips)',
 P_PATH='@t6g_mb_lib.t6g(sch_1):page171_i299@pure_quanta.q_cap(chips)',
 PATH='I299',
 DRAWING='@T6G_MB_LIB.T6G(SCH_1):PAGE148',
 TOLERANCE='10%',
 MATERIAL='X7R',
 PHYS_PAGE='171',
 XY='(-5475,2625)',
 ROT='0',
 VER='1',
 PACK_TYPE='C0402',
 LOCATION='C194',
 CDS_LIB='pure_quanta',
 CDS_PART_NAME='Q_CAP_C0402-0.1UF,16V,10%,X7R,CH4103K1B08',
 VOLTAGE='16V',
 PART_NUMBER='CH4103K1B08',
 VALUE='0.1UF',
 PRIM_FILE='./archive_libs/logical/q_cap/chips/chips.prt';

PART_NAME
 C195 'Q_CAP_0402-4.7UF,6.3V,20%,X6S,CH5471MEB01':;

SECTION_NUMBER 1
 '@T6G_MB_LIB.T6G(SCH_1):PAGE443_I18@PURE_QUANTA.Q_CAP(CHIPS)':
 C_PATH='@t6g_mb_lib.t6g(sch_1):page443_i18@pure_quanta.q_cap(chips)',
 P_PATH='@t6g_mb_lib.t6g(sch_1):page334_i18@pure_quanta.q_cap(chips)',
 PATH='I18',
 DRAWING='@T6G_MB_LIB.T6G(SCH_1):PAGE443',
 TOLERANCE='20%',
 MATERIAL='X6S',
 PHYS_PAGE='334',
 XY='(-6600,4000)',
 ROT='0',
 VER='1',
 PACK_TYPE='0402',
 LOCATION='C195',
 CDS_LIB='pure_quanta',
 CDS_PART_NAME='Q_CAP_0402-4.7UF,6.3V,20%,X6S,CH5471MEB01',
 VOLTAGE='6.3V',
 PART_NUMBER='CH5471MEB01',
 VALUE='4.7UF',
 PRIM_FILE='./archive_libs/logical/q_cap/chips/chips.prt';

PART_NAME
 C196 'Q_CAP_0402-1000PF,50V,5%,EMPTY,TMP_QCH21006JB10':;

SECTION_NUMBER 1
 '@T6G_MB_LIB.T6G(SCH_1):PAGE182_I47@PURE_QUANTA.Q_CAP(CHIPS)':
 C_PATH='@t6g_mb_lib.t6g(sch_1):page182_i47@pure_quanta.q_cap(chips)',
 P_PATH='@t6g_mb_lib.t6g(sch_1):page207_i47@pure_quanta.q_cap(chips)',
 PATH='I47',
 DRAWING='@T6G_MB_LIB.T6G(SCH_1):PAGE182',
 TOLERANCE='5%',
 MATERIAL='EMPTY',
 PHYS_PAGE='207',
 XY='(-5350,6400)',
 ROT='0',
 VER='2',
 PACK_TYPE='0402',
 LOCATION='C196',
 CDS_LIB='pure_quanta',
 CDS_PART_NAME='Q_CAP_0402-1000PF,50V,5%,EMPTY,TMP_QCH21006JB10',
 VOLTAGE='50V',
 PART_NUMBER='TMP_QCH21006JB10',
 VALUE='1000PF',
 PRIM_FILE='./archive_libs/logical/q_cap/chips/chips.prt';

PART_NAME
 C197 'Q_CAP_0402-1000PF,50V,5%,X7R,TMP_QCH21006JB10':;

SECTION_NUMBER 1
 '@T6G_MB_LIB.T6G(SCH_1):PAGE182_I45@PURE_QUANTA.Q_CAP(CHIPS)':
 C_PATH='@t6g_mb_lib.t6g(sch_1):page182_i45@pure_quanta.q_cap(chips)',
 P_PATH='@t6g_mb_lib.t6g(sch_1):page207_i45@pure_quanta.q_cap(chips)',
 PATH='I45',
 DRAWING='@T6G_MB_LIB.T6G(SCH_1):PAGE182',
 TOLERANCE='5%',
 MATERIAL='X7R',
 PHYS_PAGE='207',
 XY='(-5325,5850)',
 ROT='0',
 VER='2',
 PACK_TYPE='0402',
 LOCATION='C197',
 CDS_LIB='pure_quanta',
 CDS_PART_NAME='Q_CAP_0402-1000PF,50V,5%,X7R,TMP_QCH21006JB10',
 VOLTAGE='50V',
 PART_NUMBER='TMP_QCH21006JB10',
 VALUE='1000PF',
 PRIM_FILE='./archive_libs/logical/q_cap/chips/chips.prt';

PART_NAME
 C198 'Q_CAP_C0201-0.1UF,10V,10%,X7S,CH4102K6E00':;

SECTION_NUMBER 1
 '@T6G_MB_LIB.T6G(SCH_1):PAGE398_I92@PURE_QUANTA.Q_CAP(CHIPS)':
 C_PATH='@t6g_mb_lib.t6g(sch_1):page398_i92@pure_quanta.q_cap(chips)',
 P_PATH='@t6g_mb_lib.t6g(sch_1):page323_i92@pure_quanta.q_cap(chips)',
 PATH='I92',
 DRAWING='@T6G_MB_LIB.T6G(SCH_1):PAGE398',
 TOLERANCE='10%',
 MATERIAL='X7S',
 PHYS_PAGE='323',
 XY='(-2750,1425)',
 ROT='0',
 VER='1',
 PACK_TYPE='C0201',
 LOCATION='C198',
 CDS_LIB='pure_quanta',
 CDS_PART_NAME='Q_CAP_C0201-0.1UF,10V,10%,X7S,CH4102K6E00',
 VOLTAGE='10V',
 PART_NUMBER='CH4102K6E00',
 VALUE='0.1UF',
 PRIM_FILE='./archive_libs/logical/q_cap/chips/chips.prt';

PART_NAME
 C199 'Q_CAP_C0402-10UF,6.3V,20%,X6S,CH6101MEB01':;

SECTION_NUMBER 1
 '@T6G_MB_LIB.T6G(SCH_1):PAGE443_I17@PURE_QUANTA.Q_CAP(CHIPS)':
 C_PATH='@t6g_mb_lib.t6g(sch_1):page443_i17@pure_quanta.q_cap(chips)',
 P_PATH='@t6g_mb_lib.t6g(sch_1):page334_i17@pure_quanta.q_cap(chips)',
 PATH='I17',
 DRAWING='@T6G_MB_LIB.T6G(SCH_1):PAGE443',
 TOLERANCE='20%',
 MATERIAL='X6S',
 PHYS_PAGE='334',
 XY='(-6800,4000)',
 ROT='0',
 VER='1',
 PACK_TYPE='C0402',
 LOCATION='C199',
 CDS_LIB='pure_quanta',
 CDS_PART_NAME='Q_CAP_C0402-10UF,6.3V,20%,X6S,CH6101MEB01',
 VOLTAGE='6.3V',
 PART_NUMBER='CH6101MEB01',
 VALUE='10UF',
 PRIM_FILE='./archive_libs/logical/q_cap/chips/chips.prt';

PART_NAME
 C200 'Q_CAP_0402-4.7UF,6.3V,20%,X6S,CH5471MEB01':;

SECTION_NUMBER 1
 '@T6G_MB_LIB.T6G(SCH_1):PAGE443_I26@PURE_QUANTA.Q_CAP(CHIPS)':
 C_PATH='@t6g_mb_lib.t6g(sch_1):page443_i26@pure_quanta.q_cap(chips)',
 P_PATH='@t6g_mb_lib.t6g(sch_1):page334_i26@pure_quanta.q_cap(chips)',
 PATH='I26',
 DRAWING='@T6G_MB_LIB.T6G(SCH_1):PAGE443',
 TOLERANCE='20%',
 MATERIAL='X6S',
 PHYS_PAGE='334',
 XY='(-6325,4800)',
 ROT='0',
 VER='1',
 PACK_TYPE='0402',
 LOCATION='C200',
 CDS_LIB='pure_quanta',
 CDS_PART_NAME='Q_CAP_0402-4.7UF,6.3V,20%,X6S,CH5471MEB01',
 VOLTAGE='6.3V',
 PART_NUMBER='CH5471MEB01',
 VALUE='4.7UF',
 PRIM_FILE='./archive_libs/logical/q_cap/chips/chips.prt';

PART_NAME
 C201 'Q_CAP_0201-1UF,4V,20%,X6S,CH-10KMEE00':;

SECTION_NUMBER 1
 '@T6G_MB_LIB.T6G(SCH_1):PAGE398_I100@PURE_QUANTA.Q_CAP(CHIPS)':
 C_PATH='@t6g_mb_lib.t6g(sch_1):page398_i100@pure_quanta.q_cap(chips)',
 P_PATH='@t6g_mb_lib.t6g(sch_1):page323_i100@pure_quanta.q_cap(chips)',
 PATH='I100',
 DRAWING='@T6G_MB_LIB.T6G(SCH_1):PAGE398',
 TOLERANCE='20%',
 MATERIAL='X6S',
 PHYS_PAGE='323',
 XY='(-2500,1425)',
 ROT='0',
 VER='1',
 PACK_TYPE='0201',
 LOCATION='C201',
 CDS_LIB='pure_quanta',
 CDS_PART_NAME='Q_CAP_0201-1UF,4V,20%,X6S,CH-10KMEE00',
 VOLTAGE='4V',
 PART_NUMBER='CH-10KMEE00',
 VALUE='1UF',
 PRIM_FILE='./archive_libs/logical/q_cap/chips/chips.prt';

PART_NAME
 C202 'Q_CAP_0201-1UF,4V,20%,X6S,CH-10KMEE00':;

SECTION_NUMBER 1
 '@T6G_MB_LIB.T6G(SCH_1):PAGE443_I20@PURE_QUANTA.Q_CAP(CHIPS)':
 C_PATH='@t6g_mb_lib.t6g(sch_1):page443_i20@pure_quanta.q_cap(chips)',
 P_PATH='@t6g_mb_lib.t6g(sch_1):page334_i20@pure_quanta.q_cap(chips)',
 PATH='I20',
 DRAWING='@T6G_MB_LIB.T6G(SCH_1):PAGE443',
 TOLERANCE='20%',
 MATERIAL='X6S',
 PHYS_PAGE='334',
 XY='(-6375,4000)',
 ROT='0',
 VER='1',
 PACK_TYPE='0201',
 LOCATION='C202',
 CDS_LIB='pure_quanta',
 CDS_PART_NAME='Q_CAP_0201-1UF,4V,20%,X6S,CH-10KMEE00',
 VOLTAGE='4V',
 PART_NUMBER='CH-10KMEE00',
 VALUE='1UF',
 PRIM_FILE='./archive_libs/logical/q_cap/chips/chips.prt';

PART_NAME
 C203 'Q_CAP_0201-1UF,4V,20%,X6S,CH-10KMEE00':;

SECTION_NUMBER 1
 '@T6G_MB_LIB.T6G(SCH_1):PAGE443_I8@PURE_QUANTA.Q_CAP(CHIPS)':
 C_PATH='@t6g_mb_lib.t6g(sch_1):page443_i8@pure_quanta.q_cap(chips)',
 P_PATH='@t6g_mb_lib.t6g(sch_1):page334_i8@pure_quanta.q_cap(chips)',
 PATH='I8',
 DRAWING='@T6G_MB_LIB.T6G(SCH_1):PAGE443',
 TOLERANCE='20%',
 MATERIAL='X6S',
 PHYS_PAGE='334',
 XY='(-6800,2925)',
 ROT='0',
 VER='1',
 PACK_TYPE='0201',
 LOCATION='C203',
 CDS_LIB='pure_quanta',
 CDS_PART_NAME='Q_CAP_0201-1UF,4V,20%,X6S,CH-10KMEE00',
 VOLTAGE='4V',
 PART_NUMBER='CH-10KMEE00',
 VALUE='1UF',
 PRIM_FILE='./archive_libs/logical/q_cap/chips/chips.prt';

PART_NAME
 C204 'Q_CAP_0201-1UF,4V,20%,X6S,CH-10KMEE00':;

SECTION_NUMBER 1
 '@T6G_MB_LIB.T6G(SCH_1):PAGE443_I22@PURE_QUANTA.Q_CAP(CHIPS)':
 C_PATH='@t6g_mb_lib.t6g(sch_1):page443_i22@pure_quanta.q_cap(chips)',
 P_PATH='@t6g_mb_lib.t6g(sch_1):page334_i22@pure_quanta.q_cap(chips)',
 PATH='I22',
 DRAWING='@T6G_MB_LIB.T6G(SCH_1):PAGE443',
 TOLERANCE='20%',
 MATERIAL='X6S',
 PHYS_PAGE='334',
 XY='(-6175,4000)',
 ROT='0',
 VER='1',
 PACK_TYPE='0201',
 LOCATION='C204',
 CDS_LIB='pure_quanta',
 CDS_PART_NAME='Q_CAP_0201-1UF,4V,20%,X6S,CH-10KMEE00',
 VOLTAGE='4V',
 PART_NUMBER='CH-10KMEE00',
 VALUE='1UF',
 PRIM_FILE='./archive_libs/logical/q_cap/chips/chips.prt';

PART_NAME
 C205 'Q_CAP_C0201-0.1UF,10V,10%,X7S,CH4102K6E00':;

SECTION_NUMBER 1
 '@T6G_MB_LIB.T6G(SCH_1):PAGE443_I23@PURE_QUANTA.Q_CAP(CHIPS)':
 C_PATH='@t6g_mb_lib.t6g(sch_1):page443_i23@pure_quanta.q_cap(chips)',
 P_PATH='@t6g_mb_lib.t6g(sch_1):page334_i23@pure_quanta.q_cap(chips)',
 PATH='I23',
 DRAWING='@T6G_MB_LIB.T6G(SCH_1):PAGE443',
 TOLERANCE='10%',
 MATERIAL='X7S',
 PHYS_PAGE='334',
 XY='(-5950,4000)',
 ROT='0',
 VER='1',
 PACK_TYPE='C0201',
 LOCATION='C205',
 CDS_LIB='pure_quanta',
 CDS_PART_NAME='Q_CAP_C0201-0.1UF,10V,10%,X7S,CH4102K6E00',
 VOLTAGE='10V',
 PART_NUMBER='CH4102K6E00',
 VALUE='0.1UF',
 PRIM_FILE='./archive_libs/logical/q_cap/chips/chips.prt';

PART_NAME
 C206 'Q_CAP_C0201-0.1UF,10V,10%,X7S,CH4102K6E00':;

SECTION_NUMBER 1
 '@T6G_MB_LIB.T6G(SCH_1):PAGE443_I9@PURE_QUANTA.Q_CAP(CHIPS)':
 C_PATH='@t6g_mb_lib.t6g(sch_1):page443_i9@pure_quanta.q_cap(chips)',
 P_PATH='@t6g_mb_lib.t6g(sch_1):page334_i9@pure_quanta.q_cap(chips)',
 PATH='I9',
 DRAWING='@T6G_MB_LIB.T6G(SCH_1):PAGE443',
 TOLERANCE='10%',
 MATERIAL='X7S',
 PHYS_PAGE='334',
 XY='(-6525,2900)',
 ROT='0',
 VER='1',
 PACK_TYPE='C0201',
 LOCATION='C206',
 CDS_LIB='pure_quanta',
 CDS_PART_NAME='Q_CAP_C0201-0.1UF,10V,10%,X7S,CH4102K6E00',
 VOLTAGE='10V',
 PART_NUMBER='CH4102K6E00',
 VALUE='0.1UF',
 PRIM_FILE='./archive_libs/logical/q_cap/chips/chips.prt';

PART_NAME
 C207 'Q_CAP_C0402-0.001UF,50V,10%,EMPTY,CH30106KB19':;

SECTION_NUMBER 1
 '@T6G_MB_LIB.T6G(SCH_1):PAGE27_I307@PURE_QUANTA.Q_CAP(CHIPS)':
 C_PATH='@t6g_mb_lib.t6g(sch_1):page27_i307@pure_quanta.q_cap(chips)',
 P_PATH='@t6g_mb_lib.t6g(sch_1):page27_i307@pure_quanta.q_cap(chips)',
 PATH='I307',
 DRAWING='@T6G_MB_LIB.T6G(SCH_1):PAGE27',
 TOLERANCE='10%',
 MATERIAL='EMPTY',
 PHYS_PAGE='27',
 XY='(-8000,600)',
 ROT='0',
 VER='1',
 PACK_TYPE='C0402',
 LOCATION='C207',
 CDS_LIB='pure_quanta',
 CDS_PART_NAME='Q_CAP_C0402-0.001UF,50V,10%,EMPTY,CH30106KB19',
 VOLTAGE='50V',
 PART_NUMBER='CH30106KB19',
 VALUE='0.001UF',
 PRIM_FILE='./archive_libs/logical/q_cap/chips/chips.prt';

PART_NAME
 C208 'Q_CAP_C0402-0.001UF,50V,10%,EMPTY,CH30106KB19':;

SECTION_NUMBER 1
 '@T6G_MB_LIB.T6G(SCH_1):PAGE27_I306@PURE_QUANTA.Q_CAP(CHIPS)':
 C_PATH='@t6g_mb_lib.t6g(sch_1):page27_i306@pure_quanta.q_cap(chips)',
 P_PATH='@t6g_mb_lib.t6g(sch_1):page27_i306@pure_quanta.q_cap(chips)',
 PATH='I306',
 DRAWING='@T6G_MB_LIB.T6G(SCH_1):PAGE27',
 TOLERANCE='10%',
 MATERIAL='EMPTY',
 PHYS_PAGE='27',
 XY='(-7675,600)',
 ROT='0',
 VER='1',
 PACK_TYPE='C0402',
 LOCATION='C208',
 CDS_LIB='pure_quanta',
 CDS_PART_NAME='Q_CAP_C0402-0.001UF,50V,10%,EMPTY,CH30106KB19',
 VOLTAGE='50V',
 PART_NUMBER='CH30106KB19',
 VALUE='0.001UF',
 PRIM_FILE='./archive_libs/logical/q_cap/chips/chips.prt';

PART_NAME
 C209 'Q_CAP_C0402-0.001UF,50V,10%,EMPTY,CH30106KB19':;

SECTION_NUMBER 1
 '@T6G_MB_LIB.T6G(SCH_1):PAGE27_I303@PURE_QUANTA.Q_CAP(CHIPS)':
 C_PATH='@t6g_mb_lib.t6g(sch_1):page27_i303@pure_quanta.q_cap(chips)',
 P_PATH='@t6g_mb_lib.t6g(sch_1):page27_i303@pure_quanta.q_cap(chips)',
 PATH='I303',
 DRAWING='@T6G_MB_LIB.T6G(SCH_1):PAGE27',
 TOLERANCE='10%',
 MATERIAL='EMPTY',
 PHYS_PAGE='27',
 XY='(-7350,600)',
 ROT='0',
 VER='1',
 PACK_TYPE='C0402',
 LOCATION='C209',
 CDS_LIB='pure_quanta',
 CDS_PART_NAME='Q_CAP_C0402-0.001UF,50V,10%,EMPTY,CH30106KB19',
 VOLTAGE='50V',
 PART_NUMBER='CH30106KB19',
 VALUE='0.001UF',
 PRIM_FILE='./archive_libs/logical/q_cap/chips/chips.prt';

PART_NAME
 C210 'Q_CAP_C0402-0.001UF,50V,10%,EMPTY,CH30106KB19':;

SECTION_NUMBER 1
 '@T6G_MB_LIB.T6G(SCH_1):PAGE27_I302@PURE_QUANTA.Q_CAP(CHIPS)':
 C_PATH='@t6g_mb_lib.t6g(sch_1):page27_i302@pure_quanta.q_cap(chips)',
 P_PATH='@t6g_mb_lib.t6g(sch_1):page27_i302@pure_quanta.q_cap(chips)',
 PATH='I302',
 DRAWING='@T6G_MB_LIB.T6G(SCH_1):PAGE27',
 TOLERANCE='10%',
 MATERIAL='EMPTY',
 PHYS_PAGE='27',
 XY='(-7025,600)',
 ROT='0',
 VER='1',
 PACK_TYPE='C0402',
 LOCATION='C210',
 CDS_LIB='pure_quanta',
 CDS_PART_NAME='Q_CAP_C0402-0.001UF,50V,10%,EMPTY,CH30106KB19',
 VOLTAGE='50V',
 PART_NUMBER='CH30106KB19',
 VALUE='0.001UF',
 PRIM_FILE='./archive_libs/logical/q_cap/chips/chips.prt';

PART_NAME
 C211 'Q_CAP_C0402-0.001UF,50V,10%,EMPTY,CH30106KB19':;

SECTION_NUMBER 1
 '@T6G_MB_LIB.T6G(SCH_1):PAGE27_I297@PURE_QUANTA.Q_CAP(CHIPS)':
 C_PATH='@t6g_mb_lib.t6g(sch_1):page27_i297@pure_quanta.q_cap(chips)',
 P_PATH='@t6g_mb_lib.t6g(sch_1):page27_i297@pure_quanta.q_cap(chips)',
 PATH='I297',
 DRAWING='@T6G_MB_LIB.T6G(SCH_1):PAGE27',
 TOLERANCE='10%',
 MATERIAL='EMPTY',
 PHYS_PAGE='27',
 XY='(-6675,600)',
 ROT='0',
 VER='1',
 PACK_TYPE='C0402',
 LOCATION='C211',
 CDS_LIB='pure_quanta',
 CDS_PART_NAME='Q_CAP_C0402-0.001UF,50V,10%,EMPTY,CH30106KB19',
 VOLTAGE='50V',
 PART_NUMBER='CH30106KB19',
 VALUE='0.001UF',
 PRIM_FILE='./archive_libs/logical/q_cap/chips/chips.prt';

PART_NAME
 C212 'Q_CAP_C0402-0.001UF,50V,10%,EMPTY,CH30106KB19':;

SECTION_NUMBER 1
 '@T6G_MB_LIB.T6G(SCH_1):PAGE27_I295@PURE_QUANTA.Q_CAP(CHIPS)':
 C_PATH='@t6g_mb_lib.t6g(sch_1):page27_i295@pure_quanta.q_cap(chips)',
 P_PATH='@t6g_mb_lib.t6g(sch_1):page27_i295@pure_quanta.q_cap(chips)',
 PATH='I295',
 DRAWING='@T6G_MB_LIB.T6G(SCH_1):PAGE27',
 TOLERANCE='10%',
 MATERIAL='EMPTY',
 PHYS_PAGE='27',
 XY='(-6375,600)',
 ROT='0',
 VER='1',
 PACK_TYPE='C0402',
 LOCATION='C212',
 CDS_LIB='pure_quanta',
 CDS_PART_NAME='Q_CAP_C0402-0.001UF,50V,10%,EMPTY,CH30106KB19',
 VOLTAGE='50V',
 PART_NUMBER='CH30106KB19',
 VALUE='0.001UF',
 PRIM_FILE='./archive_libs/logical/q_cap/chips/chips.prt';

PART_NAME
 C213 'Q_CAP_C0402-3.9P,50V,0.1P,NPO,CH-3916TB01':;

SECTION_NUMBER 1
 '@T6G_MB_LIB.T6G(SCH_1):PAGE28_I232@PURE_QUANTA.Q_CAP(CHIPS)':
 C_PATH='@t6g_mb_lib.t6g(sch_1):page28_i232@pure_quanta.q_cap(chips)',
 P_PATH='@t6g_mb_lib.t6g(sch_1):page28_i232@pure_quanta.q_cap(chips)',
 PATH='I232',
 DRAWING='@T6G_MB_LIB.T6G(SCH_1):PAGE28',
 TOLERANCE='0.1P',
 MATERIAL='NPO',
 PHYS_PAGE='28',
 XY='(-6225,7900)',
 ROT='0',
 VER='1',
 PACK_TYPE='C0402',
 LOCATION='C213',
 CDS_LIB='pure_quanta',
 CDS_PART_NAME='Q_CAP_C0402-3.9P,50V,0.1P,NPO,CH-3916TB01',
 VOLTAGE='50V',
 PART_NUMBER='CH-3916TB01',
 VALUE='3.9P',
 PRIM_FILE='./archive_libs/logical/q_cap/chips/chips.prt';

PART_NAME
 C214 'Q_CAP_C0402-3.9P,50V,0.1P,NPO,CH-3916TB01':;

SECTION_NUMBER 1
 '@T6G_MB_LIB.T6G(SCH_1):PAGE28_I233@PURE_QUANTA.Q_CAP(CHIPS)':
 C_PATH='@t6g_mb_lib.t6g(sch_1):page28_i233@pure_quanta.q_cap(chips)',
 P_PATH='@t6g_mb_lib.t6g(sch_1):page28_i233@pure_quanta.q_cap(chips)',
 PATH='I233',
 DRAWING='@T6G_MB_LIB.T6G(SCH_1):PAGE28',
 TOLERANCE='0.1P',
 MATERIAL='NPO',
 PHYS_PAGE='28',
 XY='(-4950,7900)',
 ROT='0',
 VER='1',
 PACK_TYPE='C0402',
 LOCATION='C214',
 CDS_LIB='pure_quanta',
 CDS_PART_NAME='Q_CAP_C0402-3.9P,50V,0.1P,NPO,CH-3916TB01',
 VOLTAGE='50V',
 PART_NUMBER='CH-3916TB01',
 VALUE='3.9P',
 PRIM_FILE='./archive_libs/logical/q_cap/chips/chips.prt';

PART_NAME
 C215 'Q_CAP_C0402-8.2PF,50V,0.1P,NP0,CH-8216TB09':;

SECTION_NUMBER 1
 '@T6G_MB_LIB.T6G(SCH_1):PAGE28_I230@PURE_QUANTA.Q_CAP(CHIPS)':
 C_PATH='@t6g_mb_lib.t6g(sch_1):page28_i230@pure_quanta.q_cap(chips)',
 P_PATH='@t6g_mb_lib.t6g(sch_1):page28_i230@pure_quanta.q_cap(chips)',
 PATH='I230',
 DRAWING='@T6G_MB_LIB.T6G(SCH_1):PAGE28',
 TOLERANCE='0.1P',
 MATERIAL='NP0',
 PHYS_PAGE='28',
 XY='(-3900,8050)',
 ROT='0',
 VER='1',
 PACK_TYPE='C0402',
 LOCATION='C215',
 CDS_LIB='pure_quanta',
 CDS_PART_NAME='Q_CAP_C0402-8.2PF,50V,0.1P,NP0,CH-8216TB09',
 VOLTAGE='50V',
 PART_NUMBER='CH-8216TB09',
 VALUE='8.2PF',
 PRIM_FILE='./archive_libs/logical/q_cap/chips/chips.prt';

PART_NAME
 C216 'Q_CAP_C0402-8.2PF,50V,0.1P,NP0,CH-8216TB09':;

SECTION_NUMBER 1
 '@T6G_MB_LIB.T6G(SCH_1):PAGE28_I231@PURE_QUANTA.Q_CAP(CHIPS)':
 C_PATH='@t6g_mb_lib.t6g(sch_1):page28_i231@pure_quanta.q_cap(chips)',
 P_PATH='@t6g_mb_lib.t6g(sch_1):page28_i231@pure_quanta.q_cap(chips)',
 PATH='I231',
 DRAWING='@T6G_MB_LIB.T6G(SCH_1):PAGE28',
 TOLERANCE='0.1P',
 MATERIAL='NP0',
 PHYS_PAGE='28',
 XY='(-2800,8075)',
 ROT='0',
 VER='1',
 PACK_TYPE='C0402',
 LOCATION='C216',
 CDS_LIB='pure_quanta',
 CDS_PART_NAME='Q_CAP_C0402-8.2PF,50V,0.1P,NP0,CH-8216TB09',
 VOLTAGE='50V',
 PART_NUMBER='CH-8216TB09',
 VALUE='8.2PF',
 PRIM_FILE='./archive_libs/logical/q_cap/chips/chips.prt';

PART_NAME
 C217 'Q_CAP_C0201-0.1UF,10V,10%,X7S,CH4102K6E00':;

SECTION_NUMBER 1
 '@T6G_MB_LIB.T6G(SCH_1):PAGE443_I27@PURE_QUANTA.Q_CAP(CHIPS)':
 C_PATH='@t6g_mb_lib.t6g(sch_1):page443_i27@pure_quanta.q_cap(chips)',
 P_PATH='@t6g_mb_lib.t6g(sch_1):page334_i27@pure_quanta.q_cap(chips)',
 PATH='I27',
 DRAWING='@T6G_MB_LIB.T6G(SCH_1):PAGE443',
 TOLERANCE='10%',
 MATERIAL='X7S',
 PHYS_PAGE='334',
 XY='(-5700,4000)',
 ROT='0',
 VER='1',
 PACK_TYPE='C0201',
 LOCATION='C217',
 CDS_LIB='pure_quanta',
 CDS_PART_NAME='Q_CAP_C0201-0.1UF,10V,10%,X7S,CH4102K6E00',
 VOLTAGE='10V',
 PART_NUMBER='CH4102K6E00',
 VALUE='0.1UF',
 PRIM_FILE='./archive_libs/logical/q_cap/chips/chips.prt';

PART_NAME
 C218 'Q_CAP_0402-0.1UF,25V,10%,X7R,CH4104K1B00':;

SECTION_NUMBER 1
 '@T6G_MB_LIB.T6G(SCH_1):PAGE143_I24@PURE_QUANTA.Q_CAP(CHIPS)':
 C_PATH='@t6g_mb_lib.t6g(sch_1):page143_i24@pure_quanta.q_cap(chips)',
 P_PATH='@t6g_mb_lib.t6g(sch_1):page166_i24@pure_quanta.q_cap(chips)',
 PATH='I24',
 DRAWING='@T6G_MB_LIB.T6G(SCH_1):PAGE143',
 BOM_COST='OCP3.0 ',
 TOLERANCE='10%',
 MATERIAL='X7R',
 PHYS_PAGE='166',
 XY='(-7200,5450)',
 ROT='0',
 VER='1',
 PACK_TYPE='0402',
 LOCATION='C218',
 CDS_LIB='pure_quanta',
 CDS_PART_NAME='Q_CAP_0402-0.1UF,25V,10%,X7R,CH4104K1B00',
 VOLTAGE='25V',
 PART_NUMBER='CH4104K1B00',
 VALUE='0.1UF',
 PRIM_FILE='./archive_libs/logical/q_cap/chips/chips.prt';

PART_NAME
 C219 'Q_CAP_0402-0.1UF,25V,10%,X7R,CH4104K1B00':;

SECTION_NUMBER 1
 '@T6G_MB_LIB.T6G(SCH_1):PAGE143_I29@PURE_QUANTA.Q_CAP(CHIPS)':
 C_PATH='@t6g_mb_lib.t6g(sch_1):page143_i29@pure_quanta.q_cap(chips)',
 P_PATH='@t6g_mb_lib.t6g(sch_1):page166_i29@pure_quanta.q_cap(chips)',
 PATH='I29',
 DRAWING='@T6G_MB_LIB.T6G(SCH_1):PAGE143',
 BOM_COST='OCP3.0 ',
 TOLERANCE='10%',
 MATERIAL='X7R',
 PHYS_PAGE='166',
 XY='(-7350,3825)',
 ROT='0',
 VER='1',
 PACK_TYPE='0402',
 LOCATION='C219',
 CDS_LIB='pure_quanta',
 CDS_PART_NAME='Q_CAP_0402-0.1UF,25V,10%,X7R,CH4104K1B00',
 VOLTAGE='25V',
 PART_NUMBER='CH4104K1B00',
 VALUE='0.1UF',
 PRIM_FILE='./archive_libs/logical/q_cap/chips/chips.prt';

PART_NAME
 C220 'Q_CAP_C0805-100UF,4V,20%,X6S,CH710KMEA01':;

SECTION_NUMBER 1
 '@T6G_MB_LIB.T6G(SCH_1):PAGE398_I44@PURE_QUANTA.Q_CAP(CHIPS)':
 C_PATH='@t6g_mb_lib.t6g(sch_1):page398_i44@pure_quanta.q_cap(chips)',
 P_PATH='@t6g_mb_lib.t6g(sch_1):page323_i44@pure_quanta.q_cap(chips)',
 PATH='I44',
 DRAWING='@T6G_MB_LIB.T6G(SCH_1):PAGE398',
 TOLERANCE='20%',
 MATERIAL='X6S',
 PHYS_PAGE='323',
 XY='(-3750,4475)',
 ROT='0',
 VER='1',
 PACK_TYPE='C0805',
 LOCATION='C220',
 CDS_LIB='pure_quanta',
 CDS_PART_NAME='Q_CAP_C0805-100UF,4V,20%,X6S,CH710KMEA01',
 VOLTAGE='4V',
 PART_NUMBER='CH710KMEA01',
 VALUE='100UF',
 PRIM_FILE='./archive_libs/logical/q_cap/chips/chips.prt';

PART_NAME
 C221 'Q_CAP_0402-4.7UF,6.3V,20%,X6S,CH5471MEB01':;

SECTION_NUMBER 1
 '@T6G_MB_LIB.T6G(SCH_1):PAGE398_I50@PURE_QUANTA.Q_CAP(CHIPS)':
 C_PATH='@t6g_mb_lib.t6g(sch_1):page398_i50@pure_quanta.q_cap(chips)',
 P_PATH='@t6g_mb_lib.t6g(sch_1):page323_i50@pure_quanta.q_cap(chips)',
 PATH='I50',
 DRAWING='@T6G_MB_LIB.T6G(SCH_1):PAGE398',
 TOLERANCE='20%',
 MATERIAL='X6S',
 PHYS_PAGE='323',
 XY='(-3075,3850)',
 ROT='0',
 VER='1',
 PACK_TYPE='0402',
 LOCATION='C221',
 CDS_LIB='pure_quanta',
 CDS_PART_NAME='Q_CAP_0402-4.7UF,6.3V,20%,X6S,CH5471MEB01',
 VOLTAGE='6.3V',
 PART_NUMBER='CH5471MEB01',
 VALUE='4.7UF',
 PRIM_FILE='./archive_libs/logical/q_cap/chips/chips.prt';

PART_NAME
 C222 'Q_CAP_0201-1UF,4V,20%,X6S,CH-10KMEE00':;

SECTION_NUMBER 1
 '@T6G_MB_LIB.T6G(SCH_1):PAGE398_I42@PURE_QUANTA.Q_CAP(CHIPS)':
 C_PATH='@t6g_mb_lib.t6g(sch_1):page398_i42@pure_quanta.q_cap(chips)',
 P_PATH='@t6g_mb_lib.t6g(sch_1):page323_i42@pure_quanta.q_cap(chips)',
 PATH='I42',
 DRAWING='@T6G_MB_LIB.T6G(SCH_1):PAGE398',
 TOLERANCE='20%',
 MATERIAL='X6S',
 PHYS_PAGE='323',
 XY='(-3750,3225)',
 ROT='0',
 VER='1',
 PACK_TYPE='0201',
 LOCATION='C222',
 CDS_LIB='pure_quanta',
 CDS_PART_NAME='Q_CAP_0201-1UF,4V,20%,X6S,CH-10KMEE00',
 VOLTAGE='4V',
 PART_NUMBER='CH-10KMEE00',
 VALUE='1UF',
 PRIM_FILE='./archive_libs/logical/q_cap/chips/chips.prt';

PART_NAME
 C223 'Q_CAP_0402-0.1UF,25V,10%,X7R,CH4104K1B00':;

SECTION_NUMBER 1
 '@T6G_MB_LIB.T6G(SCH_1):PAGE77_I11@PURE_QUANTA.Q_CAP(CHIPS)':
 C_PATH='@t6g_mb_lib.t6g(sch_1):page77_i11@pure_quanta.q_cap(chips)',
 P_PATH='@t6g_mb_lib.t6g(sch_1):page78_i11@pure_quanta.q_cap(chips)',
 PATH='I11',
 DRAWING='@T6G_MB_LIB.T6G(SCH_1):PAGE77',
 TOLERANCE='10%',
 MATERIAL='X7R',
 PHYS_PAGE='78',
 XY='(-4125,4575)',
 ROT='0',
 VER='1',
 PACK_TYPE='0402',
 LOCATION='C223',
 CDS_LIB='pure_quanta',
 CDS_PART_NAME='Q_CAP_0402-0.1UF,25V,10%,X7R,CH4104K1B00',
 VOLTAGE='25V',
 PART_NUMBER='CH4104K1B00',
 VALUE='0.1UF',
 PRIM_FILE='./archive_libs/logical/q_cap/chips/chips.prt';

PART_NAME
 C224 'Q_CAP_0402-0.1UF,25V,10%,X7R,CH4104K1B00':;

SECTION_NUMBER 1
 '@T6G_MB_LIB.T6G(SCH_1):PAGE77_I19@PURE_QUANTA.Q_CAP(CHIPS)':
 C_PATH='@t6g_mb_lib.t6g(sch_1):page77_i19@pure_quanta.q_cap(chips)',
 P_PATH='@t6g_mb_lib.t6g(sch_1):page78_i19@pure_quanta.q_cap(chips)',
 PATH='I19',
 DRAWING='@T6G_MB_LIB.T6G(SCH_1):PAGE77',
 TOLERANCE='10%',
 MATERIAL='X7R',
 PHYS_PAGE='78',
 XY='(-4075,2800)',
 ROT='0',
 VER='1',
 PACK_TYPE='0402',
 LOCATION='C224',
 CDS_LIB='pure_quanta',
 CDS_PART_NAME='Q_CAP_0402-0.1UF,25V,10%,X7R,CH4104K1B00',
 VOLTAGE='25V',
 PART_NUMBER='CH4104K1B00',
 VALUE='0.1UF',
 PRIM_FILE='./archive_libs/logical/q_cap/chips/chips.prt';

PART_NAME
 C225 'Q_CAP_C0805-100UF,4V,20%,X6S,CH710KMEA01':;

SECTION_NUMBER 1
 '@T6G_MB_LIB.T6G(SCH_1):PAGE398_I52@PURE_QUANTA.Q_CAP(CHIPS)':
 C_PATH='@t6g_mb_lib.t6g(sch_1):page398_i52@pure_quanta.q_cap(chips)',
 P_PATH='@t6g_mb_lib.t6g(sch_1):page323_i52@pure_quanta.q_cap(chips)',
 PATH='I52',
 DRAWING='@T6G_MB_LIB.T6G(SCH_1):PAGE398',
 TOLERANCE='20%',
 MATERIAL='X6S',
 PHYS_PAGE='323',
 XY='(-3525,4475)',
 ROT='0',
 VER='1',
 PACK_TYPE='C0805',
 LOCATION='C225',
 CDS_LIB='pure_quanta',
 CDS_PART_NAME='Q_CAP_C0805-100UF,4V,20%,X6S,CH710KMEA01',
 VOLTAGE='4V',
 PART_NUMBER='CH710KMEA01',
 VALUE='100UF',
 PRIM_FILE='./archive_libs/logical/q_cap/chips/chips.prt';

PART_NAME
 C226 'Q_CAP_0402-0.1UF,25V,10%,X7R,CH4104K1B00':;

SECTION_NUMBER 1
 '@T6G_MB_LIB.T6G(SCH_1):PAGE34_I59@PURE_QUANTA.Q_CAP(CHIPS)':
 C_PATH='@t6g_mb_lib.t6g(sch_1):page34_i59@pure_quanta.q_cap(chips)',
 P_PATH='@t6g_mb_lib.t6g(sch_1):page34_i59@pure_quanta.q_cap(chips)',
 PATH='I59',
 DRAWING='@T6G_MB_LIB.T6G(SCH_1):PAGE34',
 BOM_COST='OCP3.0 ',
 TOLERANCE='10%',
 MATERIAL='X7R',
 PHYS_PAGE='34',
 XY='(-6950,3050)',
 ROT='0',
 VER='1',
 PACK_TYPE='0402',
 LOCATION='C226',
 CDS_LIB='pure_quanta',
 CDS_PART_NAME='Q_CAP_0402-0.1UF,25V,10%,X7R,CH4104K1B00',
 VOLTAGE='25V',
 PART_NUMBER='CH4104K1B00',
 VALUE='0.1UF',
 PRIM_FILE='./archive_libs/logical/q_cap/chips/chips.prt';

PART_NAME
 C227 'Q_CAP_0402-4.7UF,6.3V,20%,X6S,CH5471MEB01':;

SECTION_NUMBER 1
 '@T6G_MB_LIB.T6G(SCH_1):PAGE398_I57@PURE_QUANTA.Q_CAP(CHIPS)':
 C_PATH='@t6g_mb_lib.t6g(sch_1):page398_i57@pure_quanta.q_cap(chips)',
 P_PATH='@t6g_mb_lib.t6g(sch_1):page323_i57@pure_quanta.q_cap(chips)',
 PATH='I57',
 DRAWING='@T6G_MB_LIB.T6G(SCH_1):PAGE398',
 TOLERANCE='20%',
 MATERIAL='X6S',
 PHYS_PAGE='323',
 XY='(-2600,3850)',
 ROT='0',
 VER='1',
 PACK_TYPE='0402',
 LOCATION='C227',
 CDS_LIB='pure_quanta',
 CDS_PART_NAME='Q_CAP_0402-4.7UF,6.3V,20%,X6S,CH5471MEB01',
 VOLTAGE='6.3V',
 PART_NUMBER='CH5471MEB01',
 VALUE='4.7UF',
 PRIM_FILE='./archive_libs/logical/q_cap/chips/chips.prt';

PART_NAME
 C228 'Q_CAP_C0201-0.1UF,10V,10%,X7S,CH4102K6E00':;

SECTION_NUMBER 1
 '@T6G_MB_LIB.T6G(SCH_1):PAGE398_I87@PURE_QUANTA.Q_CAP(CHIPS)':
 C_PATH='@t6g_mb_lib.t6g(sch_1):page398_i87@pure_quanta.q_cap(chips)',
 P_PATH='@t6g_mb_lib.t6g(sch_1):page323_i87@pure_quanta.q_cap(chips)',
 PATH='I87',
 DRAWING='@T6G_MB_LIB.T6G(SCH_1):PAGE398',
 TOLERANCE='10%',
 MATERIAL='X7S',
 PHYS_PAGE='323',
 XY='(-2700,2525)',
 ROT='0',
 VER='1',
 PACK_TYPE='C0201',
 LOCATION='C228',
 CDS_LIB='pure_quanta',
 CDS_PART_NAME='Q_CAP_C0201-0.1UF,10V,10%,X7S,CH4102K6E00',
 VOLTAGE='10V',
 PART_NUMBER='CH4102K6E00',
 VALUE='0.1UF',
 PRIM_FILE='./archive_libs/logical/q_cap/chips/chips.prt';

PART_NAME
 C229 'Q_CAP_C0805-100UF,4V,20%,X6S,CH710KMEA01':;

SECTION_NUMBER 1
 '@T6G_MB_LIB.T6G(SCH_1):PAGE398_I34@PURE_QUANTA.Q_CAP(CHIPS)':
 C_PATH='@t6g_mb_lib.t6g(sch_1):page398_i34@pure_quanta.q_cap(chips)',
 P_PATH='@t6g_mb_lib.t6g(sch_1):page323_i34@pure_quanta.q_cap(chips)',
 PATH='I34',
 DRAWING='@T6G_MB_LIB.T6G(SCH_1):PAGE398',
 TOLERANCE='20%',
 MATERIAL='X6S',
 PHYS_PAGE='323',
 XY='(-3700,5750)',
 ROT='0',
 VER='1',
 PACK_TYPE='C0805',
 LOCATION='C229',
 CDS_LIB='pure_quanta',
 CDS_PART_NAME='Q_CAP_C0805-100UF,4V,20%,X6S,CH710KMEA01',
 VOLTAGE='4V',
 PART_NUMBER='CH710KMEA01',
 VALUE='100UF',
 PRIM_FILE='./archive_libs/logical/q_cap/chips/chips.prt';

PART_NAME
 C230 'Q_CAP_C0402-0.001UF,50V,10%,EMPTY,CH30106KB19':;

SECTION_NUMBER 1
 '@T6G_MB_LIB.T6G(SCH_1):PAGE54_I325@PURE_QUANTA.Q_CAP(CHIPS)':
 C_PATH='@t6g_mb_lib.t6g(sch_1):page54_i325@pure_quanta.q_cap(chips)',
 P_PATH='@t6g_mb_lib.t6g(sch_1):page54_i325@pure_quanta.q_cap(chips)',
 PATH='I325',
 DRAWING='@T6G_MB_LIB.T6G(SCH_1):PAGE54',
 TOLERANCE='10%',
 MATERIAL='EMPTY',
 PHYS_PAGE='54',
 XY='(-8275,625)',
 ROT='0',
 VER='1',
 PACK_TYPE='C0402',
 LOCATION='C230',
 CDS_LIB='pure_quanta',
 CDS_PART_NAME='Q_CAP_C0402-0.001UF,50V,10%,EMPTY,CH30106KB19',
 VOLTAGE='50V',
 PART_NUMBER='CH30106KB19',
 VALUE='0.001UF',
 PRIM_FILE='./archive_libs/logical/q_cap/chips/chips.prt';

PART_NAME
 C231 'Q_CAP_C0402-0.001UF,50V,10%,EMPTY,CH30106KB19':;

SECTION_NUMBER 1
 '@T6G_MB_LIB.T6G(SCH_1):PAGE54_I319@PURE_QUANTA.Q_CAP(CHIPS)':
 C_PATH='@t6g_mb_lib.t6g(sch_1):page54_i319@pure_quanta.q_cap(chips)',
 P_PATH='@t6g_mb_lib.t6g(sch_1):page54_i319@pure_quanta.q_cap(chips)',
 PATH='I319',
 DRAWING='@T6G_MB_LIB.T6G(SCH_1):PAGE54',
 TOLERANCE='10%',
 MATERIAL='EMPTY',
 PHYS_PAGE='54',
 XY='(-7950,625)',
 ROT='0',
 VER='1',
 PACK_TYPE='C0402',
 LOCATION='C231',
 CDS_LIB='pure_quanta',
 CDS_PART_NAME='Q_CAP_C0402-0.001UF,50V,10%,EMPTY,CH30106KB19',
 VOLTAGE='50V',
 PART_NUMBER='CH30106KB19',
 VALUE='0.001UF',
 PRIM_FILE='./archive_libs/logical/q_cap/chips/chips.prt';

PART_NAME
 C232 'Q_CAP_C0402-0.001UF,50V,10%,EMPTY,CH30106KB19':;

SECTION_NUMBER 1
 '@T6G_MB_LIB.T6G(SCH_1):PAGE54_I318@PURE_QUANTA.Q_CAP(CHIPS)':
 C_PATH='@t6g_mb_lib.t6g(sch_1):page54_i318@pure_quanta.q_cap(chips)',
 P_PATH='@t6g_mb_lib.t6g(sch_1):page54_i318@pure_quanta.q_cap(chips)',
 PATH='I318',
 DRAWING='@T6G_MB_LIB.T6G(SCH_1):PAGE54',
 TOLERANCE='10%',
 MATERIAL='EMPTY',
 PHYS_PAGE='54',
 XY='(-7625,625)',
 ROT='0',
 VER='1',
 PACK_TYPE='C0402',
 LOCATION='C232',
 CDS_LIB='pure_quanta',
 CDS_PART_NAME='Q_CAP_C0402-0.001UF,50V,10%,EMPTY,CH30106KB19',
 VOLTAGE='50V',
 PART_NUMBER='CH30106KB19',
 VALUE='0.001UF',
 PRIM_FILE='./archive_libs/logical/q_cap/chips/chips.prt';

PART_NAME
 C233 'Q_CAP_C0402-0.001UF,50V,10%,EMPTY,CH30106KB19':;

SECTION_NUMBER 1
 '@T6G_MB_LIB.T6G(SCH_1):PAGE54_I315@PURE_QUANTA.Q_CAP(CHIPS)':
 C_PATH='@t6g_mb_lib.t6g(sch_1):page54_i315@pure_quanta.q_cap(chips)',
 P_PATH='@t6g_mb_lib.t6g(sch_1):page54_i315@pure_quanta.q_cap(chips)',
 PATH='I315',
 DRAWING='@T6G_MB_LIB.T6G(SCH_1):PAGE54',
 TOLERANCE='10%',
 MATERIAL='EMPTY',
 PHYS_PAGE='54',
 XY='(-7300,625)',
 ROT='0',
 VER='1',
 PACK_TYPE='C0402',
 LOCATION='C233',
 CDS_LIB='pure_quanta',
 CDS_PART_NAME='Q_CAP_C0402-0.001UF,50V,10%,EMPTY,CH30106KB19',
 VOLTAGE='50V',
 PART_NUMBER='CH30106KB19',
 VALUE='0.001UF',
 PRIM_FILE='./archive_libs/logical/q_cap/chips/chips.prt';

PART_NAME
 C234 'Q_CAP_C0402-0.001UF,50V,10%,EMPTY,CH30106KB19':;

SECTION_NUMBER 1
 '@T6G_MB_LIB.T6G(SCH_1):PAGE54_I311@PURE_QUANTA.Q_CAP(CHIPS)':
 C_PATH='@t6g_mb_lib.t6g(sch_1):page54_i311@pure_quanta.q_cap(chips)',
 P_PATH='@t6g_mb_lib.t6g(sch_1):page54_i311@pure_quanta.q_cap(chips)',
 PATH='I311',
 DRAWING='@T6G_MB_LIB.T6G(SCH_1):PAGE54',
 TOLERANCE='10%',
 MATERIAL='EMPTY',
 PHYS_PAGE='54',
 XY='(-7000,625)',
 ROT='0',
 VER='1',
 PACK_TYPE='C0402',
 LOCATION='C234',
 CDS_LIB='pure_quanta',
 CDS_PART_NAME='Q_CAP_C0402-0.001UF,50V,10%,EMPTY,CH30106KB19',
 VOLTAGE='50V',
 PART_NUMBER='CH30106KB19',
 VALUE='0.001UF',
 PRIM_FILE='./archive_libs/logical/q_cap/chips/chips.prt';

PART_NAME
 C235 'Q_CAP_C0402-0.001UF,50V,10%,EMPTY,CH30106KB19':;

SECTION_NUMBER 1
 '@T6G_MB_LIB.T6G(SCH_1):PAGE54_I310@PURE_QUANTA.Q_CAP(CHIPS)':
 C_PATH='@t6g_mb_lib.t6g(sch_1):page54_i310@pure_quanta.q_cap(chips)',
 P_PATH='@t6g_mb_lib.t6g(sch_1):page54_i310@pure_quanta.q_cap(chips)',
 PATH='I310',
 DRAWING='@T6G_MB_LIB.T6G(SCH_1):PAGE54',
 TOLERANCE='10%',
 MATERIAL='EMPTY',
 PHYS_PAGE='54',
 XY='(-6725,625)',
 ROT='0',
 VER='1',
 PACK_TYPE='C0402',
 LOCATION='C235',
 CDS_LIB='pure_quanta',
 CDS_PART_NAME='Q_CAP_C0402-0.001UF,50V,10%,EMPTY,CH30106KB19',
 VOLTAGE='50V',
 PART_NUMBER='CH30106KB19',
 VALUE='0.001UF',
 PRIM_FILE='./archive_libs/logical/q_cap/chips/chips.prt';

PART_NAME
 C236 'Q_CAP_C0402-2.7PF,50V,0.1PF,NPO,CH-276B0B00':;

SECTION_NUMBER 1
 '@T6G_MB_LIB.T6G(SCH_1):PAGE55_I3@PURE_QUANTA.Q_CAP(CHIPS)':
 C_PATH='@t6g_mb_lib.t6g(sch_1):page55_i3@pure_quanta.q_cap(chips)',
 P_PATH='@t6g_mb_lib.t6g(sch_1):page55_i3@pure_quanta.q_cap(chips)',
 PATH='I3',
 DRAWING='@T6G_MB_LIB.T6G(SCH_1):PAGE55',
 TOLERANCE='0.1PF',
 MATERIAL='NPO',
 PHYS_PAGE='55',
 XY='(-6175,825)',
 ROT='0',
 VER='1',
 PACK_TYPE='C0402',
 LOCATION='C236',
 CDS_LIB='pure_quanta',
 CDS_PART_NAME='Q_CAP_C0402-2.7PF,50V,0.1PF,NPO,CH-276B0B00',
 VOLTAGE='50V',
 PART_NUMBER='CH-276B0B00',
 VALUE='2.7PF',
 PRIM_FILE='./archive_libs/logical/q_cap/chips/chips.prt';

PART_NAME
 C237 'Q_CAP_C0402-2.7PF,50V,0.1PF,NPO,CH-276B0B00':;

SECTION_NUMBER 1
 '@T6G_MB_LIB.T6G(SCH_1):PAGE55_I15@PURE_QUANTA.Q_CAP(CHIPS)':
 C_PATH='@t6g_mb_lib.t6g(sch_1):page55_i15@pure_quanta.q_cap(chips)',
 P_PATH='@t6g_mb_lib.t6g(sch_1):page55_i15@pure_quanta.q_cap(chips)',
 PATH='I15',
 DRAWING='@T6G_MB_LIB.T6G(SCH_1):PAGE55',
 TOLERANCE='0.1PF',
 MATERIAL='NPO',
 PHYS_PAGE='55',
 XY='(-4900,825)',
 ROT='0',
 VER='1',
 PACK_TYPE='C0402',
 LOCATION='C237',
 CDS_LIB='pure_quanta',
 CDS_PART_NAME='Q_CAP_C0402-2.7PF,50V,0.1PF,NPO,CH-276B0B00',
 VOLTAGE='50V',
 PART_NUMBER='CH-276B0B00',
 VALUE='2.7PF',
 PRIM_FILE='./archive_libs/logical/q_cap/chips/chips.prt';

PART_NAME
 C238 'Q_CAP_0402-10PF,50V,1%,NPO,TMP_QCH0106F0B00':;

SECTION_NUMBER 1
 '@T6G_MB_LIB.T6G(SCH_1):PAGE55_I5@PURE_QUANTA.Q_CAP(CHIPS)':
 C_PATH='@t6g_mb_lib.t6g(sch_1):page55_i5@pure_quanta.q_cap(chips)',
 P_PATH='@t6g_mb_lib.t6g(sch_1):page55_i5@pure_quanta.q_cap(chips)',
 PATH='I5',
 DRAWING='@T6G_MB_LIB.T6G(SCH_1):PAGE55',
 TOLERANCE='1%',
 MATERIAL='NPO',
 PHYS_PAGE='55',
 XY='(-4125,1050)',
 ROT='0',
 VER='1',
 PACK_TYPE='0402',
 LOCATION='C238',
 CDS_LIB='pure_quanta',
 CDS_PART_NAME='Q_CAP_0402-10PF,50V,1%,NPO,TMP_QCH0106F0B00',
 VOLTAGE='50V',
 PART_NUMBER='TMP_QCH0106F0B00',
 VALUE='10PF',
 PRIM_FILE='./archive_libs/logical/q_cap/chips/chips.prt';

PART_NAME
 C239 'Q_CAP_0402-10PF,50V,1%,NPO,TMP_QCH0106F0B00':;

SECTION_NUMBER 1
 '@T6G_MB_LIB.T6G(SCH_1):PAGE55_I9@PURE_QUANTA.Q_CAP(CHIPS)':
 C_PATH='@t6g_mb_lib.t6g(sch_1):page55_i9@pure_quanta.q_cap(chips)',
 P_PATH='@t6g_mb_lib.t6g(sch_1):page55_i9@pure_quanta.q_cap(chips)',
 PATH='I9',
 DRAWING='@T6G_MB_LIB.T6G(SCH_1):PAGE55',
 TOLERANCE='1%',
 MATERIAL='NPO',
 PHYS_PAGE='55',
 XY='(-3075,1075)',
 ROT='0',
 VER='1',
 PACK_TYPE='0402',
 LOCATION='C239',
 CDS_LIB='pure_quanta',
 CDS_PART_NAME='Q_CAP_0402-10PF,50V,1%,NPO,TMP_QCH0106F0B00',
 VOLTAGE='50V',
 PART_NUMBER='TMP_QCH0106F0B00',
 VALUE='10PF',
 PRIM_FILE='./archive_libs/logical/q_cap/chips/chips.prt';

PART_NAME
 C240 'Q_CAP_C0805-100UF,4V,20%,X6S,CH710KMEA01':;

SECTION_NUMBER 1
 '@T6G_MB_LIB.T6G(SCH_1):PAGE398_I53@PURE_QUANTA.Q_CAP(CHIPS)':
 C_PATH='@t6g_mb_lib.t6g(sch_1):page398_i53@pure_quanta.q_cap(chips)',
 P_PATH='@t6g_mb_lib.t6g(sch_1):page323_i53@pure_quanta.q_cap(chips)',
 PATH='I53',
 DRAWING='@T6G_MB_LIB.T6G(SCH_1):PAGE398',
 TOLERANCE='20%',
 MATERIAL='X6S',
 PHYS_PAGE='323',
 XY='(-3300,4475)',
 ROT='0',
 VER='1',
 PACK_TYPE='C0805',
 LOCATION='C240',
 CDS_LIB='pure_quanta',
 CDS_PART_NAME='Q_CAP_C0805-100UF,4V,20%,X6S,CH710KMEA01',
 VOLTAGE='4V',
 PART_NUMBER='CH710KMEA01',
 VALUE='100UF',
 PRIM_FILE='./archive_libs/logical/q_cap/chips/chips.prt';

PART_NAME
 C241 'Q_CAP_0402-4.7UF,6.3V,20%,X6S,CH5471MEB01':;

SECTION_NUMBER 1
 '@T6G_MB_LIB.T6G(SCH_1):PAGE398_I72@PURE_QUANTA.Q_CAP(CHIPS)':
 C_PATH='@t6g_mb_lib.t6g(sch_1):page398_i72@pure_quanta.q_cap(chips)',
 P_PATH='@t6g_mb_lib.t6g(sch_1):page323_i72@pure_quanta.q_cap(chips)',
 PATH='I72',
 DRAWING='@T6G_MB_LIB.T6G(SCH_1):PAGE398',
 TOLERANCE='20%',
 MATERIAL='X6S',
 PHYS_PAGE='323',
 XY='(-3300,3850)',
 ROT='0',
 VER='1',
 PACK_TYPE='0402',
 LOCATION='C241',
 CDS_LIB='pure_quanta',
 CDS_PART_NAME='Q_CAP_0402-4.7UF,6.3V,20%,X6S,CH5471MEB01',
 VOLTAGE='6.3V',
 PART_NUMBER='CH5471MEB01',
 VALUE='4.7UF',
 PRIM_FILE='./archive_libs/logical/q_cap/chips/chips.prt';

PART_NAME
 C242 'Q_CAP_0402-1000PF,50V,5%,X7R,TMP_QCH21006JB10':;

SECTION_NUMBER 1
 '@T6G_MB_LIB.T6G(SCH_1):PAGE185_I13@PURE_QUANTA.Q_CAP(CHIPS)':
 C_PATH='@t6g_mb_lib.t6g(sch_1):page185_i13@pure_quanta.q_cap(chips)',
 P_PATH='@t6g_mb_lib.t6g(sch_1):page210_i13@pure_quanta.q_cap(chips)',
 PATH='I13',
 DRAWING='@T6G_MB_LIB.T6G(SCH_1):PAGE185',
 TOLERANCE='5%',
 MATERIAL='X7R',
 PHYS_PAGE='210',
 XY='(-4850,2950)',
 ROT='0',
 VER='1',
 PACK_TYPE='0402',
 LOCATION='C242',
 CDS_LIB='pure_quanta',
 CDS_PART_NAME='Q_CAP_0402-1000PF,50V,5%,X7R,TMP_QCH21006JB10',
 VOLTAGE='50V',
 PART_NUMBER='TMP_QCH21006JB10',
 VALUE='1000PF',
 PRIM_FILE='./archive_libs/logical/q_cap/chips/chips.prt';

PART_NAME
 C243 'Q_CAP_0201-1UF,4V,20%,X6S,CH-10KMEE00':;

SECTION_NUMBER 1
 '@T6G_MB_LIB.T6G(SCH_1):PAGE398_I47@PURE_QUANTA.Q_CAP(CHIPS)':
 C_PATH='@t6g_mb_lib.t6g(sch_1):page398_i47@pure_quanta.q_cap(chips)',
 P_PATH='@t6g_mb_lib.t6g(sch_1):page323_i47@pure_quanta.q_cap(chips)',
 PATH='I47',
 DRAWING='@T6G_MB_LIB.T6G(SCH_1):PAGE398',
 TOLERANCE='20%',
 MATERIAL='X6S',
 PHYS_PAGE='323',
 XY='(-3275,3225)',
 ROT='0',
 VER='1',
 PACK_TYPE='0201',
 LOCATION='C243',
 CDS_LIB='pure_quanta',
 CDS_PART_NAME='Q_CAP_0201-1UF,4V,20%,X6S,CH-10KMEE00',
 VOLTAGE='4V',
 PART_NUMBER='CH-10KMEE00',
 VALUE='1UF',
 PRIM_FILE='./archive_libs/logical/q_cap/chips/chips.prt';

PART_NAME
 C244 'Q_CAP_C0402-22UF,4V,20%,X6S,CH622KMEB02':;

SECTION_NUMBER 1
 '@T6G_MB_LIB.T6G(SCH_1):PAGE398_I35@PURE_QUANTA.Q_CAP(CHIPS)':
 C_PATH='@t6g_mb_lib.t6g(sch_1):page398_i35@pure_quanta.q_cap(chips)',
 P_PATH='@t6g_mb_lib.t6g(sch_1):page323_i35@pure_quanta.q_cap(chips)',
 PATH='I35',
 DRAWING='@T6G_MB_LIB.T6G(SCH_1):PAGE398',
 TOLERANCE='20%',
 MATERIAL='X6S',
 PHYS_PAGE='323',
 XY='(-3425,5750)',
 ROT='0',
 VER='1',
 PACK_TYPE='C0402',
 LOCATION='C244',
 CDS_LIB='pure_quanta',
 CDS_PART_NAME='Q_CAP_C0402-22UF,4V,20%,X6S,CH622KMEB02',
 VOLTAGE='4V',
 PART_NUMBER='CH622KMEB02',
 VALUE='22UF',
 PRIM_FILE='./archive_libs/logical/q_cap/chips/chips.prt';

PART_NAME
 C245 'Q_CAP_C0402-22UF,4V,20%,X6S,CH622KMEB02':;

SECTION_NUMBER 1
 '@T6G_MB_LIB.T6G(SCH_1):PAGE68_I14@PURE_QUANTA.Q_CAP(CHIPS)':
 C_PATH='@t6g_mb_lib.t6g(sch_1):page68_i14@pure_quanta.q_cap(chips)',
 P_PATH='@t6g_mb_lib.t6g(sch_1):page69_i14@pure_quanta.q_cap(chips)',
 PATH='I14',
 DRAWING='@T6G_MB_LIB.T6G(SCH_1):PAGE68',
 TOLERANCE='20%',
 MATERIAL='X6S',
 PHYS_PAGE='69',
 XY='(-9000,5250)',
 ROT='0',
 VER='1',
 PACK_TYPE='C0402',
 LOCATION='C245',
 CDS_LIB='pure_quanta',
 CDS_PART_NAME='Q_CAP_C0402-22UF,4V,20%,X6S,CH622KMEB02',
 VOLTAGE='4V',
 PART_NUMBER='CH622KMEB02',
 VALUE='22UF',
 PRIM_FILE='./archive_libs/logical/q_cap/chips/chips.prt';

PART_NAME
 C246 'Q_CAP_C0402-22UF,4V,20%,X6S,CH622KMEB02':;

SECTION_NUMBER 1
 '@T6G_MB_LIB.T6G(SCH_1):PAGE68_I10@PURE_QUANTA.Q_CAP(CHIPS)':
 C_PATH='@t6g_mb_lib.t6g(sch_1):page68_i10@pure_quanta.q_cap(chips)',
 P_PATH='@t6g_mb_lib.t6g(sch_1):page69_i10@pure_quanta.q_cap(chips)',
 PATH='I10',
 DRAWING='@T6G_MB_LIB.T6G(SCH_1):PAGE68',
 TOLERANCE='20%',
 MATERIAL='X6S',
 PHYS_PAGE='69',
 XY='(-9000,4475)',
 ROT='0',
 VER='1',
 PACK_TYPE='C0402',
 LOCATION='C246',
 CDS_LIB='pure_quanta',
 CDS_PART_NAME='Q_CAP_C0402-22UF,4V,20%,X6S,CH622KMEB02',
 VOLTAGE='4V',
 PART_NUMBER='CH622KMEB02',
 VALUE='22UF',
 PRIM_FILE='./archive_libs/logical/q_cap/chips/chips.prt';

PART_NAME
 C247 'Q_CAP_C0805-100UF,4V,20%,X6S,CH710KMEA01':;

SECTION_NUMBER 1
 '@T6G_MB_LIB.T6G(SCH_1):PAGE398_I73@PURE_QUANTA.Q_CAP(CHIPS)':
 C_PATH='@t6g_mb_lib.t6g(sch_1):page398_i73@pure_quanta.q_cap(chips)',
 P_PATH='@t6g_mb_lib.t6g(sch_1):page323_i73@pure_quanta.q_cap(chips)',
 PATH='I73',
 DRAWING='@T6G_MB_LIB.T6G(SCH_1):PAGE398',
 TOLERANCE='20%',
 MATERIAL='X6S',
 PHYS_PAGE='323',
 XY='(-3075,4475)',
 ROT='0',
 VER='1',
 PACK_TYPE='C0805',
 LOCATION='C247',
 CDS_LIB='pure_quanta',
 CDS_PART_NAME='Q_CAP_C0805-100UF,4V,20%,X6S,CH710KMEA01',
 VOLTAGE='4V',
 PART_NUMBER='CH710KMEA01',
 VALUE='100UF',
 PRIM_FILE='./archive_libs/logical/q_cap/chips/chips.prt';

PART_NAME
 C248 'Q_CAP_0402-1000PF,50V,5%,EMPTY,TMP_QCH21006JB10':;

SECTION_NUMBER 1
 '@T6G_MB_LIB.T6G(SCH_1):PAGE185_I88@PURE_QUANTA.Q_CAP(CHIPS)':
 C_PATH='@t6g_mb_lib.t6g(sch_1):page185_i88@pure_quanta.q_cap(chips)',
 P_PATH='@t6g_mb_lib.t6g(sch_1):page210_i88@pure_quanta.q_cap(chips)',
 PATH='I88',
 DRAWING='@T6G_MB_LIB.T6G(SCH_1):PAGE185',
 TOLERANCE='5%',
 MATERIAL='EMPTY',
 PHYS_PAGE='210',
 XY='(-2025,8150)',
 ROT='0',
 VER='2',
 PACK_TYPE='0402',
 LOCATION='C248',
 CDS_LIB='pure_quanta',
 CDS_PART_NAME='Q_CAP_0402-1000PF,50V,5%,EMPTY,TMP_QCH21006JB10',
 VOLTAGE='50V',
 PART_NUMBER='TMP_QCH21006JB10',
 VALUE='1000PF',
 PRIM_FILE='./archive_libs/logical/q_cap/chips/chips.prt';

PART_NAME
 C249 'Q_CAP_0402-1000PF,50V,5%,X7R,TMP_QCH21006JB10':;

SECTION_NUMBER 1
 '@T6G_MB_LIB.T6G(SCH_1):PAGE185_I86@PURE_QUANTA.Q_CAP(CHIPS)':
 C_PATH='@t6g_mb_lib.t6g(sch_1):page185_i86@pure_quanta.q_cap(chips)',
 P_PATH='@t6g_mb_lib.t6g(sch_1):page210_i86@pure_quanta.q_cap(chips)',
 PATH='I86',
 DRAWING='@T6G_MB_LIB.T6G(SCH_1):PAGE185',
 TOLERANCE='5%',
 MATERIAL='X7R',
 PHYS_PAGE='210',
 XY='(-2000,7600)',
 ROT='0',
 VER='2',
 PACK_TYPE='0402',
 LOCATION='C249',
 CDS_LIB='pure_quanta',
 CDS_PART_NAME='Q_CAP_0402-1000PF,50V,5%,X7R,TMP_QCH21006JB10',
 VOLTAGE='50V',
 PART_NUMBER='TMP_QCH21006JB10',
 VALUE='1000PF',
 PRIM_FILE='./archive_libs/logical/q_cap/chips/chips.prt';

PART_NAME
 C250 'Q_CAP_C0402-10UF,6.3V,20%,X6S,CH6101MEB01':;

SECTION_NUMBER 1
 '@T6G_MB_LIB.T6G(SCH_1):PAGE398_I70@PURE_QUANTA.Q_CAP(CHIPS)':
 C_PATH='@t6g_mb_lib.t6g(sch_1):page398_i70@pure_quanta.q_cap(chips)',
 P_PATH='@t6g_mb_lib.t6g(sch_1):page323_i70@pure_quanta.q_cap(chips)',
 PATH='I70',
 DRAWING='@T6G_MB_LIB.T6G(SCH_1):PAGE398',
 TOLERANCE='20%',
 MATERIAL='X6S',
 PHYS_PAGE='323',
 XY='(-3750,3850)',
 ROT='0',
 VER='1',
 PACK_TYPE='C0402',
 LOCATION='C250',
 CDS_LIB='pure_quanta',
 CDS_PART_NAME='Q_CAP_C0402-10UF,6.3V,20%,X6S,CH6101MEB01',
 VOLTAGE='6.3V',
 PART_NUMBER='CH6101MEB01',
 VALUE='10UF',
 PRIM_FILE='./archive_libs/logical/q_cap/chips/chips.prt';

PART_NAME
 C251 'Q_CAP_C0402-22UF,4V,20%,X6S,CH622KMEB02':;

SECTION_NUMBER 1
 '@T6G_MB_LIB.T6G(SCH_1):PAGE68_I15@PURE_QUANTA.Q_CAP(CHIPS)':
 C_PATH='@t6g_mb_lib.t6g(sch_1):page68_i15@pure_quanta.q_cap(chips)',
 P_PATH='@t6g_mb_lib.t6g(sch_1):page69_i15@pure_quanta.q_cap(chips)',
 PATH='I15',
 DRAWING='@T6G_MB_LIB.T6G(SCH_1):PAGE68',
 TOLERANCE='20%',
 MATERIAL='X6S',
 PHYS_PAGE='69',
 XY='(-8550,5250)',
 ROT='0',
 VER='1',
 PACK_TYPE='C0402',
 LOCATION='C251',
 CDS_LIB='pure_quanta',
 CDS_PART_NAME='Q_CAP_C0402-22UF,4V,20%,X6S,CH622KMEB02',
 VOLTAGE='4V',
 PART_NUMBER='CH622KMEB02',
 VALUE='22UF',
 PRIM_FILE='./archive_libs/logical/q_cap/chips/chips.prt';

PART_NAME
 C252 'Q_CAP_C0402-22UF,4V,20%,X6S,CH622KMEB02':;

SECTION_NUMBER 1
 '@T6G_MB_LIB.T6G(SCH_1):PAGE68_I12@PURE_QUANTA.Q_CAP(CHIPS)':
 C_PATH='@t6g_mb_lib.t6g(sch_1):page68_i12@pure_quanta.q_cap(chips)',
 P_PATH='@t6g_mb_lib.t6g(sch_1):page69_i12@pure_quanta.q_cap(chips)',
 PATH='I12',
 DRAWING='@T6G_MB_LIB.T6G(SCH_1):PAGE68',
 TOLERANCE='20%',
 MATERIAL='X6S',
 PHYS_PAGE='69',
 XY='(-8550,4475)',
 ROT='0',
 VER='1',
 PACK_TYPE='C0402',
 LOCATION='C252',
 CDS_LIB='pure_quanta',
 CDS_PART_NAME='Q_CAP_C0402-22UF,4V,20%,X6S,CH622KMEB02',
 VOLTAGE='4V',
 PART_NUMBER='CH622KMEB02',
 VALUE='22UF',
 PRIM_FILE='./archive_libs/logical/q_cap/chips/chips.prt';

PART_NAME
 C253 'Q_CAP_C0201-0.1UF,10V,10%,X7S,CH4102K6E00':;

SECTION_NUMBER 1
 '@T6G_MB_LIB.T6G(SCH_1):PAGE398_I86@PURE_QUANTA.Q_CAP(CHIPS)':
 C_PATH='@t6g_mb_lib.t6g(sch_1):page398_i86@pure_quanta.q_cap(chips)',
 P_PATH='@t6g_mb_lib.t6g(sch_1):page323_i86@pure_quanta.q_cap(chips)',
 PATH='I86',
 DRAWING='@T6G_MB_LIB.T6G(SCH_1):PAGE398',
 TOLERANCE='10%',
 MATERIAL='X7S',
 PHYS_PAGE='323',
 XY='(-2450,2525)',
 ROT='0',
 VER='1',
 PACK_TYPE='C0201',
 LOCATION='C253',
 CDS_LIB='pure_quanta',
 CDS_PART_NAME='Q_CAP_C0201-0.1UF,10V,10%,X7S,CH4102K6E00',
 VOLTAGE='10V',
 PART_NUMBER='CH4102K6E00',
 VALUE='0.1UF',
 PRIM_FILE='./archive_libs/logical/q_cap/chips/chips.prt';

PART_NAME
 C254 'Q_CAP_C0402-10UF,6.3V,20%,X6S,CH6101MEB01':;

SECTION_NUMBER 1
 '@T6G_MB_LIB.T6G(SCH_1):PAGE398_I67@PURE_QUANTA.Q_CAP(CHIPS)':
 C_PATH='@t6g_mb_lib.t6g(sch_1):page398_i67@pure_quanta.q_cap(chips)',
 P_PATH='@t6g_mb_lib.t6g(sch_1):page323_i67@pure_quanta.q_cap(chips)',
 PATH='I67',
 DRAWING='@T6G_MB_LIB.T6G(SCH_1):PAGE398',
 TOLERANCE='20%',
 MATERIAL='X6S',
 PHYS_PAGE='323',
 XY='(-1850,4475)',
 ROT='0',
 VER='1',
 PACK_TYPE='C0402',
 LOCATION='C254',
 CDS_LIB='pure_quanta',
 CDS_PART_NAME='Q_CAP_C0402-10UF,6.3V,20%,X6S,CH6101MEB01',
 VOLTAGE='6.3V',
 PART_NUMBER='CH6101MEB01',
 VALUE='10UF',
 PRIM_FILE='./archive_libs/logical/q_cap/chips/chips.prt';

PART_NAME
 C255 'Q_CAP_C0402-22UF,4V,20%,X6S,CH622KMEB02':;

SECTION_NUMBER 1
 '@T6G_MB_LIB.T6G(SCH_1):PAGE398_I64@PURE_QUANTA.Q_CAP(CHIPS)':
 C_PATH='@t6g_mb_lib.t6g(sch_1):page398_i64@pure_quanta.q_cap(chips)',
 P_PATH='@t6g_mb_lib.t6g(sch_1):page323_i64@pure_quanta.q_cap(chips)',
 PATH='I64',
 DRAWING='@T6G_MB_LIB.T6G(SCH_1):PAGE398',
 TOLERANCE='20%',
 MATERIAL='X6S',
 PHYS_PAGE='323',
 XY='(-2600,4475)',
 ROT='0',
 VER='1',
 PACK_TYPE='C0402',
 LOCATION='C255',
 CDS_LIB='pure_quanta',
 CDS_PART_NAME='Q_CAP_C0402-22UF,4V,20%,X6S,CH622KMEB02',
 VOLTAGE='4V',
 PART_NUMBER='CH622KMEB02',
 VALUE='22UF',
 PRIM_FILE='./archive_libs/logical/q_cap/chips/chips.prt';

PART_NAME
 C256 'Q_CAP_0402-4.7UF,6.3V,20%,X6S,CH5471MEB01':;

SECTION_NUMBER 1
 '@T6G_MB_LIB.T6G(SCH_1):PAGE398_I39@PURE_QUANTA.Q_CAP(CHIPS)':
 C_PATH='@t6g_mb_lib.t6g(sch_1):page398_i39@pure_quanta.q_cap(chips)',
 P_PATH='@t6g_mb_lib.t6g(sch_1):page323_i39@pure_quanta.q_cap(chips)',
 PATH='I39',
 DRAWING='@T6G_MB_LIB.T6G(SCH_1):PAGE398',
 TOLERANCE='20%',
 MATERIAL='X6S',
 PHYS_PAGE='323',
 XY='(-2800,5725)',
 ROT='0',
 VER='1',
 PACK_TYPE='0402',
 LOCATION='C256',
 CDS_LIB='pure_quanta',
 CDS_PART_NAME='Q_CAP_0402-4.7UF,6.3V,20%,X6S,CH5471MEB01',
 VOLTAGE='6.3V',
 PART_NUMBER='CH5471MEB01',
 VALUE='4.7UF',
 PRIM_FILE='./archive_libs/logical/q_cap/chips/chips.prt';

PART_NAME
 C257 'Q_CAP_0201-1UF,4V,20%,X6S,CH-10KMEE00':;

SECTION_NUMBER 1
 '@T6G_MB_LIB.T6G(SCH_1):PAGE398_I49@PURE_QUANTA.Q_CAP(CHIPS)':
 C_PATH='@t6g_mb_lib.t6g(sch_1):page398_i49@pure_quanta.q_cap(chips)',
 P_PATH='@t6g_mb_lib.t6g(sch_1):page323_i49@pure_quanta.q_cap(chips)',
 PATH='I49',
 DRAWING='@T6G_MB_LIB.T6G(SCH_1):PAGE398',
 TOLERANCE='20%',
 MATERIAL='X6S',
 PHYS_PAGE='323',
 XY='(-2800,3225)',
 ROT='0',
 VER='1',
 PACK_TYPE='0201',
 LOCATION='C257',
 CDS_LIB='pure_quanta',
 CDS_PART_NAME='Q_CAP_0201-1UF,4V,20%,X6S,CH-10KMEE00',
 VOLTAGE='4V',
 PART_NUMBER='CH-10KMEE00',
 VALUE='1UF',
 PRIM_FILE='./archive_libs/logical/q_cap/chips/chips.prt';

PART_NAME
 C258 'Q_CAP_0402-4.7UF,6.3V,20%,X6S,CH5471MEB01':;

SECTION_NUMBER 1
 '@T6G_MB_LIB.T6G(SCH_1):PAGE398_I51@PURE_QUANTA.Q_CAP(CHIPS)':
 C_PATH='@t6g_mb_lib.t6g(sch_1):page398_i51@pure_quanta.q_cap(chips)',
 P_PATH='@t6g_mb_lib.t6g(sch_1):page323_i51@pure_quanta.q_cap(chips)',
 PATH='I51',
 DRAWING='@T6G_MB_LIB.T6G(SCH_1):PAGE398',
 TOLERANCE='20%',
 MATERIAL='X6S',
 PHYS_PAGE='323',
 XY='(-2825,3850)',
 ROT='0',
 VER='1',
 PACK_TYPE='0402',
 LOCATION='C258',
 CDS_LIB='pure_quanta',
 CDS_PART_NAME='Q_CAP_0402-4.7UF,6.3V,20%,X6S,CH5471MEB01',
 VOLTAGE='6.3V',
 PART_NUMBER='CH5471MEB01',
 VALUE='4.7UF',
 PRIM_FILE='./archive_libs/logical/q_cap/chips/chips.prt';

PART_NAME
 C259 'Q_CAP_C0402-22UF,4V,20%,X6S,CH622KMEB02':;

SECTION_NUMBER 1
 '@T6G_MB_LIB.T6G(SCH_1):PAGE398_I66@PURE_QUANTA.Q_CAP(CHIPS)':
 C_PATH='@t6g_mb_lib.t6g(sch_1):page398_i66@pure_quanta.q_cap(chips)',
 P_PATH='@t6g_mb_lib.t6g(sch_1):page323_i66@pure_quanta.q_cap(chips)',
 PATH='I66',
 DRAWING='@T6G_MB_LIB.T6G(SCH_1):PAGE398',
 TOLERANCE='20%',
 MATERIAL='X6S',
 PHYS_PAGE='323',
 XY='(-2150,4475)',
 ROT='0',
 VER='1',
 PACK_TYPE='C0402',
 LOCATION='C259',
 CDS_LIB='pure_quanta',
 CDS_PART_NAME='Q_CAP_C0402-22UF,4V,20%,X6S,CH622KMEB02',
 VOLTAGE='4V',
 PART_NUMBER='CH622KMEB02',
 VALUE='22UF',
 PRIM_FILE='./archive_libs/logical/q_cap/chips/chips.prt';

PART_NAME
 C260 'Q_CAP_C0201-0.1UF,10V,10%,X7S,CH4102K6E00':;

SECTION_NUMBER 1
 '@T6G_MB_LIB.T6G(SCH_1):PAGE398_I84@PURE_QUANTA.Q_CAP(CHIPS)':
 C_PATH='@t6g_mb_lib.t6g(sch_1):page398_i84@pure_quanta.q_cap(chips)',
 P_PATH='@t6g_mb_lib.t6g(sch_1):page323_i84@pure_quanta.q_cap(chips)',
 PATH='I84',
 DRAWING='@T6G_MB_LIB.T6G(SCH_1):PAGE398',
 TOLERANCE='10%',
 MATERIAL='X7S',
 PHYS_PAGE='323',
 XY='(-1900,2525)',
 ROT='0',
 VER='1',
 PACK_TYPE='C0201',
 LOCATION='C260',
 CDS_LIB='pure_quanta',
 CDS_PART_NAME='Q_CAP_C0201-0.1UF,10V,10%,X7S,CH4102K6E00',
 VOLTAGE='10V',
 PART_NUMBER='CH4102K6E00',
 VALUE='0.1UF',
 PRIM_FILE='./archive_libs/logical/q_cap/chips/chips.prt';

PART_NAME
 C261 'Q_CAP_C0402-10UF,6.3V,20%,X6S,CH6101MEB01':;

SECTION_NUMBER 1
 '@T6G_MB_LIB.T6G(SCH_1):PAGE398_I36@PURE_QUANTA.Q_CAP(CHIPS)':
 C_PATH='@t6g_mb_lib.t6g(sch_1):page398_i36@pure_quanta.q_cap(chips)',
 P_PATH='@t6g_mb_lib.t6g(sch_1):page323_i36@pure_quanta.q_cap(chips)',
 PATH='I36',
 DRAWING='@T6G_MB_LIB.T6G(SCH_1):PAGE398',
 TOLERANCE='20%',
 MATERIAL='X6S',
 PHYS_PAGE='323',
 XY='(-3100,5725)',
 ROT='0',
 VER='1',
 PACK_TYPE='C0402',
 LOCATION='C261',
 CDS_LIB='pure_quanta',
 CDS_PART_NAME='Q_CAP_C0402-10UF,6.3V,20%,X6S,CH6101MEB01',
 VOLTAGE='6.3V',
 PART_NUMBER='CH6101MEB01',
 VALUE='10UF',
 PRIM_FILE='./archive_libs/logical/q_cap/chips/chips.prt';

PART_NAME
 C262 'Q_CAP_C0402-22UF,4V,20%,X6S,CH622KMEB02':;

SECTION_NUMBER 1
 '@T6G_MB_LIB.T6G(SCH_1):PAGE398_I65@PURE_QUANTA.Q_CAP(CHIPS)':
 C_PATH='@t6g_mb_lib.t6g(sch_1):page398_i65@pure_quanta.q_cap(chips)',
 P_PATH='@t6g_mb_lib.t6g(sch_1):page323_i65@pure_quanta.q_cap(chips)',
 PATH='I65',
 DRAWING='@T6G_MB_LIB.T6G(SCH_1):PAGE398',
 TOLERANCE='20%',
 MATERIAL='X6S',
 PHYS_PAGE='323',
 XY='(-2375,4475)',
 ROT='0',
 VER='1',
 PACK_TYPE='C0402',
 LOCATION='C262',
 CDS_LIB='pure_quanta',
 CDS_PART_NAME='Q_CAP_C0402-22UF,4V,20%,X6S,CH622KMEB02',
 VOLTAGE='4V',
 PART_NUMBER='CH622KMEB02',
 VALUE='22UF',
 PRIM_FILE='./archive_libs/logical/q_cap/chips/chips.prt';

PART_NAME
 C263 'Q_CAP_C0402-22UF,4V,20%,X6S,CH622KMEB02':;

SECTION_NUMBER 1
 '@T6G_MB_LIB.T6G(SCH_1):PAGE68_I46@PURE_QUANTA.Q_CAP(CHIPS)':
 C_PATH='@t6g_mb_lib.t6g(sch_1):page68_i46@pure_quanta.q_cap(chips)',
 P_PATH='@t6g_mb_lib.t6g(sch_1):page69_i46@pure_quanta.q_cap(chips)',
 PATH='I46',
 DRAWING='@T6G_MB_LIB.T6G(SCH_1):PAGE68',
 TOLERANCE='20%',
 MATERIAL='X6S',
 PHYS_PAGE='69',
 XY='(-7650,4475)',
 ROT='0',
 VER='1',
 PACK_TYPE='C0402',
 LOCATION='C263',
 CDS_LIB='pure_quanta',
 CDS_PART_NAME='Q_CAP_C0402-22UF,4V,20%,X6S,CH622KMEB02',
 VOLTAGE='4V',
 PART_NUMBER='CH622KMEB02',
 VALUE='22UF',
 PRIM_FILE='./archive_libs/logical/q_cap/chips/chips.prt';

PART_NAME
 C264 'Q_CAP_C0201-0.1UF,10V,10%,X7S,CH4102K6E00':;

SECTION_NUMBER 1
 '@T6G_MB_LIB.T6G(SCH_1):PAGE398_I81@PURE_QUANTA.Q_CAP(CHIPS)':
 C_PATH='@t6g_mb_lib.t6g(sch_1):page398_i81@pure_quanta.q_cap(chips)',
 P_PATH='@t6g_mb_lib.t6g(sch_1):page323_i81@pure_quanta.q_cap(chips)',
 PATH='I81',
 DRAWING='@T6G_MB_LIB.T6G(SCH_1):PAGE398',
 TOLERANCE='10%',
 MATERIAL='X7S',
 PHYS_PAGE='323',
 XY='(-3175,2525)',
 ROT='0',
 VER='1',
 PACK_TYPE='C0201',
 LOCATION='C264',
 CDS_LIB='pure_quanta',
 CDS_PART_NAME='Q_CAP_C0201-0.1UF,10V,10%,X7S,CH4102K6E00',
 VOLTAGE='10V',
 PART_NUMBER='CH4102K6E00',
 VALUE='0.1UF',
 PRIM_FILE='./archive_libs/logical/q_cap/chips/chips.prt';

PART_NAME
 C265 'Q_CAP_0201-1UF,4V,20%,X6S,CH-10KMEE00':;

SECTION_NUMBER 1
 '@T6G_MB_LIB.T6G(SCH_1):PAGE398_I56@PURE_QUANTA.Q_CAP(CHIPS)':
 C_PATH='@t6g_mb_lib.t6g(sch_1):page398_i56@pure_quanta.q_cap(chips)',
 P_PATH='@t6g_mb_lib.t6g(sch_1):page323_i56@pure_quanta.q_cap(chips)',
 PATH='I56',
 DRAWING='@T6G_MB_LIB.T6G(SCH_1):PAGE398',
 TOLERANCE='20%',
 MATERIAL='X6S',
 PHYS_PAGE='323',
 XY='(-2350,3200)',
 ROT='0',
 VER='1',
 PACK_TYPE='0201',
 LOCATION='C265',
 CDS_LIB='pure_quanta',
 CDS_PART_NAME='Q_CAP_0201-1UF,4V,20%,X6S,CH-10KMEE00',
 VOLTAGE='4V',
 PART_NUMBER='CH-10KMEE00',
 VALUE='1UF',
 PRIM_FILE='./archive_libs/logical/q_cap/chips/chips.prt';

PART_NAME
 C266 'Q_CAP_C0201-0.1UF,10V,10%,X7S,CH4102K6E00':;

SECTION_NUMBER 1
 '@T6G_MB_LIB.T6G(SCH_1):PAGE398_I76@PURE_QUANTA.Q_CAP(CHIPS)':
 C_PATH='@t6g_mb_lib.t6g(sch_1):page398_i76@pure_quanta.q_cap(chips)',
 P_PATH='@t6g_mb_lib.t6g(sch_1):page323_i76@pure_quanta.q_cap(chips)',
 PATH='I76',
 DRAWING='@T6G_MB_LIB.T6G(SCH_1):PAGE398',
 TOLERANCE='10%',
 MATERIAL='X7S',
 PHYS_PAGE='323',
 XY='(-1675,5700)',
 ROT='0',
 VER='1',
 PACK_TYPE='C0201',
 LOCATION='C266',
 CDS_LIB='pure_quanta',
 CDS_PART_NAME='Q_CAP_C0201-0.1UF,10V,10%,X7S,CH4102K6E00',
 VOLTAGE='10V',
 PART_NUMBER='CH4102K6E00',
 VALUE='0.1UF',
 PRIM_FILE='./archive_libs/logical/q_cap/chips/chips.prt';

PART_NAME
 C267 'Q_CAP_C0402-22UF,4V,20%,X6S,CH622KMEB02':;

SECTION_NUMBER 1
 '@T6G_MB_LIB.T6G(SCH_1):PAGE68_I50@PURE_QUANTA.Q_CAP(CHIPS)':
 C_PATH='@t6g_mb_lib.t6g(sch_1):page68_i50@pure_quanta.q_cap(chips)',
 P_PATH='@t6g_mb_lib.t6g(sch_1):page69_i50@pure_quanta.q_cap(chips)',
 PATH='I50',
 DRAWING='@T6G_MB_LIB.T6G(SCH_1):PAGE68',
 TOLERANCE='20%',
 MATERIAL='X6S',
 PHYS_PAGE='69',
 XY='(-7200,5250)',
 ROT='0',
 VER='1',
 PACK_TYPE='C0402',
 LOCATION='C267',
 CDS_LIB='pure_quanta',
 CDS_PART_NAME='Q_CAP_C0402-22UF,4V,20%,X6S,CH622KMEB02',
 VOLTAGE='4V',
 PART_NUMBER='CH622KMEB02',
 VALUE='22UF',
 PRIM_FILE='./archive_libs/logical/q_cap/chips/chips.prt';

PART_NAME
 C268 'Q_CAP_C0402-22UF,4V,20%,X6S,CH622KMEB02':;

SECTION_NUMBER 1
 '@T6G_MB_LIB.T6G(SCH_1):PAGE68_I49@PURE_QUANTA.Q_CAP(CHIPS)':
 C_PATH='@t6g_mb_lib.t6g(sch_1):page68_i49@pure_quanta.q_cap(chips)',
 P_PATH='@t6g_mb_lib.t6g(sch_1):page69_i49@pure_quanta.q_cap(chips)',
 PATH='I49',
 DRAWING='@T6G_MB_LIB.T6G(SCH_1):PAGE68',
 TOLERANCE='20%',
 MATERIAL='X6S',
 PHYS_PAGE='69',
 XY='(-7200,4475)',
 ROT='0',
 VER='1',
 PACK_TYPE='C0402',
 LOCATION='C268',
 CDS_LIB='pure_quanta',
 CDS_PART_NAME='Q_CAP_C0402-22UF,4V,20%,X6S,CH622KMEB02',
 VOLTAGE='4V',
 PART_NUMBER='CH622KMEB02',
 VALUE='22UF',
 PRIM_FILE='./archive_libs/logical/q_cap/chips/chips.prt';

PART_NAME
 C269 'Q_CAP_C0402-10UF,6.3V,20%,X6S,CH6101MEB01':;

SECTION_NUMBER 1
 '@T6G_MB_LIB.T6G(SCH_1):PAGE398_I71@PURE_QUANTA.Q_CAP(CHIPS)':
 C_PATH='@t6g_mb_lib.t6g(sch_1):page398_i71@pure_quanta.q_cap(chips)',
 P_PATH='@t6g_mb_lib.t6g(sch_1):page323_i71@pure_quanta.q_cap(chips)',
 PATH='I71',
 DRAWING='@T6G_MB_LIB.T6G(SCH_1):PAGE398',
 TOLERANCE='20%',
 MATERIAL='X6S',
 PHYS_PAGE='323',
 XY='(-3525,3850)',
 ROT='0',
 VER='1',
 PACK_TYPE='C0402',
 LOCATION='C269',
 CDS_LIB='pure_quanta',
 CDS_PART_NAME='Q_CAP_C0402-10UF,6.3V,20%,X6S,CH6101MEB01',
 VOLTAGE='6.3V',
 PART_NUMBER='CH6101MEB01',
 VALUE='10UF',
 PRIM_FILE='./archive_libs/logical/q_cap/chips/chips.prt';

PART_NAME
 C270 'Q_CAP_C0402-22UF,4V,20%,X6S,CH622KMEB02':;

SECTION_NUMBER 1
 '@T6G_MB_LIB.T6G(SCH_1):PAGE68_I53@PURE_QUANTA.Q_CAP(CHIPS)':
 C_PATH='@t6g_mb_lib.t6g(sch_1):page68_i53@pure_quanta.q_cap(chips)',
 P_PATH='@t6g_mb_lib.t6g(sch_1):page69_i53@pure_quanta.q_cap(chips)',
 PATH='I53',
 DRAWING='@T6G_MB_LIB.T6G(SCH_1):PAGE68',
 TOLERANCE='20%',
 MATERIAL='X6S',
 PHYS_PAGE='69',
 XY='(-6750,5250)',
 ROT='0',
 VER='1',
 PACK_TYPE='C0402',
 LOCATION='C270',
 CDS_LIB='pure_quanta',
 CDS_PART_NAME='Q_CAP_C0402-22UF,4V,20%,X6S,CH622KMEB02',
 VOLTAGE='4V',
 PART_NUMBER='CH622KMEB02',
 VALUE='22UF',
 PRIM_FILE='./archive_libs/logical/q_cap/chips/chips.prt';

PART_NAME
 C271 'Q_CAP_C0402-22UF,4V,20%,X6S,CH622KMEB02':;

SECTION_NUMBER 1
 '@T6G_MB_LIB.T6G(SCH_1):PAGE68_I51@PURE_QUANTA.Q_CAP(CHIPS)':
 C_PATH='@t6g_mb_lib.t6g(sch_1):page68_i51@pure_quanta.q_cap(chips)',
 P_PATH='@t6g_mb_lib.t6g(sch_1):page69_i51@pure_quanta.q_cap(chips)',
 PATH='I51',
 DRAWING='@T6G_MB_LIB.T6G(SCH_1):PAGE68',
 TOLERANCE='20%',
 MATERIAL='X6S',
 PHYS_PAGE='69',
 XY='(-6750,4475)',
 ROT='0',
 VER='1',
 PACK_TYPE='C0402',
 LOCATION='C271',
 CDS_LIB='pure_quanta',
 CDS_PART_NAME='Q_CAP_C0402-22UF,4V,20%,X6S,CH622KMEB02',
 VOLTAGE='4V',
 PART_NUMBER='CH622KMEB02',
 VALUE='22UF',
 PRIM_FILE='./archive_libs/logical/q_cap/chips/chips.prt';

PART_NAME
 C272 'Q_CAP_C0402-22UF,4V,20%,X6S,CH622KMEB02':;

SECTION_NUMBER 1
 '@T6G_MB_LIB.T6G(SCH_1):PAGE68_I110@PURE_QUANTA.Q_CAP(CHIPS)':
 C_PATH='@t6g_mb_lib.t6g(sch_1):page68_i110@pure_quanta.q_cap(chips)',
 P_PATH='@t6g_mb_lib.t6g(sch_1):page69_i110@pure_quanta.q_cap(chips)',
 PATH='I110',
 DRAWING='@T6G_MB_LIB.T6G(SCH_1):PAGE68',
 TOLERANCE='20%',
 MATERIAL='X6S',
 PHYS_PAGE='69',
 XY='(-6300,5250)',
 ROT='0',
 VER='1',
 PACK_TYPE='C0402',
 LOCATION='C272',
 CDS_LIB='pure_quanta',
 CDS_PART_NAME='Q_CAP_C0402-22UF,4V,20%,X6S,CH622KMEB02',
 VOLTAGE='4V',
 PART_NUMBER='CH622KMEB02',
 VALUE='22UF',
 PRIM_FILE='./archive_libs/logical/q_cap/chips/chips.prt';

PART_NAME
 C273 'Q_CAP_C0402-22UF,4V,20%,X6S,CH622KMEB02':;

SECTION_NUMBER 1
 '@T6G_MB_LIB.T6G(SCH_1):PAGE68_I52@PURE_QUANTA.Q_CAP(CHIPS)':
 C_PATH='@t6g_mb_lib.t6g(sch_1):page68_i52@pure_quanta.q_cap(chips)',
 P_PATH='@t6g_mb_lib.t6g(sch_1):page69_i52@pure_quanta.q_cap(chips)',
 PATH='I52',
 DRAWING='@T6G_MB_LIB.T6G(SCH_1):PAGE68',
 TOLERANCE='20%',
 MATERIAL='X6S',
 PHYS_PAGE='69',
 XY='(-6300,4475)',
 ROT='0',
 VER='1',
 PACK_TYPE='C0402',
 LOCATION='C273',
 CDS_LIB='pure_quanta',
 CDS_PART_NAME='Q_CAP_C0402-22UF,4V,20%,X6S,CH622KMEB02',
 VOLTAGE='4V',
 PART_NUMBER='CH622KMEB02',
 VALUE='22UF',
 PRIM_FILE='./archive_libs/logical/q_cap/chips/chips.prt';

PART_NAME
 C274 'Q_CAP_C0402-22UF,4V,20%,X6S,CH622KMEB02':;

SECTION_NUMBER 1
 '@T6G_MB_LIB.T6G(SCH_1):PAGE68_I56@PURE_QUANTA.Q_CAP(CHIPS)':
 C_PATH='@t6g_mb_lib.t6g(sch_1):page68_i56@pure_quanta.q_cap(chips)',
 P_PATH='@t6g_mb_lib.t6g(sch_1):page69_i56@pure_quanta.q_cap(chips)',
 PATH='I56',
 DRAWING='@T6G_MB_LIB.T6G(SCH_1):PAGE68',
 TOLERANCE='20%',
 MATERIAL='X6S',
 PHYS_PAGE='69',
 XY='(-5850,5250)',
 ROT='0',
 VER='1',
 PACK_TYPE='C0402',
 LOCATION='C274',
 CDS_LIB='pure_quanta',
 CDS_PART_NAME='Q_CAP_C0402-22UF,4V,20%,X6S,CH622KMEB02',
 VOLTAGE='4V',
 PART_NUMBER='CH622KMEB02',
 VALUE='22UF',
 PRIM_FILE='./archive_libs/logical/q_cap/chips/chips.prt';

PART_NAME
 C275 'Q_CAP_C0402-22UF,4V,20%,X6S,CH622KMEB02':;

SECTION_NUMBER 1
 '@T6G_MB_LIB.T6G(SCH_1):PAGE68_I54@PURE_QUANTA.Q_CAP(CHIPS)':
 C_PATH='@t6g_mb_lib.t6g(sch_1):page68_i54@pure_quanta.q_cap(chips)',
 P_PATH='@t6g_mb_lib.t6g(sch_1):page69_i54@pure_quanta.q_cap(chips)',
 PATH='I54',
 DRAWING='@T6G_MB_LIB.T6G(SCH_1):PAGE68',
 TOLERANCE='20%',
 MATERIAL='X6S',
 PHYS_PAGE='69',
 XY='(-5850,4475)',
 ROT='0',
 VER='1',
 PACK_TYPE='C0402',
 LOCATION='C275',
 CDS_LIB='pure_quanta',
 CDS_PART_NAME='Q_CAP_C0402-22UF,4V,20%,X6S,CH622KMEB02',
 VOLTAGE='4V',
 PART_NUMBER='CH622KMEB02',
 VALUE='22UF',
 PRIM_FILE='./archive_libs/logical/q_cap/chips/chips.prt';

PART_NAME
 C276 'Q_CAP_C0402-22UF,4V,20%,X6S,CH622KMEB02':;

SECTION_NUMBER 1
 '@T6G_MB_LIB.T6G(SCH_1):PAGE68_I57@PURE_QUANTA.Q_CAP(CHIPS)':
 C_PATH='@t6g_mb_lib.t6g(sch_1):page68_i57@pure_quanta.q_cap(chips)',
 P_PATH='@t6g_mb_lib.t6g(sch_1):page69_i57@pure_quanta.q_cap(chips)',
 PATH='I57',
 DRAWING='@T6G_MB_LIB.T6G(SCH_1):PAGE68',
 TOLERANCE='20%',
 MATERIAL='X6S',
 PHYS_PAGE='69',
 XY='(-5400,5250)',
 ROT='0',
 VER='1',
 PACK_TYPE='C0402',
 LOCATION='C276',
 CDS_LIB='pure_quanta',
 CDS_PART_NAME='Q_CAP_C0402-22UF,4V,20%,X6S,CH622KMEB02',
 VOLTAGE='4V',
 PART_NUMBER='CH622KMEB02',
 VALUE='22UF',
 PRIM_FILE='./archive_libs/logical/q_cap/chips/chips.prt';

PART_NAME
 C277 'Q_CAP_C0402-22UF,4V,20%,X6S,CH622KMEB02':;

SECTION_NUMBER 1
 '@T6G_MB_LIB.T6G(SCH_1):PAGE68_I55@PURE_QUANTA.Q_CAP(CHIPS)':
 C_PATH='@t6g_mb_lib.t6g(sch_1):page68_i55@pure_quanta.q_cap(chips)',
 P_PATH='@t6g_mb_lib.t6g(sch_1):page69_i55@pure_quanta.q_cap(chips)',
 PATH='I55',
 DRAWING='@T6G_MB_LIB.T6G(SCH_1):PAGE68',
 TOLERANCE='20%',
 MATERIAL='X6S',
 PHYS_PAGE='69',
 XY='(-5400,4475)',
 ROT='0',
 VER='1',
 PACK_TYPE='C0402',
 LOCATION='C277',
 CDS_LIB='pure_quanta',
 CDS_PART_NAME='Q_CAP_C0402-22UF,4V,20%,X6S,CH622KMEB02',
 VOLTAGE='4V',
 PART_NUMBER='CH622KMEB02',
 VALUE='22UF',
 PRIM_FILE='./archive_libs/logical/q_cap/chips/chips.prt';

PART_NAME
 C278 'Q_CAP_C0402-22UF,4V,20%,X6S,CH622KMEB02':;

SECTION_NUMBER 1
 '@T6G_MB_LIB.T6G(SCH_1):PAGE68_I62@PURE_QUANTA.Q_CAP(CHIPS)':
 C_PATH='@t6g_mb_lib.t6g(sch_1):page68_i62@pure_quanta.q_cap(chips)',
 P_PATH='@t6g_mb_lib.t6g(sch_1):page69_i62@pure_quanta.q_cap(chips)',
 PATH='I62',
 DRAWING='@T6G_MB_LIB.T6G(SCH_1):PAGE68',
 TOLERANCE='20%',
 MATERIAL='X6S',
 PHYS_PAGE='69',
 XY='(-5000,5250)',
 ROT='0',
 VER='1',
 PACK_TYPE='C0402',
 LOCATION='C278',
 CDS_LIB='pure_quanta',
 CDS_PART_NAME='Q_CAP_C0402-22UF,4V,20%,X6S,CH622KMEB02',
 VOLTAGE='4V',
 PART_NUMBER='CH622KMEB02',
 VALUE='22UF',
 PRIM_FILE='./archive_libs/logical/q_cap/chips/chips.prt';

PART_NAME
 C279 'Q_CAP_C0402-22UF,4V,20%,X6S,CH622KMEB02':;

SECTION_NUMBER 1
 '@T6G_MB_LIB.T6G(SCH_1):PAGE68_I58@PURE_QUANTA.Q_CAP(CHIPS)':
 C_PATH='@t6g_mb_lib.t6g(sch_1):page68_i58@pure_quanta.q_cap(chips)',
 P_PATH='@t6g_mb_lib.t6g(sch_1):page69_i58@pure_quanta.q_cap(chips)',
 PATH='I58',
 DRAWING='@T6G_MB_LIB.T6G(SCH_1):PAGE68',
 TOLERANCE='20%',
 MATERIAL='X6S',
 PHYS_PAGE='69',
 XY='(-5000,4475)',
 ROT='0',
 VER='1',
 PACK_TYPE='C0402',
 LOCATION='C279',
 CDS_LIB='pure_quanta',
 CDS_PART_NAME='Q_CAP_C0402-22UF,4V,20%,X6S,CH622KMEB02',
 VOLTAGE='4V',
 PART_NUMBER='CH622KMEB02',
 VALUE='22UF',
 PRIM_FILE='./archive_libs/logical/q_cap/chips/chips.prt';

PART_NAME
 C280 'Q_CAP_0201-1UF,4V,20%,X6S,CH-10KMEE00':;

SECTION_NUMBER 1
 '@T6G_MB_LIB.T6G(SCH_1):PAGE398_I59@PURE_QUANTA.Q_CAP(CHIPS)':
 C_PATH='@t6g_mb_lib.t6g(sch_1):page398_i59@pure_quanta.q_cap(chips)',
 P_PATH='@t6g_mb_lib.t6g(sch_1):page323_i59@pure_quanta.q_cap(chips)',
 PATH='I59',
 DRAWING='@T6G_MB_LIB.T6G(SCH_1):PAGE398',
 TOLERANCE='20%',
 MATERIAL='X6S',
 PHYS_PAGE='323',
 XY='(-2150,3850)',
 ROT='0',
 VER='1',
 PACK_TYPE='0201',
 LOCATION='C280',
 CDS_LIB='pure_quanta',
 CDS_PART_NAME='Q_CAP_0201-1UF,4V,20%,X6S,CH-10KMEE00',
 VOLTAGE='4V',
 PART_NUMBER='CH-10KMEE00',
 VALUE='1UF',
 PRIM_FILE='./archive_libs/logical/q_cap/chips/chips.prt';

PART_NAME
 C281 'Q_CAP_C0201-0.1UF,10V,10%,X7S,CH4102K6E00':;

SECTION_NUMBER 1
 '@T6G_MB_LIB.T6G(SCH_1):PAGE398_I101@PURE_QUANTA.Q_CAP(CHIPS)':
 C_PATH='@t6g_mb_lib.t6g(sch_1):page398_i101@pure_quanta.q_cap(chips)',
 P_PATH='@t6g_mb_lib.t6g(sch_1):page323_i101@pure_quanta.q_cap(chips)',
 PATH='I101',
 DRAWING='@T6G_MB_LIB.T6G(SCH_1):PAGE398',
 TOLERANCE='10%',
 MATERIAL='X7S',
 PHYS_PAGE='323',
 XY='(-2125,3200)',
 ROT='0',
 VER='1',
 PACK_TYPE='C0201',
 LOCATION='C281',
 CDS_LIB='pure_quanta',
 CDS_PART_NAME='Q_CAP_C0201-0.1UF,10V,10%,X7S,CH4102K6E00',
 VOLTAGE='10V',
 PART_NUMBER='CH4102K6E00',
 VALUE='0.1UF',
 PRIM_FILE='./archive_libs/logical/q_cap/chips/chips.prt';

PART_NAME
 C282 'Q_CAP_C0201-0.1UF,10V,10%,X7S,CH4102K6E00':;

SECTION_NUMBER 1
 '@T6G_MB_LIB.T6G(SCH_1):PAGE398_I80@PURE_QUANTA.Q_CAP(CHIPS)':
 C_PATH='@t6g_mb_lib.t6g(sch_1):page398_i80@pure_quanta.q_cap(chips)',
 P_PATH='@t6g_mb_lib.t6g(sch_1):page323_i80@pure_quanta.q_cap(chips)',
 PATH='I80',
 DRAWING='@T6G_MB_LIB.T6G(SCH_1):PAGE398',
 TOLERANCE='10%',
 MATERIAL='X7S',
 PHYS_PAGE='323',
 XY='(-2950,2525)',
 ROT='0',
 VER='1',
 PACK_TYPE='C0201',
 LOCATION='C282',
 CDS_LIB='pure_quanta',
 CDS_PART_NAME='Q_CAP_C0201-0.1UF,10V,10%,X7S,CH4102K6E00',
 VOLTAGE='10V',
 PART_NUMBER='CH4102K6E00',
 VALUE='0.1UF',
 PRIM_FILE='./archive_libs/logical/q_cap/chips/chips.prt';

PART_NAME
 C283 'Q_CAP_C0201-0.1UF,10V,10%,X7S,CH4102K6E00':;

SECTION_NUMBER 1
 '@T6G_MB_LIB.T6G(SCH_1):PAGE398_I102@PURE_QUANTA.Q_CAP(CHIPS)':
 C_PATH='@t6g_mb_lib.t6g(sch_1):page398_i102@pure_quanta.q_cap(chips)',
 P_PATH='@t6g_mb_lib.t6g(sch_1):page323_i102@pure_quanta.q_cap(chips)',
 PATH='I102',
 DRAWING='@T6G_MB_LIB.T6G(SCH_1):PAGE398',
 TOLERANCE='10%',
 MATERIAL='X7S',
 PHYS_PAGE='323',
 XY='(-1875,3200)',
 ROT='0',
 VER='1',
 PACK_TYPE='C0201',
 LOCATION='C283',
 CDS_LIB='pure_quanta',
 CDS_PART_NAME='Q_CAP_C0201-0.1UF,10V,10%,X7S,CH4102K6E00',
 VOLTAGE='10V',
 PART_NUMBER='CH4102K6E00',
 VALUE='0.1UF',
 PRIM_FILE='./archive_libs/logical/q_cap/chips/chips.prt';

PART_NAME
 C284 'Q_CAP_C0402-22UF,4V,20%,X6S,CH622KMEB02':;

SECTION_NUMBER 1
 '@T6G_MB_LIB.T6G(SCH_1):PAGE398_I54@PURE_QUANTA.Q_CAP(CHIPS)':
 C_PATH='@t6g_mb_lib.t6g(sch_1):page398_i54@pure_quanta.q_cap(chips)',
 P_PATH='@t6g_mb_lib.t6g(sch_1):page323_i54@pure_quanta.q_cap(chips)',
 PATH='I54',
 DRAWING='@T6G_MB_LIB.T6G(SCH_1):PAGE398',
 TOLERANCE='20%',
 MATERIAL='X6S',
 PHYS_PAGE='323',
 XY='(-2825,4475)',
 ROT='0',
 VER='1',
 PACK_TYPE='C0402',
 LOCATION='C284',
 CDS_LIB='pure_quanta',
 CDS_PART_NAME='Q_CAP_C0402-22UF,4V,20%,X6S,CH622KMEB02',
 VOLTAGE='4V',
 PART_NUMBER='CH622KMEB02',
 VALUE='22UF',
 PRIM_FILE='./archive_libs/logical/q_cap/chips/chips.prt';

PART_NAME
 C285 'Q_CAP_0201-1UF,4V,20%,X6S,CH-10KMEE00':;

SECTION_NUMBER 1
 '@T6G_MB_LIB.T6G(SCH_1):PAGE398_I63@PURE_QUANTA.Q_CAP(CHIPS)':
 C_PATH='@t6g_mb_lib.t6g(sch_1):page398_i63@pure_quanta.q_cap(chips)',
 P_PATH='@t6g_mb_lib.t6g(sch_1):page323_i63@pure_quanta.q_cap(chips)',
 PATH='I63',
 DRAWING='@T6G_MB_LIB.T6G(SCH_1):PAGE398',
 TOLERANCE='20%',
 MATERIAL='X6S',
 PHYS_PAGE='323',
 XY='(-1675,3850)',
 ROT='0',
 VER='1',
 PACK_TYPE='0201',
 LOCATION='C285',
 CDS_LIB='pure_quanta',
 CDS_PART_NAME='Q_CAP_0201-1UF,4V,20%,X6S,CH-10KMEE00',
 VOLTAGE='4V',
 PART_NUMBER='CH-10KMEE00',
 VALUE='1UF',
 PRIM_FILE='./archive_libs/logical/q_cap/chips/chips.prt';

PART_NAME
 C286 'Q_CAP_C0402-10UF,6.3V,20%,X6S,CH6101MEB01':;

SECTION_NUMBER 1
 '@T6G_MB_LIB.T6G(SCH_1):PAGE398_I68@PURE_QUANTA.Q_CAP(CHIPS)':
 C_PATH='@t6g_mb_lib.t6g(sch_1):page398_i68@pure_quanta.q_cap(chips)',
 P_PATH='@t6g_mb_lib.t6g(sch_1):page323_i68@pure_quanta.q_cap(chips)',
 PATH='I68',
 DRAWING='@T6G_MB_LIB.T6G(SCH_1):PAGE398',
 TOLERANCE='20%',
 MATERIAL='X6S',
 PHYS_PAGE='323',
 XY='(-1550,4475)',
 ROT='0',
 VER='1',
 PACK_TYPE='C0402',
 LOCATION='C286',
 CDS_LIB='pure_quanta',
 CDS_PART_NAME='Q_CAP_C0402-10UF,6.3V,20%,X6S,CH6101MEB01',
 VOLTAGE='6.3V',
 PART_NUMBER='CH6101MEB01',
 VALUE='10UF',
 PRIM_FILE='./archive_libs/logical/q_cap/chips/chips.prt';

PART_NAME
 C287 'Q_CAP_C0201-0.1UF,10V,10%,X7S,CH4102K6E00':;

SECTION_NUMBER 1
 '@T6G_MB_LIB.T6G(SCH_1):PAGE443_I28@PURE_QUANTA.Q_CAP(CHIPS)':
 C_PATH='@t6g_mb_lib.t6g(sch_1):page443_i28@pure_quanta.q_cap(chips)',
 P_PATH='@t6g_mb_lib.t6g(sch_1):page334_i28@pure_quanta.q_cap(chips)',
 PATH='I28',
 DRAWING='@T6G_MB_LIB.T6G(SCH_1):PAGE443',
 TOLERANCE='10%',
 MATERIAL='X7S',
 PHYS_PAGE='334',
 XY='(-5450,4000)',
 ROT='0',
 VER='1',
 PACK_TYPE='C0201',
 LOCATION='C287',
 CDS_LIB='pure_quanta',
 CDS_PART_NAME='Q_CAP_C0201-0.1UF,10V,10%,X7S,CH4102K6E00',
 VOLTAGE='10V',
 PART_NUMBER='CH4102K6E00',
 VALUE='0.1UF',
 PRIM_FILE='./archive_libs/logical/q_cap/chips/chips.prt';

PART_NAME
 C288 'Q_CAP_C0201-0.1UF,10V,10%,X7S,CH4102K6E00':;

SECTION_NUMBER 1
 '@T6G_MB_LIB.T6G(SCH_1):PAGE443_I29@PURE_QUANTA.Q_CAP(CHIPS)':
 C_PATH='@t6g_mb_lib.t6g(sch_1):page443_i29@pure_quanta.q_cap(chips)',
 P_PATH='@t6g_mb_lib.t6g(sch_1):page334_i29@pure_quanta.q_cap(chips)',
 PATH='I29',
 DRAWING='@T6G_MB_LIB.T6G(SCH_1):PAGE443',
 TOLERANCE='10%',
 MATERIAL='X7S',
 PHYS_PAGE='334',
 XY='(-5175,4000)',
 ROT='0',
 VER='1',
 PACK_TYPE='C0201',
 LOCATION='C288',
 CDS_LIB='pure_quanta',
 CDS_PART_NAME='Q_CAP_C0201-0.1UF,10V,10%,X7S,CH4102K6E00',
 VOLTAGE='10V',
 PART_NUMBER='CH4102K6E00',
 VALUE='0.1UF',
 PRIM_FILE='./archive_libs/logical/q_cap/chips/chips.prt';

PART_NAME
 C289 'Q_CAP_0201-1UF,4V,20%,X6S,CH-10KMEE00':;

SECTION_NUMBER 1
 '@T6G_MB_LIB.T6G(SCH_1):PAGE443_I65@PURE_QUANTA.Q_CAP(CHIPS)':
 C_PATH='@t6g_mb_lib.t6g(sch_1):page443_i65@pure_quanta.q_cap(chips)',
 P_PATH='@t6g_mb_lib.t6g(sch_1):page334_i65@pure_quanta.q_cap(chips)',
 PATH='I65',
 DRAWING='@T6G_MB_LIB.T6G(SCH_1):PAGE443',
 TOLERANCE='20%',
 MATERIAL='X6S',
 PHYS_PAGE='334',
 XY='(-1675,3375)',
 ROT='0',
 VER='1',
 PACK_TYPE='0201',
 LOCATION='C289',
 CDS_LIB='pure_quanta',
 CDS_PART_NAME='Q_CAP_0201-1UF,4V,20%,X6S,CH-10KMEE00',
 VOLTAGE='4V',
 PART_NUMBER='CH-10KMEE00',
 VALUE='1UF',
 PRIM_FILE='./archive_libs/logical/q_cap/chips/chips.prt';

PART_NAME
 C290 'Q_CAP_C0201-0.1UF,10V,10%,X7S,CH4102K6E00':;

SECTION_NUMBER 1
 '@T6G_MB_LIB.T6G(SCH_1):PAGE443_I86@PURE_QUANTA.Q_CAP(CHIPS)':
 C_PATH='@t6g_mb_lib.t6g(sch_1):page443_i86@pure_quanta.q_cap(chips)',
 P_PATH='@t6g_mb_lib.t6g(sch_1):page334_i86@pure_quanta.q_cap(chips)',
 PATH='I86',
 DRAWING='@T6G_MB_LIB.T6G(SCH_1):PAGE443',
 TOLERANCE='10%',
 MATERIAL='X7S',
 PHYS_PAGE='334',
 XY='(-1950,5225)',
 ROT='0',
 VER='1',
 PACK_TYPE='C0201',
 LOCATION='C290',
 CDS_LIB='pure_quanta',
 CDS_PART_NAME='Q_CAP_C0201-0.1UF,10V,10%,X7S,CH4102K6E00',
 VOLTAGE='10V',
 PART_NUMBER='CH4102K6E00',
 VALUE='0.1UF',
 PRIM_FILE='./archive_libs/logical/q_cap/chips/chips.prt';

PART_NAME
 C291 'Q_CAP_C0201-0.1UF,10V,10%,X7S,CH4102K6E00':;

SECTION_NUMBER 1
 '@T6G_MB_LIB.T6G(SCH_1):PAGE443_I50@PURE_QUANTA.Q_CAP(CHIPS)':
 C_PATH='@t6g_mb_lib.t6g(sch_1):page443_i50@pure_quanta.q_cap(chips)',
 P_PATH='@t6g_mb_lib.t6g(sch_1):page334_i50@pure_quanta.q_cap(chips)',
 PATH='I50',
 DRAWING='@T6G_MB_LIB.T6G(SCH_1):PAGE443',
 TOLERANCE='10%',
 MATERIAL='X7S',
 PHYS_PAGE='334',
 XY='(-2200,2050)',
 ROT='0',
 VER='1',
 PACK_TYPE='C0201',
 LOCATION='C291',
 CDS_LIB='pure_quanta',
 CDS_PART_NAME='Q_CAP_C0201-0.1UF,10V,10%,X7S,CH4102K6E00',
 VOLTAGE='10V',
 PART_NUMBER='CH4102K6E00',
 VALUE='0.1UF',
 PRIM_FILE='./archive_libs/logical/q_cap/chips/chips.prt';

PART_NAME
 C292 'Q_CAP_C0201-0.1UF,10V,10%,X7S,CH4102K6E00':;

SECTION_NUMBER 1
 '@T6G_MB_LIB.T6G(SCH_1):PAGE443_I85@PURE_QUANTA.Q_CAP(CHIPS)':
 C_PATH='@t6g_mb_lib.t6g(sch_1):page443_i85@pure_quanta.q_cap(chips)',
 P_PATH='@t6g_mb_lib.t6g(sch_1):page334_i85@pure_quanta.q_cap(chips)',
 PATH='I85',
 DRAWING='@T6G_MB_LIB.T6G(SCH_1):PAGE443',
 TOLERANCE='10%',
 MATERIAL='X7S',
 PHYS_PAGE='334',
 XY='(-1675,5225)',
 ROT='0',
 VER='1',
 PACK_TYPE='C0201',
 LOCATION='C292',
 CDS_LIB='pure_quanta',
 CDS_PART_NAME='Q_CAP_C0201-0.1UF,10V,10%,X7S,CH4102K6E00',
 VOLTAGE='10V',
 PART_NUMBER='CH4102K6E00',
 VALUE='0.1UF',
 PRIM_FILE='./archive_libs/logical/q_cap/chips/chips.prt';

PART_NAME
 C293 'Q_CAP_0201-1UF,4V,20%,X6S,CH-10KMEE00':;

SECTION_NUMBER 1
 '@T6G_MB_LIB.T6G(SCH_1):PAGE443_I58@PURE_QUANTA.Q_CAP(CHIPS)':
 C_PATH='@t6g_mb_lib.t6g(sch_1):page443_i58@pure_quanta.q_cap(chips)',
 P_PATH='@t6g_mb_lib.t6g(sch_1):page334_i58@pure_quanta.q_cap(chips)',
 PATH='I58',
 DRAWING='@T6G_MB_LIB.T6G(SCH_1):PAGE443',
 TOLERANCE='20%',
 MATERIAL='X6S',
 PHYS_PAGE='334',
 XY='(-2125,3375)',
 ROT='0',
 VER='1',
 PACK_TYPE='0201',
 LOCATION='C293',
 CDS_LIB='pure_quanta',
 CDS_PART_NAME='Q_CAP_0201-1UF,4V,20%,X6S,CH-10KMEE00',
 VOLTAGE='4V',
 PART_NUMBER='CH-10KMEE00',
 VALUE='1UF',
 PRIM_FILE='./archive_libs/logical/q_cap/chips/chips.prt';

PART_NAME
 C294 'Q_CAP_0201-1UF,4V,20%,X6S,CH-10KMEE00':;

SECTION_NUMBER 1
 '@T6G_MB_LIB.T6G(SCH_1):PAGE443_I40@PURE_QUANTA.Q_CAP(CHIPS)':
 C_PATH='@t6g_mb_lib.t6g(sch_1):page443_i40@pure_quanta.q_cap(chips)',
 P_PATH='@t6g_mb_lib.t6g(sch_1):page334_i40@pure_quanta.q_cap(chips)',
 PATH='I40',
 DRAWING='@T6G_MB_LIB.T6G(SCH_1):PAGE443',
 TOLERANCE='20%',
 MATERIAL='X6S',
 PHYS_PAGE='334',
 XY='(-3500,2750)',
 ROT='0',
 VER='1',
 PACK_TYPE='0201',
 LOCATION='C294',
 CDS_LIB='pure_quanta',
 CDS_PART_NAME='Q_CAP_0201-1UF,4V,20%,X6S,CH-10KMEE00',
 VOLTAGE='4V',
 PART_NUMBER='CH-10KMEE00',
 VALUE='1UF',
 PRIM_FILE='./archive_libs/logical/q_cap/chips/chips.prt';

PART_NAME
 C295 'Q_CAP_0402-10PF,50V,5%,EMPTY,CH01006JB08':;

SECTION_NUMBER 1
 '@T6G_MB_LIB.T6G(SCH_1):PAGE185_I62@PURE_QUANTA.Q_CAP(CHIPS)':
 C_PATH='@t6g_mb_lib.t6g(sch_1):page185_i62@pure_quanta.q_cap(chips)',
 P_PATH='@t6g_mb_lib.t6g(sch_1):page210_i62@pure_quanta.q_cap(chips)',
 PATH='I62',
 DRAWING='@T6G_MB_LIB.T6G(SCH_1):PAGE185',
 TOLERANCE='5%',
 MATERIAL='EMPTY',
 PHYS_PAGE='210',
 XY='(-4825,6800)',
 ROT='0',
 VER='1',
 PACK_TYPE='0402',
 LOCATION='C295',
 CDS_LIB='pure_quanta',
 CDS_PART_NAME='Q_CAP_0402-10PF,50V,5%,EMPTY,CH01006JB08',
 VOLTAGE='50V',
 PART_NUMBER='CH01006JB08',
 VALUE='10PF',
 PRIM_FILE='./archive_libs/logical/q_cap/chips/chips.prt';

PART_NAME
 C296 'Q_CAP_0402-10PF,50V,5%,EMPTY,CH01006JB08':;

SECTION_NUMBER 1
 '@T6G_MB_LIB.T6G(SCH_1):PAGE185_I64@PURE_QUANTA.Q_CAP(CHIPS)':
 C_PATH='@t6g_mb_lib.t6g(sch_1):page185_i64@pure_quanta.q_cap(chips)',
 P_PATH='@t6g_mb_lib.t6g(sch_1):page210_i64@pure_quanta.q_cap(chips)',
 PATH='I64',
 DRAWING='@T6G_MB_LIB.T6G(SCH_1):PAGE185',
 TOLERANCE='5%',
 MATERIAL='EMPTY',
 PHYS_PAGE='210',
 XY='(-4600,6800)',
 ROT='0',
 VER='1',
 PACK_TYPE='0402',
 LOCATION='C296',
 CDS_LIB='pure_quanta',
 CDS_PART_NAME='Q_CAP_0402-10PF,50V,5%,EMPTY,CH01006JB08',
 VOLTAGE='50V',
 PART_NUMBER='CH01006JB08',
 VALUE='10PF',
 PRIM_FILE='./archive_libs/logical/q_cap/chips/chips.prt';

PART_NAME
 C297 'Q_CAP_0402-10PF,50V,5%,EMPTY,CH01006JB08':;

SECTION_NUMBER 1
 '@T6G_MB_LIB.T6G(SCH_1):PAGE185_I66@PURE_QUANTA.Q_CAP(CHIPS)':
 C_PATH='@t6g_mb_lib.t6g(sch_1):page185_i66@pure_quanta.q_cap(chips)',
 P_PATH='@t6g_mb_lib.t6g(sch_1):page210_i66@pure_quanta.q_cap(chips)',
 PATH='I66',
 DRAWING='@T6G_MB_LIB.T6G(SCH_1):PAGE185',
 TOLERANCE='5%',
 MATERIAL='EMPTY',
 PHYS_PAGE='210',
 XY='(-4325,6800)',
 ROT='0',
 VER='1',
 PACK_TYPE='0402',
 LOCATION='C297',
 CDS_LIB='pure_quanta',
 CDS_PART_NAME='Q_CAP_0402-10PF,50V,5%,EMPTY,CH01006JB08',
 VOLTAGE='50V',
 PART_NUMBER='CH01006JB08',
 VALUE='10PF',
 PRIM_FILE='./archive_libs/logical/q_cap/chips/chips.prt';

PART_NAME
 C298 'Q_CAP_0402-10PF,50V,5%,EMPTY,CH01006JB08':;

SECTION_NUMBER 1
 '@T6G_MB_LIB.T6G(SCH_1):PAGE168_I64@PURE_QUANTA.Q_CAP(CHIPS)':
 C_PATH='@t6g_mb_lib.t6g(sch_1):page168_i64@pure_quanta.q_cap(chips)',
 P_PATH='@t6g_mb_lib.t6g(sch_1):page193_i64@pure_quanta.q_cap(chips)',
 PATH='I64',
 DRAWING='@T6G_MB_LIB.T6G(SCH_1):PAGE168',
 TOLERANCE='5%',
 MATERIAL='EMPTY',
 PHYS_PAGE='193',
 XY='(-7625,5425)',
 ROT='0',
 VER='1',
 PACK_TYPE='0402',
 LOCATION='C298',
 CDS_LIB='pure_quanta',
 CDS_PART_NAME='Q_CAP_0402-10PF,50V,5%,EMPTY,CH01006JB08',
 VOLTAGE='50V',
 PART_NUMBER='CH01006JB08',
 VALUE='10PF',
 PRIM_FILE='./archive_libs/logical/q_cap/chips/chips.prt';

PART_NAME
 C299 'Q_CAP_0402-10PF,50V,5%,EMPTY,CH01006JB08':;

SECTION_NUMBER 1
 '@T6G_MB_LIB.T6G(SCH_1):PAGE168_I66@PURE_QUANTA.Q_CAP(CHIPS)':
 C_PATH='@t6g_mb_lib.t6g(sch_1):page168_i66@pure_quanta.q_cap(chips)',
 P_PATH='@t6g_mb_lib.t6g(sch_1):page193_i66@pure_quanta.q_cap(chips)',
 PATH='I66',
 DRAWING='@T6G_MB_LIB.T6G(SCH_1):PAGE168',
 TOLERANCE='5%',
 MATERIAL='EMPTY',
 PHYS_PAGE='193',
 XY='(-7400,5425)',
 ROT='0',
 VER='1',
 PACK_TYPE='0402',
 LOCATION='C299',
 CDS_LIB='pure_quanta',
 CDS_PART_NAME='Q_CAP_0402-10PF,50V,5%,EMPTY,CH01006JB08',
 VOLTAGE='50V',
 PART_NUMBER='CH01006JB08',
 VALUE='10PF',
 PRIM_FILE='./archive_libs/logical/q_cap/chips/chips.prt';

PART_NAME
 C300 'Q_CAP_C0201-0.1UF,10V,10%,X7S,CH4102K6E00':;

SECTION_NUMBER 1
 '@T6G_MB_LIB.T6G(SCH_1):PAGE443_I82@PURE_QUANTA.Q_CAP(CHIPS)':
 C_PATH='@t6g_mb_lib.t6g(sch_1):page443_i82@pure_quanta.q_cap(chips)',
 P_PATH='@t6g_mb_lib.t6g(sch_1):page334_i82@pure_quanta.q_cap(chips)',
 PATH='I82',
 DRAWING='@T6G_MB_LIB.T6G(SCH_1):PAGE443',
 TOLERANCE='10%',
 MATERIAL='X7S',
 PHYS_PAGE='334',
 XY='(-1425,5225)',
 ROT='0',
 VER='1',
 PACK_TYPE='C0201',
 LOCATION='C300',
 CDS_LIB='pure_quanta',
 CDS_PART_NAME='Q_CAP_C0201-0.1UF,10V,10%,X7S,CH4102K6E00',
 VOLTAGE='10V',
 PART_NUMBER='CH4102K6E00',
 VALUE='0.1UF',
 PRIM_FILE='./archive_libs/logical/q_cap/chips/chips.prt';

PART_NAME
 C301 'Q_CAP_0201-1UF,4V,20%,X6S,CH-10KMEE00':;

SECTION_NUMBER 1
 '@T6G_MB_LIB.T6G(SCH_1):PAGE443_I59@PURE_QUANTA.Q_CAP(CHIPS)':
 C_PATH='@t6g_mb_lib.t6g(sch_1):page443_i59@pure_quanta.q_cap(chips)',
 P_PATH='@t6g_mb_lib.t6g(sch_1):page334_i59@pure_quanta.q_cap(chips)',
 PATH='I59',
 DRAWING='@T6G_MB_LIB.T6G(SCH_1):PAGE443',
 TOLERANCE='20%',
 MATERIAL='X6S',
 PHYS_PAGE='334',
 XY='(-1900,3375)',
 ROT='0',
 VER='1',
 PACK_TYPE='0201',
 LOCATION='C301',
 CDS_LIB='pure_quanta',
 CDS_PART_NAME='Q_CAP_0201-1UF,4V,20%,X6S,CH-10KMEE00',
 VOLTAGE='4V',
 PART_NUMBER='CH-10KMEE00',
 VALUE='1UF',
 PRIM_FILE='./archive_libs/logical/q_cap/chips/chips.prt';

PART_NAME
 C302 'Q_CAP_0402-10PF,50V,5%,EMPTY,CH01006JB08':;

SECTION_NUMBER 1
 '@T6G_MB_LIB.T6G(SCH_1):PAGE168_I68@PURE_QUANTA.Q_CAP(CHIPS)':
 C_PATH='@t6g_mb_lib.t6g(sch_1):page168_i68@pure_quanta.q_cap(chips)',
 P_PATH='@t6g_mb_lib.t6g(sch_1):page193_i68@pure_quanta.q_cap(chips)',
 PATH='I68',
 DRAWING='@T6G_MB_LIB.T6G(SCH_1):PAGE168',
 TOLERANCE='5%',
 MATERIAL='EMPTY',
 PHYS_PAGE='193',
 XY='(-7175,5425)',
 ROT='0',
 VER='1',
 PACK_TYPE='0402',
 LOCATION='C302',
 CDS_LIB='pure_quanta',
 CDS_PART_NAME='Q_CAP_0402-10PF,50V,5%,EMPTY,CH01006JB08',
 VOLTAGE='50V',
 PART_NUMBER='CH01006JB08',
 VALUE='10PF',
 PRIM_FILE='./archive_libs/logical/q_cap/chips/chips.prt';

PART_NAME
 C303 'Q_CAP_0402-10PF,50V,5%,EMPTY,CH01006JB08':;

SECTION_NUMBER 1
 '@T6G_MB_LIB.T6G(SCH_1):PAGE175_I33@PURE_QUANTA.Q_CAP(CHIPS)':
 C_PATH='@t6g_mb_lib.t6g(sch_1):page175_i33@pure_quanta.q_cap(chips)',
 P_PATH='@t6g_mb_lib.t6g(sch_1):page200_i33@pure_quanta.q_cap(chips)',
 PATH='I33',
 DRAWING='@T6G_MB_LIB.T6G(SCH_1):PAGE175',
 TOLERANCE='5%',
 MATERIAL='EMPTY',
 PHYS_PAGE='200',
 XY='(-8250,5200)',
 ROT='0',
 VER='1',
 PACK_TYPE='0402',
 LOCATION='C303',
 CDS_LIB='pure_quanta',
 CDS_PART_NAME='Q_CAP_0402-10PF,50V,5%,EMPTY,CH01006JB08',
 VOLTAGE='50V',
 PART_NUMBER='CH01006JB08',
 VALUE='10PF',
 PRIM_FILE='./archive_libs/logical/q_cap/chips/chips.prt';

PART_NAME
 C304 'Q_CAP_0402-10PF,50V,5%,EMPTY,CH01006JB08':;

SECTION_NUMBER 1
 '@T6G_MB_LIB.T6G(SCH_1):PAGE175_I34@PURE_QUANTA.Q_CAP(CHIPS)':
 C_PATH='@t6g_mb_lib.t6g(sch_1):page175_i34@pure_quanta.q_cap(chips)',
 P_PATH='@t6g_mb_lib.t6g(sch_1):page200_i34@pure_quanta.q_cap(chips)',
 PATH='I34',
 DRAWING='@T6G_MB_LIB.T6G(SCH_1):PAGE175',
 TOLERANCE='5%',
 MATERIAL='EMPTY',
 PHYS_PAGE='200',
 XY='(-8075,5200)',
 ROT='0',
 VER='1',
 PACK_TYPE='0402',
 LOCATION='C304',
 CDS_LIB='pure_quanta',
 CDS_PART_NAME='Q_CAP_0402-10PF,50V,5%,EMPTY,CH01006JB08',
 VOLTAGE='50V',
 PART_NUMBER='CH01006JB08',
 VALUE='10PF',
 PRIM_FILE='./archive_libs/logical/q_cap/chips/chips.prt';

PART_NAME
 C305 'Q_CAP_0402-10PF,50V,5%,EMPTY,CH01006JB08':;

SECTION_NUMBER 1
 '@T6G_MB_LIB.T6G(SCH_1):PAGE175_I35@PURE_QUANTA.Q_CAP(CHIPS)':
 C_PATH='@t6g_mb_lib.t6g(sch_1):page175_i35@pure_quanta.q_cap(chips)',
 P_PATH='@t6g_mb_lib.t6g(sch_1):page200_i35@pure_quanta.q_cap(chips)',
 PATH='I35',
 DRAWING='@T6G_MB_LIB.T6G(SCH_1):PAGE175',
 TOLERANCE='5%',
 MATERIAL='EMPTY',
 PHYS_PAGE='200',
 XY='(-7825,5200)',
 ROT='0',
 VER='1',
 PACK_TYPE='0402',
 LOCATION='C305',
 CDS_LIB='pure_quanta',
 CDS_PART_NAME='Q_CAP_0402-10PF,50V,5%,EMPTY,CH01006JB08',
 VOLTAGE='50V',
 PART_NUMBER='CH01006JB08',
 VALUE='10PF',
 PRIM_FILE='./archive_libs/logical/q_cap/chips/chips.prt';

PART_NAME
 C306 'Q_CAP_0201-1UF,4V,20%,X6S,CH-10KMEE00':;

SECTION_NUMBER 1
 '@T6G_MB_LIB.T6G(SCH_1):PAGE443_I90@PURE_QUANTA.Q_CAP(CHIPS)':
 C_PATH='@t6g_mb_lib.t6g(sch_1):page443_i90@pure_quanta.q_cap(chips)',
 P_PATH='@t6g_mb_lib.t6g(sch_1):page334_i90@pure_quanta.q_cap(chips)',
 PATH='I90',
 DRAWING='@T6G_MB_LIB.T6G(SCH_1):PAGE443',
 TOLERANCE='20%',
 MATERIAL='X6S',
 PHYS_PAGE='334',
 XY='(-3050,950)',
 ROT='0',
 VER='1',
 PACK_TYPE='0201',
 LOCATION='C306',
 CDS_LIB='pure_quanta',
 CDS_PART_NAME='Q_CAP_0201-1UF,4V,20%,X6S,CH-10KMEE00',
 VOLTAGE='4V',
 PART_NUMBER='CH-10KMEE00',
 VALUE='1UF',
 PRIM_FILE='./archive_libs/logical/q_cap/chips/chips.prt';

PART_NAME
 C307 'Q_CAP_0201-1UF,4V,20%,X6S,CH-10KMEE00':;

SECTION_NUMBER 1
 '@T6G_MB_LIB.T6G(SCH_1):PAGE443_I42@PURE_QUANTA.Q_CAP(CHIPS)':
 C_PATH='@t6g_mb_lib.t6g(sch_1):page443_i42@pure_quanta.q_cap(chips)',
 P_PATH='@t6g_mb_lib.t6g(sch_1):page334_i42@pure_quanta.q_cap(chips)',
 PATH='I42',
 DRAWING='@T6G_MB_LIB.T6G(SCH_1):PAGE443',
 TOLERANCE='20%',
 MATERIAL='X6S',
 PHYS_PAGE='334',
 XY='(-3275,2750)',
 ROT='0',
 VER='1',
 PACK_TYPE='0201',
 LOCATION='C307',
 CDS_LIB='pure_quanta',
 CDS_PART_NAME='Q_CAP_0201-1UF,4V,20%,X6S,CH-10KMEE00',
 VOLTAGE='4V',
 PART_NUMBER='CH-10KMEE00',
 VALUE='1UF',
 PRIM_FILE='./archive_libs/logical/q_cap/chips/chips.prt';

PART_NAME
 C308 'Q_CAP_0402-10PF,50V,5%,EMPTY,CH01006JB08':;

SECTION_NUMBER 1
 '@T6G_MB_LIB.T6G(SCH_1):PAGE192_I31@PURE_QUANTA.Q_CAP(CHIPS)':
 C_PATH='@t6g_mb_lib.t6g(sch_1):page192_i31@pure_quanta.q_cap(chips)',
 P_PATH='@t6g_mb_lib.t6g(sch_1):page217_i31@pure_quanta.q_cap(chips)',
 PATH='I31',
 DRAWING='@T6G_MB_LIB.T6G(SCH_1):PAGE192',
 TOLERANCE='5%',
 MATERIAL='EMPTY',
 PHYS_PAGE='217',
 XY='(-4650,6100)',
 ROT='0',
 VER='1',
 PACK_TYPE='0402',
 LOCATION='C308',
 CDS_LIB='pure_quanta',
 CDS_PART_NAME='Q_CAP_0402-10PF,50V,5%,EMPTY,CH01006JB08',
 VOLTAGE='50V',
 PART_NUMBER='CH01006JB08',
 VALUE='10PF',
 PRIM_FILE='./archive_libs/logical/q_cap/chips/chips.prt';

PART_NAME
 C309 'Q_CAP_0402-10PF,50V,5%,EMPTY,CH01006JB08':;

SECTION_NUMBER 1
 '@T6G_MB_LIB.T6G(SCH_1):PAGE192_I32@PURE_QUANTA.Q_CAP(CHIPS)':
 C_PATH='@t6g_mb_lib.t6g(sch_1):page192_i32@pure_quanta.q_cap(chips)',
 P_PATH='@t6g_mb_lib.t6g(sch_1):page217_i32@pure_quanta.q_cap(chips)',
 PATH='I32',
 DRAWING='@T6G_MB_LIB.T6G(SCH_1):PAGE192',
 TOLERANCE='5%',
 MATERIAL='EMPTY',
 PHYS_PAGE='217',
 XY='(-4450,6125)',
 ROT='0',
 VER='1',
 PACK_TYPE='0402',
 LOCATION='C309',
 CDS_LIB='pure_quanta',
 CDS_PART_NAME='Q_CAP_0402-10PF,50V,5%,EMPTY,CH01006JB08',
 VOLTAGE='50V',
 PART_NUMBER='CH01006JB08',
 VALUE='10PF',
 PRIM_FILE='./archive_libs/logical/q_cap/chips/chips.prt';

PART_NAME
 C310 'Q_CAP_0402-10PF,50V,5%,EMPTY,CH01006JB08':;

SECTION_NUMBER 1
 '@T6G_MB_LIB.T6G(SCH_1):PAGE192_I33@PURE_QUANTA.Q_CAP(CHIPS)':
 C_PATH='@t6g_mb_lib.t6g(sch_1):page192_i33@pure_quanta.q_cap(chips)',
 P_PATH='@t6g_mb_lib.t6g(sch_1):page217_i33@pure_quanta.q_cap(chips)',
 PATH='I33',
 DRAWING='@T6G_MB_LIB.T6G(SCH_1):PAGE192',
 TOLERANCE='5%',
 MATERIAL='EMPTY',
 PHYS_PAGE='217',
 XY='(-4250,6125)',
 ROT='0',
 VER='1',
 PACK_TYPE='0402',
 LOCATION='C310',
 CDS_LIB='pure_quanta',
 CDS_PART_NAME='Q_CAP_0402-10PF,50V,5%,EMPTY,CH01006JB08',
 VOLTAGE='50V',
 PART_NUMBER='CH01006JB08',
 VALUE='10PF',
 PRIM_FILE='./archive_libs/logical/q_cap/chips/chips.prt';

PART_NAME
 C311 'Q_CAP_C0201-0.1UF,10V,10%,X7S,CH4102K6E00':;

SECTION_NUMBER 1
 '@T6G_MB_LIB.T6G(SCH_1):PAGE443_I84@PURE_QUANTA.Q_CAP(CHIPS)':
 C_PATH='@t6g_mb_lib.t6g(sch_1):page443_i84@pure_quanta.q_cap(chips)',
 P_PATH='@t6g_mb_lib.t6g(sch_1):page334_i84@pure_quanta.q_cap(chips)',
 PATH='I84',
 DRAWING='@T6G_MB_LIB.T6G(SCH_1):PAGE443',
 TOLERANCE='10%',
 MATERIAL='X7S',
 PHYS_PAGE='334',
 XY='(-1150,5225)',
 ROT='0',
 VER='1',
 PACK_TYPE='C0201',
 LOCATION='C311',
 CDS_LIB='pure_quanta',
 CDS_PART_NAME='Q_CAP_C0201-0.1UF,10V,10%,X7S,CH4102K6E00',
 VOLTAGE='10V',
 PART_NUMBER='CH4102K6E00',
 VALUE='0.1UF',
 PRIM_FILE='./archive_libs/logical/q_cap/chips/chips.prt';

PART_NAME
 C312 'Q_CAP_C0201-0.1UF,10V,10%,X7S,CH4102K6E00':;

SECTION_NUMBER 1
 '@T6G_MB_LIB.T6G(SCH_1):PAGE443_I48@PURE_QUANTA.Q_CAP(CHIPS)':
 C_PATH='@t6g_mb_lib.t6g(sch_1):page443_i48@pure_quanta.q_cap(chips)',
 P_PATH='@t6g_mb_lib.t6g(sch_1):page334_i48@pure_quanta.q_cap(chips)',
 PATH='I48',
 DRAWING='@T6G_MB_LIB.T6G(SCH_1):PAGE443',
 TOLERANCE='10%',
 MATERIAL='X7S',
 PHYS_PAGE='334',
 XY='(-2700,2050)',
 ROT='0',
 VER='1',
 PACK_TYPE='C0201',
 LOCATION='C312',
 CDS_LIB='pure_quanta',
 CDS_PART_NAME='Q_CAP_C0201-0.1UF,10V,10%,X7S,CH4102K6E00',
 VOLTAGE='10V',
 PART_NUMBER='CH4102K6E00',
 VALUE='0.1UF',
 PRIM_FILE='./archive_libs/logical/q_cap/chips/chips.prt';

PART_NAME
 C313 'Q_CAP_C0201-0.1UF,10V,10%,X7S,CH4102K6E00':;

SECTION_NUMBER 1
 '@T6G_MB_LIB.T6G(SCH_1):PAGE443_I34@PURE_QUANTA.Q_CAP(CHIPS)':
 C_PATH='@t6g_mb_lib.t6g(sch_1):page443_i34@pure_quanta.q_cap(chips)',
 P_PATH='@t6g_mb_lib.t6g(sch_1):page334_i34@pure_quanta.q_cap(chips)',
 PATH='I34',
 DRAWING='@T6G_MB_LIB.T6G(SCH_1):PAGE443',
 TOLERANCE='10%',
 MATERIAL='X7S',
 PHYS_PAGE='334',
 XY='(-2800,950)',
 ROT='0',
 VER='1',
 PACK_TYPE='C0201',
 LOCATION='C313',
 CDS_LIB='pure_quanta',
 CDS_PART_NAME='Q_CAP_C0201-0.1UF,10V,10%,X7S,CH4102K6E00',
 VOLTAGE='10V',
 PART_NUMBER='CH4102K6E00',
 VALUE='0.1UF',
 PRIM_FILE='./archive_libs/logical/q_cap/chips/chips.prt';

PART_NAME
 C314 'Q_CAP_0201-1UF,4V,20%,X6S,CH-10KMEE00':;

SECTION_NUMBER 1
 '@T6G_MB_LIB.T6G(SCH_1):PAGE443_I52@PURE_QUANTA.Q_CAP(CHIPS)':
 C_PATH='@t6g_mb_lib.t6g(sch_1):page443_i52@pure_quanta.q_cap(chips)',
 P_PATH='@t6g_mb_lib.t6g(sch_1):page334_i52@pure_quanta.q_cap(chips)',
 PATH='I52',
 DRAWING='@T6G_MB_LIB.T6G(SCH_1):PAGE443',
 TOLERANCE='20%',
 MATERIAL='X6S',
 PHYS_PAGE='334',
 XY='(-2550,2750)',
 ROT='0',
 VER='1',
 PACK_TYPE='0201',
 LOCATION='C314',
 CDS_LIB='pure_quanta',
 CDS_PART_NAME='Q_CAP_0201-1UF,4V,20%,X6S,CH-10KMEE00',
 VOLTAGE='4V',
 PART_NUMBER='CH-10KMEE00',
 VALUE='1UF',
 PRIM_FILE='./archive_libs/logical/q_cap/chips/chips.prt';

PART_NAME
 C315 'Q_CAP_0201-1UF,4V,20%,X6S,CH-10KMEE00':;

SECTION_NUMBER 1
 '@T6G_MB_LIB.T6G(SCH_1):PAGE443_I91@PURE_QUANTA.Q_CAP(CHIPS)':
 C_PATH='@t6g_mb_lib.t6g(sch_1):page443_i91@pure_quanta.q_cap(chips)',
 P_PATH='@t6g_mb_lib.t6g(sch_1):page334_i91@pure_quanta.q_cap(chips)',
 PATH='I91',
 DRAWING='@T6G_MB_LIB.T6G(SCH_1):PAGE443',
 TOLERANCE='20%',
 MATERIAL='X6S',
 PHYS_PAGE='334',
 XY='(-2500,950)',
 ROT='0',
 VER='1',
 PACK_TYPE='0201',
 LOCATION='C315',
 CDS_LIB='pure_quanta',
 CDS_PART_NAME='Q_CAP_0201-1UF,4V,20%,X6S,CH-10KMEE00',
 VOLTAGE='4V',
 PART_NUMBER='CH-10KMEE00',
 VALUE='1UF',
 PRIM_FILE='./archive_libs/logical/q_cap/chips/chips.prt';

PART_NAME
 C316 'Q_CAP_C0201-0.1UF,10V,10%,X7S,CH4102K6E00':;

SECTION_NUMBER 1
 '@T6G_MB_LIB.T6G(SCH_1):PAGE443_I37@PURE_QUANTA.Q_CAP(CHIPS)':
 C_PATH='@t6g_mb_lib.t6g(sch_1):page443_i37@pure_quanta.q_cap(chips)',
 P_PATH='@t6g_mb_lib.t6g(sch_1):page334_i37@pure_quanta.q_cap(chips)',
 PATH='I37',
 DRAWING='@T6G_MB_LIB.T6G(SCH_1):PAGE443',
 TOLERANCE='10%',
 MATERIAL='X7S',
 PHYS_PAGE='334',
 XY='(-2250,950)',
 ROT='0',
 VER='1',
 PACK_TYPE='C0201',
 LOCATION='C316',
 CDS_LIB='pure_quanta',
 CDS_PART_NAME='Q_CAP_C0201-0.1UF,10V,10%,X7S,CH4102K6E00',
 VOLTAGE='10V',
 PART_NUMBER='CH4102K6E00',
 VALUE='0.1UF',
 PRIM_FILE='./archive_libs/logical/q_cap/chips/chips.prt';

PART_NAME
 C317 'Q_CAP_C0805-100UF,4V,20%,X6S,CH710KMEA01':;

SECTION_NUMBER 1
 '@T6G_MB_LIB.T6G(SCH_1):PAGE443_I67@PURE_QUANTA.Q_CAP(CHIPS)':
 C_PATH='@t6g_mb_lib.t6g(sch_1):page443_i67@pure_quanta.q_cap(chips)',
 P_PATH='@t6g_mb_lib.t6g(sch_1):page334_i67@pure_quanta.q_cap(chips)',
 PATH='I67',
 DRAWING='@T6G_MB_LIB.T6G(SCH_1):PAGE443',
 TOLERANCE='20%',
 MATERIAL='X6S',
 PHYS_PAGE='334',
 XY='(-3500,4000)',
 ROT='0',
 VER='1',
 PACK_TYPE='C0805',
 LOCATION='C317',
 CDS_LIB='pure_quanta',
 CDS_PART_NAME='Q_CAP_C0805-100UF,4V,20%,X6S,CH710KMEA01',
 VOLTAGE='4V',
 PART_NUMBER='CH710KMEA01',
 VALUE='100UF',
 PRIM_FILE='./archive_libs/logical/q_cap/chips/chips.prt';

PART_NAME
 C318 'Q_CAP_C0402-22UF,4V,20%,X6S,CH622KMEB02':;

SECTION_NUMBER 1
 '@T6G_MB_LIB.T6G(SCH_1):PAGE443_I77@PURE_QUANTA.Q_CAP(CHIPS)':
 C_PATH='@t6g_mb_lib.t6g(sch_1):page443_i77@pure_quanta.q_cap(chips)',
 P_PATH='@t6g_mb_lib.t6g(sch_1):page334_i77@pure_quanta.q_cap(chips)',
 PATH='I77',
 DRAWING='@T6G_MB_LIB.T6G(SCH_1):PAGE443',
 TOLERANCE='20%',
 MATERIAL='X6S',
 PHYS_PAGE='334',
 XY='(-1900,4000)',
 ROT='0',
 VER='1',
 PACK_TYPE='C0402',
 LOCATION='C318',
 CDS_LIB='pure_quanta',
 CDS_PART_NAME='Q_CAP_C0402-22UF,4V,20%,X6S,CH622KMEB02',
 VOLTAGE='4V',
 PART_NUMBER='CH622KMEB02',
 VALUE='22UF',
 PRIM_FILE='./archive_libs/logical/q_cap/chips/chips.prt';

PART_NAME
 C319 'Q_CAP_C0201-0.1UF,10V,10%,X7S,CH4102K6E00':;

SECTION_NUMBER 1
 '@T6G_MB_LIB.T6G(SCH_1):PAGE443_I51@PURE_QUANTA.Q_CAP(CHIPS)':
 C_PATH='@t6g_mb_lib.t6g(sch_1):page443_i51@pure_quanta.q_cap(chips)',
 P_PATH='@t6g_mb_lib.t6g(sch_1):page334_i51@pure_quanta.q_cap(chips)',
 PATH='I51',
 DRAWING='@T6G_MB_LIB.T6G(SCH_1):PAGE443',
 TOLERANCE='10%',
 MATERIAL='X7S',
 PHYS_PAGE='334',
 XY='(-1925,2050)',
 ROT='0',
 VER='1',
 PACK_TYPE='C0201',
 LOCATION='C319',
 CDS_LIB='pure_quanta',
 CDS_PART_NAME='Q_CAP_C0201-0.1UF,10V,10%,X7S,CH4102K6E00',
 VOLTAGE='10V',
 PART_NUMBER='CH4102K6E00',
 VALUE='0.1UF',
 PRIM_FILE='./archive_libs/logical/q_cap/chips/chips.prt';

PART_NAME
 C320 'Q_CAP_C0805-100UF,4V,20%,X6S,CH710KMEA01':;

SECTION_NUMBER 1
 '@T6G_MB_LIB.T6G(SCH_1):PAGE443_I69@PURE_QUANTA.Q_CAP(CHIPS)':
 C_PATH='@t6g_mb_lib.t6g(sch_1):page443_i69@pure_quanta.q_cap(chips)',
 P_PATH='@t6g_mb_lib.t6g(sch_1):page334_i69@pure_quanta.q_cap(chips)',
 PATH='I69',
 DRAWING='@T6G_MB_LIB.T6G(SCH_1):PAGE443',
 TOLERANCE='20%',
 MATERIAL='X6S',
 PHYS_PAGE='334',
 XY='(-3275,4000)',
 ROT='0',
 VER='1',
 PACK_TYPE='C0805',
 LOCATION='C320',
 CDS_LIB='pure_quanta',
 CDS_PART_NAME='Q_CAP_C0805-100UF,4V,20%,X6S,CH710KMEA01',
 VOLTAGE='4V',
 PART_NUMBER='CH710KMEA01',
 VALUE='100UF',
 PRIM_FILE='./archive_libs/logical/q_cap/chips/chips.prt';

PART_NAME
 C321 'Q_CAP_C0402-10UF,6.3V,20%,X6S,CH6101MEB01':;

SECTION_NUMBER 1
 '@T6G_MB_LIB.T6G(SCH_1):PAGE443_I44@PURE_QUANTA.Q_CAP(CHIPS)':
 C_PATH='@t6g_mb_lib.t6g(sch_1):page443_i44@pure_quanta.q_cap(chips)',
 P_PATH='@t6g_mb_lib.t6g(sch_1):page334_i44@pure_quanta.q_cap(chips)',
 PATH='I44',
 DRAWING='@T6G_MB_LIB.T6G(SCH_1):PAGE443',
 TOLERANCE='20%',
 MATERIAL='X6S',
 PHYS_PAGE='334',
 XY='(-3275,3375)',
 ROT='0',
 VER='1',
 PACK_TYPE='C0402',
 LOCATION='C321',
 CDS_LIB='pure_quanta',
 CDS_PART_NAME='Q_CAP_C0402-10UF,6.3V,20%,X6S,CH6101MEB01',
 VOLTAGE='6.3V',
 PART_NUMBER='CH6101MEB01',
 VALUE='10UF',
 PRIM_FILE='./archive_libs/logical/q_cap/chips/chips.prt';

PART_NAME
 C322 'Q_CAP_C0201-0.1UF,10V,10%,X7S,CH4102K6E00':;

SECTION_NUMBER 1
 '@T6G_MB_LIB.T6G(SCH_1):PAGE443_I60@PURE_QUANTA.Q_CAP(CHIPS)':
 C_PATH='@t6g_mb_lib.t6g(sch_1):page443_i60@pure_quanta.q_cap(chips)',
 P_PATH='@t6g_mb_lib.t6g(sch_1):page334_i60@pure_quanta.q_cap(chips)',
 PATH='I60',
 DRAWING='@T6G_MB_LIB.T6G(SCH_1):PAGE443',
 TOLERANCE='10%',
 MATERIAL='X7S',
 PHYS_PAGE='334',
 XY='(-1650,2050)',
 ROT='0',
 VER='1',
 PACK_TYPE='C0201',
 LOCATION='C322',
 CDS_LIB='pure_quanta',
 CDS_PART_NAME='Q_CAP_C0201-0.1UF,10V,10%,X7S,CH4102K6E00',
 VOLTAGE='10V',
 PART_NUMBER='CH4102K6E00',
 VALUE='0.1UF',
 PRIM_FILE='./archive_libs/logical/q_cap/chips/chips.prt';

PART_NAME
 C323 'Q_CAP_C0805-100UF,4V,20%,X6S,CH710KMEA01':;

SECTION_NUMBER 1
 '@T6G_MB_LIB.T6G(SCH_1):PAGE443_I72@PURE_QUANTA.Q_CAP(CHIPS)':
 C_PATH='@t6g_mb_lib.t6g(sch_1):page443_i72@pure_quanta.q_cap(chips)',
 P_PATH='@t6g_mb_lib.t6g(sch_1):page334_i72@pure_quanta.q_cap(chips)',
 PATH='I72',
 DRAWING='@T6G_MB_LIB.T6G(SCH_1):PAGE443',
 TOLERANCE='20%',
 MATERIAL='X6S',
 PHYS_PAGE='334',
 XY='(-3450,5275)',
 ROT='0',
 VER='1',
 PACK_TYPE='C0805',
 LOCATION='C323',
 CDS_LIB='pure_quanta',
 CDS_PART_NAME='Q_CAP_C0805-100UF,4V,20%,X6S,CH710KMEA01',
 VOLTAGE='4V',
 PART_NUMBER='CH710KMEA01',
 VALUE='100UF',
 PRIM_FILE='./archive_libs/logical/q_cap/chips/chips.prt';

PART_NAME
 C324 'Q_CAP_C0805-100UF,4V,20%,X6S,CH710KMEA01':;

SECTION_NUMBER 1
 '@T6G_MB_LIB.T6G(SCH_1):PAGE443_I70@PURE_QUANTA.Q_CAP(CHIPS)':
 C_PATH='@t6g_mb_lib.t6g(sch_1):page443_i70@pure_quanta.q_cap(chips)',
 P_PATH='@t6g_mb_lib.t6g(sch_1):page334_i70@pure_quanta.q_cap(chips)',
 PATH='I70',
 DRAWING='@T6G_MB_LIB.T6G(SCH_1):PAGE443',
 TOLERANCE='20%',
 MATERIAL='X6S',
 PHYS_PAGE='334',
 XY='(-3050,4000)',
 ROT='0',
 VER='1',
 PACK_TYPE='C0805',
 LOCATION='C324',
 CDS_LIB='pure_quanta',
 CDS_PART_NAME='Q_CAP_C0805-100UF,4V,20%,X6S,CH710KMEA01',
 VOLTAGE='4V',
 PART_NUMBER='CH710KMEA01',
 VALUE='100UF',
 PRIM_FILE='./archive_libs/logical/q_cap/chips/chips.prt';

PART_NAME
 C325 'Q_CAP_0402-4.7UF,6.3V,20%,X6S,CH5471MEB01':;

SECTION_NUMBER 1
 '@T6G_MB_LIB.T6G(SCH_1):PAGE443_I45@PURE_QUANTA.Q_CAP(CHIPS)':
 C_PATH='@t6g_mb_lib.t6g(sch_1):page443_i45@pure_quanta.q_cap(chips)',
 P_PATH='@t6g_mb_lib.t6g(sch_1):page334_i45@pure_quanta.q_cap(chips)',
 PATH='I45',
 DRAWING='@T6G_MB_LIB.T6G(SCH_1):PAGE443',
 TOLERANCE='20%',
 MATERIAL='X6S',
 PHYS_PAGE='334',
 XY='(-3050,3375)',
 ROT='0',
 VER='1',
 PACK_TYPE='0402',
 LOCATION='C325',
 CDS_LIB='pure_quanta',
 CDS_PART_NAME='Q_CAP_0402-4.7UF,6.3V,20%,X6S,CH5471MEB01',
 VOLTAGE='6.3V',
 PART_NUMBER='CH5471MEB01',
 VALUE='4.7UF',
 PRIM_FILE='./archive_libs/logical/q_cap/chips/chips.prt';

PART_NAME
 C326 'Q_CAP_0201-1UF,4V,20%,X6S,CH-10KMEE00':;

SECTION_NUMBER 1
 '@T6G_MB_LIB.T6G(SCH_1):PAGE443_I43@PURE_QUANTA.Q_CAP(CHIPS)':
 C_PATH='@t6g_mb_lib.t6g(sch_1):page443_i43@pure_quanta.q_cap(chips)',
 P_PATH='@t6g_mb_lib.t6g(sch_1):page334_i43@pure_quanta.q_cap(chips)',
 PATH='I43',
 DRAWING='@T6G_MB_LIB.T6G(SCH_1):PAGE443',
 TOLERANCE='20%',
 MATERIAL='X6S',
 PHYS_PAGE='334',
 XY='(-3025,2750)',
 ROT='0',
 VER='1',
 PACK_TYPE='0201',
 LOCATION='C326',
 CDS_LIB='pure_quanta',
 CDS_PART_NAME='Q_CAP_0201-1UF,4V,20%,X6S,CH-10KMEE00',
 VOLTAGE='4V',
 PART_NUMBER='CH-10KMEE00',
 VALUE='1UF',
 PRIM_FILE='./archive_libs/logical/q_cap/chips/chips.prt';

PART_NAME
 C327 'Q_CAP_C0402-22UF,4V,20%,X6S,CH622KMEB02':;

SECTION_NUMBER 1
 '@T6G_MB_LIB.T6G(SCH_1):PAGE443_I73@PURE_QUANTA.Q_CAP(CHIPS)':
 C_PATH='@t6g_mb_lib.t6g(sch_1):page443_i73@pure_quanta.q_cap(chips)',
 P_PATH='@t6g_mb_lib.t6g(sch_1):page334_i73@pure_quanta.q_cap(chips)',
 PATH='I73',
 DRAWING='@T6G_MB_LIB.T6G(SCH_1):PAGE443',
 TOLERANCE='20%',
 MATERIAL='X6S',
 PHYS_PAGE='334',
 XY='(-3175,5275)',
 ROT='0',
 VER='1',
 PACK_TYPE='C0402',
 LOCATION='C327',
 CDS_LIB='pure_quanta',
 CDS_PART_NAME='Q_CAP_C0402-22UF,4V,20%,X6S,CH622KMEB02',
 VOLTAGE='4V',
 PART_NUMBER='CH622KMEB02',
 VALUE='22UF',
 PRIM_FILE='./archive_libs/logical/q_cap/chips/chips.prt';

PART_NAME
 C328 'Q_CAP_C0805-100UF,4V,20%,X6S,CH710KMEA01':;

SECTION_NUMBER 1
 '@T6G_MB_LIB.T6G(SCH_1):PAGE443_I71@PURE_QUANTA.Q_CAP(CHIPS)':
 C_PATH='@t6g_mb_lib.t6g(sch_1):page443_i71@pure_quanta.q_cap(chips)',
 P_PATH='@t6g_mb_lib.t6g(sch_1):page334_i71@pure_quanta.q_cap(chips)',
 PATH='I71',
 DRAWING='@T6G_MB_LIB.T6G(SCH_1):PAGE443',
 TOLERANCE='20%',
 MATERIAL='X6S',
 PHYS_PAGE='334',
 XY='(-2825,4000)',
 ROT='0',
 VER='1',
 PACK_TYPE='C0805',
 LOCATION='C328',
 CDS_LIB='pure_quanta',
 CDS_PART_NAME='Q_CAP_C0805-100UF,4V,20%,X6S,CH710KMEA01',
 VOLTAGE='4V',
 PART_NUMBER='CH710KMEA01',
 VALUE='100UF',
 PRIM_FILE='./archive_libs/logical/q_cap/chips/chips.prt';

PART_NAME
 C329 'Q_CAP_C0402-22UF,4V,20%,X6S,CH622KMEB02':;

SECTION_NUMBER 1
 '@T6G_MB_LIB.T6G(SCH_1):PAGE443_I74@PURE_QUANTA.Q_CAP(CHIPS)':
 C_PATH='@t6g_mb_lib.t6g(sch_1):page443_i74@pure_quanta.q_cap(chips)',
 P_PATH='@t6g_mb_lib.t6g(sch_1):page334_i74@pure_quanta.q_cap(chips)',
 PATH='I74',
 DRAWING='@T6G_MB_LIB.T6G(SCH_1):PAGE443',
 TOLERANCE='20%',
 MATERIAL='X6S',
 PHYS_PAGE='334',
 XY='(-2575,4000)',
 ROT='0',
 VER='1',
 PACK_TYPE='C0402',
 LOCATION='C329',
 CDS_LIB='pure_quanta',
 CDS_PART_NAME='Q_CAP_C0402-22UF,4V,20%,X6S,CH622KMEB02',
 VOLTAGE='4V',
 PART_NUMBER='CH622KMEB02',
 VALUE='22UF',
 PRIM_FILE='./archive_libs/logical/q_cap/chips/chips.prt';

PART_NAME
 C330 'Q_CAP_0201-1UF,4V,20%,X6S,CH-10KMEE00':;

SECTION_NUMBER 1
 '@T6G_MB_LIB.T6G(SCH_1):PAGE443_I47@PURE_QUANTA.Q_CAP(CHIPS)':
 C_PATH='@t6g_mb_lib.t6g(sch_1):page443_i47@pure_quanta.q_cap(chips)',
 P_PATH='@t6g_mb_lib.t6g(sch_1):page334_i47@pure_quanta.q_cap(chips)',
 PATH='I47',
 DRAWING='@T6G_MB_LIB.T6G(SCH_1):PAGE443',
 TOLERANCE='20%',
 MATERIAL='X6S',
 PHYS_PAGE='334',
 XY='(-2800,2750)',
 ROT='0',
 VER='1',
 PACK_TYPE='0201',
 LOCATION='C330',
 CDS_LIB='pure_quanta',
 CDS_PART_NAME='Q_CAP_0201-1UF,4V,20%,X6S,CH-10KMEE00',
 VOLTAGE='4V',
 PART_NUMBER='CH-10KMEE00',
 VALUE='1UF',
 PRIM_FILE='./archive_libs/logical/q_cap/chips/chips.prt';

PART_NAME
 C331 'Q_CAP_0402-4.7UF,6.3V,20%,X6S,CH5471MEB01':;

SECTION_NUMBER 1
 '@T6G_MB_LIB.T6G(SCH_1):PAGE443_I46@PURE_QUANTA.Q_CAP(CHIPS)':
 C_PATH='@t6g_mb_lib.t6g(sch_1):page443_i46@pure_quanta.q_cap(chips)',
 P_PATH='@t6g_mb_lib.t6g(sch_1):page334_i46@pure_quanta.q_cap(chips)',
 PATH='I46',
 DRAWING='@T6G_MB_LIB.T6G(SCH_1):PAGE443',
 TOLERANCE='20%',
 MATERIAL='X6S',
 PHYS_PAGE='334',
 XY='(-2825,3375)',
 ROT='0',
 VER='1',
 PACK_TYPE='0402',
 LOCATION='C331',
 CDS_LIB='pure_quanta',
 CDS_PART_NAME='Q_CAP_0402-4.7UF,6.3V,20%,X6S,CH5471MEB01',
 VOLTAGE='6.3V',
 PART_NUMBER='CH5471MEB01',
 VALUE='4.7UF',
 PRIM_FILE='./archive_libs/logical/q_cap/chips/chips.prt';

PART_NAME
 C332 'Q_CAP_C0402-10UF,6.3V,20%,X6S,CH6101MEB01':;

SECTION_NUMBER 1
 '@T6G_MB_LIB.T6G(SCH_1):PAGE443_I41@PURE_QUANTA.Q_CAP(CHIPS)':
 C_PATH='@t6g_mb_lib.t6g(sch_1):page443_i41@pure_quanta.q_cap(chips)',
 P_PATH='@t6g_mb_lib.t6g(sch_1):page334_i41@pure_quanta.q_cap(chips)',
 PATH='I41',
 DRAWING='@T6G_MB_LIB.T6G(SCH_1):PAGE443',
 TOLERANCE='20%',
 MATERIAL='X6S',
 PHYS_PAGE='334',
 XY='(-3500,3375)',
 ROT='0',
 VER='1',
 PACK_TYPE='C0402',
 LOCATION='C332',
 CDS_LIB='pure_quanta',
 CDS_PART_NAME='Q_CAP_C0402-10UF,6.3V,20%,X6S,CH6101MEB01',
 VOLTAGE='6.3V',
 PART_NUMBER='CH6101MEB01',
 VALUE='10UF',
 PRIM_FILE='./archive_libs/logical/q_cap/chips/chips.prt';

PART_NAME
 C333 'Q_CAP_C0402-10UF,6.3V,20%,X6S,CH6101MEB01':;

SECTION_NUMBER 1
 '@T6G_MB_LIB.T6G(SCH_1):PAGE443_I87@PURE_QUANTA.Q_CAP(CHIPS)':
 C_PATH='@t6g_mb_lib.t6g(sch_1):page443_i87@pure_quanta.q_cap(chips)',
 P_PATH='@t6g_mb_lib.t6g(sch_1):page334_i87@pure_quanta.q_cap(chips)',
 PATH='I87',
 DRAWING='@T6G_MB_LIB.T6G(SCH_1):PAGE443',
 TOLERANCE='20%',
 MATERIAL='X6S',
 PHYS_PAGE='334',
 XY='(-2850,5250)',
 ROT='0',
 VER='1',
 PACK_TYPE='C0402',
 LOCATION='C333',
 CDS_LIB='pure_quanta',
 CDS_PART_NAME='Q_CAP_C0402-10UF,6.3V,20%,X6S,CH6101MEB01',
 VOLTAGE='6.3V',
 PART_NUMBER='CH6101MEB01',
 VALUE='10UF',
 PRIM_FILE='./archive_libs/logical/q_cap/chips/chips.prt';

PART_NAME
 C334 'Q_CAP_C0201-0.1UF,10V,10%,X7S,CH4102K6E00':;

SECTION_NUMBER 1
 '@T6G_MB_LIB.T6G(SCH_1):PAGE443_I62@PURE_QUANTA.Q_CAP(CHIPS)':
 C_PATH='@t6g_mb_lib.t6g(sch_1):page443_i62@pure_quanta.q_cap(chips)',
 P_PATH='@t6g_mb_lib.t6g(sch_1):page334_i62@pure_quanta.q_cap(chips)',
 PATH='I62',
 DRAWING='@T6G_MB_LIB.T6G(SCH_1):PAGE443',
 TOLERANCE='10%',
 MATERIAL='X7S',
 PHYS_PAGE='334',
 XY='(-1400,2050)',
 ROT='0',
 VER='1',
 PACK_TYPE='C0201',
 LOCATION='C334',
 CDS_LIB='pure_quanta',
 CDS_PART_NAME='Q_CAP_C0201-0.1UF,10V,10%,X7S,CH4102K6E00',
 VOLTAGE='10V',
 PART_NUMBER='CH4102K6E00',
 VALUE='0.1UF',
 PRIM_FILE='./archive_libs/logical/q_cap/chips/chips.prt';

PART_NAME
 C335 'Q_CAP_C0402-22UF,4V,20%,X6S,CH622KMEB02':;

SECTION_NUMBER 1
 '@T6G_MB_LIB.T6G(SCH_1):PAGE443_I75@PURE_QUANTA.Q_CAP(CHIPS)':
 C_PATH='@t6g_mb_lib.t6g(sch_1):page443_i75@pure_quanta.q_cap(chips)',
 P_PATH='@t6g_mb_lib.t6g(sch_1):page334_i75@pure_quanta.q_cap(chips)',
 PATH='I75',
 DRAWING='@T6G_MB_LIB.T6G(SCH_1):PAGE443',
 TOLERANCE='20%',
 MATERIAL='X6S',
 PHYS_PAGE='334',
 XY='(-2350,4000)',
 ROT='0',
 VER='1',
 PACK_TYPE='C0402',
 LOCATION='C335',
 CDS_LIB='pure_quanta',
 CDS_PART_NAME='Q_CAP_C0402-22UF,4V,20%,X6S,CH622KMEB02',
 VOLTAGE='4V',
 PART_NUMBER='CH622KMEB02',
 VALUE='22UF',
 PRIM_FILE='./archive_libs/logical/q_cap/chips/chips.prt';

PART_NAME
 C336 'Q_CAP_0402-4.7UF,6.3V,20%,X6S,CH5471MEB01':;

SECTION_NUMBER 1
 '@T6G_MB_LIB.T6G(SCH_1):PAGE443_I55@PURE_QUANTA.Q_CAP(CHIPS)':
 C_PATH='@t6g_mb_lib.t6g(sch_1):page443_i55@pure_quanta.q_cap(chips)',
 P_PATH='@t6g_mb_lib.t6g(sch_1):page334_i55@pure_quanta.q_cap(chips)',
 PATH='I55',
 DRAWING='@T6G_MB_LIB.T6G(SCH_1):PAGE443',
 TOLERANCE='20%',
 MATERIAL='X6S',
 PHYS_PAGE='334',
 XY='(-2350,3375)',
 ROT='0',
 VER='1',
 PACK_TYPE='0402',
 LOCATION='C336',
 CDS_LIB='pure_quanta',
 CDS_PART_NAME='Q_CAP_0402-4.7UF,6.3V,20%,X6S,CH5471MEB01',
 VOLTAGE='6.3V',
 PART_NUMBER='CH5471MEB01',
 VALUE='4.7UF',
 PRIM_FILE='./archive_libs/logical/q_cap/chips/chips.prt';

PART_NAME
 C337 'Q_CAP_0201-1UF,4V,20%,X6S,CH-10KMEE00':;

SECTION_NUMBER 1
 '@T6G_MB_LIB.T6G(SCH_1):PAGE443_I53@PURE_QUANTA.Q_CAP(CHIPS)':
 C_PATH='@t6g_mb_lib.t6g(sch_1):page443_i53@pure_quanta.q_cap(chips)',
 P_PATH='@t6g_mb_lib.t6g(sch_1):page334_i53@pure_quanta.q_cap(chips)',
 PATH='I53',
 DRAWING='@T6G_MB_LIB.T6G(SCH_1):PAGE443',
 TOLERANCE='20%',
 MATERIAL='X6S',
 PHYS_PAGE='334',
 XY='(-2325,2725)',
 ROT='0',
 VER='1',
 PACK_TYPE='0201',
 LOCATION='C337',
 CDS_LIB='pure_quanta',
 CDS_PART_NAME='Q_CAP_0201-1UF,4V,20%,X6S,CH-10KMEE00',
 VOLTAGE='4V',
 PART_NUMBER='CH-10KMEE00',
 VALUE='1UF',
 PRIM_FILE='./archive_libs/logical/q_cap/chips/chips.prt';

PART_NAME
 C338 'Q_CAP_0402-4.7UF,6.3V,20%,X6S,CH5471MEB01':;

SECTION_NUMBER 1
 '@T6G_MB_LIB.T6G(SCH_1):PAGE443_I78@PURE_QUANTA.Q_CAP(CHIPS)':
 C_PATH='@t6g_mb_lib.t6g(sch_1):page443_i78@pure_quanta.q_cap(chips)',
 P_PATH='@t6g_mb_lib.t6g(sch_1):page334_i78@pure_quanta.q_cap(chips)',
 PATH='I78',
 DRAWING='@T6G_MB_LIB.T6G(SCH_1):PAGE443',
 TOLERANCE='20%',
 MATERIAL='X6S',
 PHYS_PAGE='334',
 XY='(-2550,5250)',
 ROT='0',
 VER='1',
 PACK_TYPE='0402',
 LOCATION='C338',
 CDS_LIB='pure_quanta',
 CDS_PART_NAME='Q_CAP_0402-4.7UF,6.3V,20%,X6S,CH5471MEB01',
 VOLTAGE='6.3V',
 PART_NUMBER='CH5471MEB01',
 VALUE='4.7UF',
 PRIM_FILE='./archive_libs/logical/q_cap/chips/chips.prt';

PART_NAME
 C339 'Q_CAP_C0402-10UF,6.3V,20%,X6S,CH6101MEB01':;

SECTION_NUMBER 1
 '@T6G_MB_LIB.T6G(SCH_1):PAGE443_I80@PURE_QUANTA.Q_CAP(CHIPS)':
 C_PATH='@t6g_mb_lib.t6g(sch_1):page443_i80@pure_quanta.q_cap(chips)',
 P_PATH='@t6g_mb_lib.t6g(sch_1):page334_i80@pure_quanta.q_cap(chips)',
 PATH='I80',
 DRAWING='@T6G_MB_LIB.T6G(SCH_1):PAGE443',
 TOLERANCE='20%',
 MATERIAL='X6S',
 PHYS_PAGE='334',
 XY='(-1600,4000)',
 ROT='0',
 VER='1',
 PACK_TYPE='C0402',
 LOCATION='C339',
 CDS_LIB='pure_quanta',
 CDS_PART_NAME='Q_CAP_C0402-10UF,6.3V,20%,X6S,CH6101MEB01',
 VOLTAGE='6.3V',
 PART_NUMBER='CH6101MEB01',
 VALUE='10UF',
 PRIM_FILE='./archive_libs/logical/q_cap/chips/chips.prt';

PART_NAME
 C340 'Q_CAP_C0201-0.1UF,10V,10%,X7S,CH4102K6E00':;

SECTION_NUMBER 1
 '@T6G_MB_LIB.T6G(SCH_1):PAGE443_I38@PURE_QUANTA.Q_CAP(CHIPS)':
 C_PATH='@t6g_mb_lib.t6g(sch_1):page443_i38@pure_quanta.q_cap(chips)',
 P_PATH='@t6g_mb_lib.t6g(sch_1):page334_i38@pure_quanta.q_cap(chips)',
 PATH='I38',
 DRAWING='@T6G_MB_LIB.T6G(SCH_1):PAGE443',
 TOLERANCE='10%',
 MATERIAL='X7S',
 PHYS_PAGE='334',
 XY='(-3225,2050)',
 ROT='0',
 VER='1',
 PACK_TYPE='C0201',
 LOCATION='C340',
 CDS_LIB='pure_quanta',
 CDS_PART_NAME='Q_CAP_C0201-0.1UF,10V,10%,X7S,CH4102K6E00',
 VOLTAGE='10V',
 PART_NUMBER='CH4102K6E00',
 VALUE='0.1UF',
 PRIM_FILE='./archive_libs/logical/q_cap/chips/chips.prt';

PART_NAME
 C341 'Q_CAP_C0201-0.1UF,10V,10%,X7S,CH4102K6E00':;

SECTION_NUMBER 1
 '@T6G_MB_LIB.T6G(SCH_1):PAGE443_I92@PURE_QUANTA.Q_CAP(CHIPS)':
 C_PATH='@t6g_mb_lib.t6g(sch_1):page443_i92@pure_quanta.q_cap(chips)',
 P_PATH='@t6g_mb_lib.t6g(sch_1):page334_i92@pure_quanta.q_cap(chips)',
 PATH='I92',
 DRAWING='@T6G_MB_LIB.T6G(SCH_1):PAGE443',
 TOLERANCE='10%',
 MATERIAL='X7S',
 PHYS_PAGE='334',
 XY='(-1825,2750)',
 ROT='0',
 VER='1',
 PACK_TYPE='C0201',
 LOCATION='C341',
 CDS_LIB='pure_quanta',
 CDS_PART_NAME='Q_CAP_C0201-0.1UF,10V,10%,X7S,CH4102K6E00',
 VOLTAGE='10V',
 PART_NUMBER='CH4102K6E00',
 VALUE='0.1UF',
 PRIM_FILE='./archive_libs/logical/q_cap/chips/chips.prt';

PART_NAME
 C342 'Q_CAP_0201-1UF,4V,20%,X6S,CH-10KMEE00':;

SECTION_NUMBER 1
 '@T6G_MB_LIB.T6G(SCH_1):PAGE443_I79@PURE_QUANTA.Q_CAP(CHIPS)':
 C_PATH='@t6g_mb_lib.t6g(sch_1):page443_i79@pure_quanta.q_cap(chips)',
 P_PATH='@t6g_mb_lib.t6g(sch_1):page334_i79@pure_quanta.q_cap(chips)',
 PATH='I79',
 DRAWING='@T6G_MB_LIB.T6G(SCH_1):PAGE443',
 TOLERANCE='20%',
 MATERIAL='X6S',
 PHYS_PAGE='334',
 XY='(-2250,5250)',
 ROT='0',
 VER='1',
 PACK_TYPE='0201',
 LOCATION='C342',
 CDS_LIB='pure_quanta',
 CDS_PART_NAME='Q_CAP_0201-1UF,4V,20%,X6S,CH-10KMEE00',
 VOLTAGE='4V',
 PART_NUMBER='CH-10KMEE00',
 VALUE='1UF',
 PRIM_FILE='./archive_libs/logical/q_cap/chips/chips.prt';

PART_NAME
 C343 'Q_CAP_0402-4.7UF,6.3V,20%,X6S,CH5471MEB01':;

SECTION_NUMBER 1
 '@T6G_MB_LIB.T6G(SCH_1):PAGE443_I54@PURE_QUANTA.Q_CAP(CHIPS)':
 C_PATH='@t6g_mb_lib.t6g(sch_1):page443_i54@pure_quanta.q_cap(chips)',
 P_PATH='@t6g_mb_lib.t6g(sch_1):page334_i54@pure_quanta.q_cap(chips)',
 PATH='I54',
 DRAWING='@T6G_MB_LIB.T6G(SCH_1):PAGE443',
 TOLERANCE='20%',
 MATERIAL='X6S',
 PHYS_PAGE='334',
 XY='(-2575,3375)',
 ROT='0',
 VER='1',
 PACK_TYPE='0402',
 LOCATION='C343',
 CDS_LIB='pure_quanta',
 CDS_PART_NAME='Q_CAP_0402-4.7UF,6.3V,20%,X6S,CH5471MEB01',
 VOLTAGE='6.3V',
 PART_NUMBER='CH5471MEB01',
 VALUE='4.7UF',
 PRIM_FILE='./archive_libs/logical/q_cap/chips/chips.prt';

PART_NAME
 C344 'Q_CAP_C0201-0.1UF,10V,10%,X7S,CH4102K6E00':;

SECTION_NUMBER 1
 '@T6G_MB_LIB.T6G(SCH_1):PAGE443_I39@PURE_QUANTA.Q_CAP(CHIPS)':
 C_PATH='@t6g_mb_lib.t6g(sch_1):page443_i39@pure_quanta.q_cap(chips)',
 P_PATH='@t6g_mb_lib.t6g(sch_1):page334_i39@pure_quanta.q_cap(chips)',
 PATH='I39',
 DRAWING='@T6G_MB_LIB.T6G(SCH_1):PAGE443',
 TOLERANCE='10%',
 MATERIAL='X7S',
 PHYS_PAGE='334',
 XY='(-2925,2050)',
 ROT='0',
 VER='1',
 PACK_TYPE='C0201',
 LOCATION='C344',
 CDS_LIB='pure_quanta',
 CDS_PART_NAME='Q_CAP_C0201-0.1UF,10V,10%,X7S,CH4102K6E00',
 VOLTAGE='10V',
 PART_NUMBER='CH4102K6E00',
 VALUE='0.1UF',
 PRIM_FILE='./archive_libs/logical/q_cap/chips/chips.prt';

PART_NAME
 C345 'Q_CAP_0402-0.1UF,25V,10%,EMPTY,CH4104K1B00':;

SECTION_NUMBER 1
 '@T6G_MB_LIB.T6G(SCH_1):PAGE315_I41@PURE_QUANTA.Q_CAP(CHIPS)':
 C_PATH='@t6g_mb_lib.t6g(sch_1):page315_i41@pure_quanta.q_cap(chips)',
 P_PATH='@t6g_mb_lib.t6g(sch_1):page269_i41@pure_quanta.q_cap(chips)',
 PATH='I41',
 DRAWING='@T6G_MB_LIB.T6G(SCH_1):PAGE315',
 TOLERANCE='10%',
 MATERIAL='EMPTY',
 PHYS_PAGE='269',
 XY='(-3525,1575)',
 ROT='2',
 VER='1',
 PACK_TYPE='0402',
 LOCATION='C345',
 CDS_LIB='pure_quanta',
 CDS_PART_NAME='Q_CAP_0402-0.1UF,25V,10%,EMPTY,CH4104K1B00',
 VOLTAGE='25V',
 PART_NUMBER='CH4104K1B00',
 VALUE='0.1UF',
 PRIM_FILE='./archive_libs/logical/q_cap/chips/chips.prt';

PART_NAME
 C346 'Q_CAP_0201-1UF,4V,20%,X6S,CH-10KMEE00':;

SECTION_NUMBER 1
 '@T6G_MB_LIB.T6G(SCH_1):PAGE443_I57@PURE_QUANTA.Q_CAP(CHIPS)':
 C_PATH='@t6g_mb_lib.t6g(sch_1):page443_i57@pure_quanta.q_cap(chips)',
 P_PATH='@t6g_mb_lib.t6g(sch_1):page334_i57@pure_quanta.q_cap(chips)',
 PATH='I57',
 DRAWING='@T6G_MB_LIB.T6G(SCH_1):PAGE443',
 TOLERANCE='20%',
 MATERIAL='X6S',
 PHYS_PAGE='334',
 XY='(-2075,2725)',
 ROT='0',
 VER='1',
 PACK_TYPE='0201',
 LOCATION='C346',
 CDS_LIB='pure_quanta',
 CDS_PART_NAME='Q_CAP_0201-1UF,4V,20%,X6S,CH-10KMEE00',
 VOLTAGE='4V',
 PART_NUMBER='CH-10KMEE00',
 VALUE='1UF',
 PRIM_FILE='./archive_libs/logical/q_cap/chips/chips.prt';

PART_NAME
 C347 'Q_CAP_0402-0.1UF,25V,10%,X7R,CH4104K1B00':;

SECTION_NUMBER 1
 '@T6G_MB_LIB.T6G(SCH_1):PAGE264_I47@PURE_QUANTA.Q_CAP(CHIPS)':
 C_PATH='@t6g_mb_lib.t6g(sch_1):page264_i47@pure_quanta.q_cap(chips)',
 P_PATH='@t6g_mb_lib.t6g(sch_1):page259_i47@pure_quanta.q_cap(chips)',
 PATH='I47',
 DRAWING='@T6G_MB_LIB.T6G(SCH_1):PAGE264',
 TOLERANCE='10%',
 MATERIAL='X7R',
 PHYS_PAGE='259',
 XY='(-3750,2350)',
 ROT='2',
 VER='1',
 PACK_TYPE='0402',
 LOCATION='C347',
 CDS_LIB='pure_quanta',
 CDS_PART_NAME='Q_CAP_0402-0.1UF,25V,10%,X7R,CH4104K1B00',
 VOLTAGE='25V',
 PART_NUMBER='CH4104K1B00',
 VALUE='0.1UF',
 PRIM_FILE='./archive_libs/logical/q_cap/chips/chips.prt';

PART_NAME
 C348 'Q_CAP_0402-0.1UF,25V,10%,EMPTY,CH4104K1B00':;

SECTION_NUMBER 1
 '@T6G_MB_LIB.T6G(SCH_1):PAGE167_I5@PURE_QUANTA.Q_CAP(CHIPS)':
 C_PATH='@t6g_mb_lib.t6g(sch_1):page167_i5@pure_quanta.q_cap(chips)',
 P_PATH='@t6g_mb_lib.t6g(sch_1):page192_i5@pure_quanta.q_cap(chips)',
 PATH='I5',
 DRAWING='@T6G_MB_LIB.T6G(SCH_1):PAGE167',
 TOLERANCE='10%',
 MATERIAL='EMPTY',
 PHYS_PAGE='192',
 XY='(-8475,3425)',
 ROT='2',
 VER='1',
 PACK_TYPE='0402',
 LOCATION='C348',
 CDS_LIB='pure_quanta',
 CDS_PART_NAME='Q_CAP_0402-0.1UF,25V,10%,EMPTY,CH4104K1B00',
 VOLTAGE='25V',
 PART_NUMBER='CH4104K1B00',
 VALUE='0.1UF',
 PRIM_FILE='./archive_libs/logical/q_cap/chips/chips.prt';

PART_NAME
 C349 'Q_CAP_C0201-0.1UF,10V,10%,X7S,CH4102K6E00':;

SECTION_NUMBER 1
 '@T6G_MB_LIB.T6G(SCH_1):PAGE443_I49@PURE_QUANTA.Q_CAP(CHIPS)':
 C_PATH='@t6g_mb_lib.t6g(sch_1):page443_i49@pure_quanta.q_cap(chips)',
 P_PATH='@t6g_mb_lib.t6g(sch_1):page334_i49@pure_quanta.q_cap(chips)',
 PATH='I49',
 DRAWING='@T6G_MB_LIB.T6G(SCH_1):PAGE443',
 TOLERANCE='10%',
 MATERIAL='X7S',
 PHYS_PAGE='334',
 XY='(-2450,2050)',
 ROT='0',
 VER='1',
 PACK_TYPE='C0201',
 LOCATION='C349',
 CDS_LIB='pure_quanta',
 CDS_PART_NAME='Q_CAP_C0201-0.1UF,10V,10%,X7S,CH4102K6E00',
 VOLTAGE='10V',
 PART_NUMBER='CH4102K6E00',
 VALUE='0.1UF',
 PRIM_FILE='./archive_libs/logical/q_cap/chips/chips.prt';

PART_NAME
 C350 'Q_CAP_C0201-0.1UF,10V,10%,X7S,CH4102K6E00':;

SECTION_NUMBER 1
 '@T6G_MB_LIB.T6G(SCH_1):PAGE443_I93@PURE_QUANTA.Q_CAP(CHIPS)':
 C_PATH='@t6g_mb_lib.t6g(sch_1):page443_i93@pure_quanta.q_cap(chips)',
 P_PATH='@t6g_mb_lib.t6g(sch_1):page334_i93@pure_quanta.q_cap(chips)',
 PATH='I93',
 DRAWING='@T6G_MB_LIB.T6G(SCH_1):PAGE443',
 TOLERANCE='10%',
 MATERIAL='X7S',
 PHYS_PAGE='334',
 XY='(-1550,2750)',
 ROT='0',
 VER='1',
 PACK_TYPE='C0201',
 LOCATION='C350',
 CDS_LIB='pure_quanta',
 CDS_PART_NAME='Q_CAP_C0201-0.1UF,10V,10%,X7S,CH4102K6E00',
 VOLTAGE='10V',
 PART_NUMBER='CH4102K6E00',
 VALUE='0.1UF',
 PRIM_FILE='./archive_libs/logical/q_cap/chips/chips.prt';

PART_NAME
 C351 'Q_CAP_C0402-22UF,4V,20%,X6S,CH622KMEB02':;

SECTION_NUMBER 1
 '@T6G_MB_LIB.T6G(SCH_1):PAGE443_I76@PURE_QUANTA.Q_CAP(CHIPS)':
 C_PATH='@t6g_mb_lib.t6g(sch_1):page443_i76@pure_quanta.q_cap(chips)',
 P_PATH='@t6g_mb_lib.t6g(sch_1):page334_i76@pure_quanta.q_cap(chips)',
 PATH='I76',
 DRAWING='@T6G_MB_LIB.T6G(SCH_1):PAGE443',
 TOLERANCE='20%',
 MATERIAL='X6S',
 PHYS_PAGE='334',
 XY='(-2125,4000)',
 ROT='0',
 VER='1',
 PACK_TYPE='C0402',
 LOCATION='C351',
 CDS_LIB='pure_quanta',
 CDS_PART_NAME='Q_CAP_C0402-22UF,4V,20%,X6S,CH622KMEB02',
 VOLTAGE='4V',
 PART_NUMBER='CH622KMEB02',
 VALUE='22UF',
 PRIM_FILE='./archive_libs/logical/q_cap/chips/chips.prt';

PART_NAME
 C352 'Q_CAP_C0402-0.1UF,16V,10%,X7R,CH4103K1B08':;

SECTION_NUMBER 1
 '@T6G_MB_LIB.T6G(SCH_1):PAGE82_I83@PURE_QUANTA.Q_CAP(CHIPS)':
 C_PATH='@t6g_mb_lib.t6g(sch_1):page82_i83@pure_quanta.q_cap(chips)',
 P_PATH='@t6g_mb_lib.t6g(sch_1):page83_i83@pure_quanta.q_cap(chips)',
 PATH='I83',
 DRAWING='@T6G_MB_LIB.T6G(SCH_1):PAGE82',
 TOLERANCE='10%',
 MATERIAL='X7R',
 PHYS_PAGE='83',
 XY='(-3450,1575)',
 ROT='0',
 VER='2',
 PACK_TYPE='C0402',
 LOCATION='C352',
 CDS_LIB='pure_quanta',
 CDS_PART_NAME='Q_CAP_C0402-0.1UF,16V,10%,X7R,CH4103K1B08',
 VOLTAGE='16V',
 PART_NUMBER='CH4103K1B08',
 VALUE='0.1UF',
 PRIM_FILE='./archive_libs/logical/q_cap/chips/chips.prt';

PART_NAME
 C353 'Q_CAP_0201-1UF,4V,20%,X6S,CH-10KMEE00':;

SECTION_NUMBER 1
 '@T6G_MB_LIB.T6G(SCH_1):PAGE443_I66@PURE_QUANTA.Q_CAP(CHIPS)':
 C_PATH='@t6g_mb_lib.t6g(sch_1):page443_i66@pure_quanta.q_cap(chips)',
 P_PATH='@t6g_mb_lib.t6g(sch_1):page334_i66@pure_quanta.q_cap(chips)',
 PATH='I66',
 DRAWING='@T6G_MB_LIB.T6G(SCH_1):PAGE443',
 TOLERANCE='20%',
 MATERIAL='X6S',
 PHYS_PAGE='334',
 XY='(-1425,3375)',
 ROT='0',
 VER='1',
 PACK_TYPE='0201',
 LOCATION='C353',
 CDS_LIB='pure_quanta',
 CDS_PART_NAME='Q_CAP_0201-1UF,4V,20%,X6S,CH-10KMEE00',
 VOLTAGE='4V',
 PART_NUMBER='CH-10KMEE00',
 VALUE='1UF',
 PRIM_FILE='./archive_libs/logical/q_cap/chips/chips.prt';

PART_NAME
 C354 'Q_CAP_C0402-10UF,6.3V,20%,X6S,CH6101MEB01':;

SECTION_NUMBER 1
 '@T6G_MB_LIB.T6G(SCH_1):PAGE443_I81@PURE_QUANTA.Q_CAP(CHIPS)':
 C_PATH='@t6g_mb_lib.t6g(sch_1):page443_i81@pure_quanta.q_cap(chips)',
 P_PATH='@t6g_mb_lib.t6g(sch_1):page334_i81@pure_quanta.q_cap(chips)',
 PATH='I81',
 DRAWING='@T6G_MB_LIB.T6G(SCH_1):PAGE443',
 TOLERANCE='20%',
 MATERIAL='X6S',
 PHYS_PAGE='334',
 XY='(-1300,4000)',
 ROT='0',
 VER='1',
 PACK_TYPE='C0402',
 LOCATION='C354',
 CDS_LIB='pure_quanta',
 CDS_PART_NAME='Q_CAP_C0402-10UF,6.3V,20%,X6S,CH6101MEB01',
 VOLTAGE='6.3V',
 PART_NUMBER='CH6101MEB01',
 VALUE='10UF',
 PRIM_FILE='./archive_libs/logical/q_cap/chips/chips.prt';

PART_NAME
 C355 'Q_CAP_C0402-0.1UF,16V,10%,X7R,CH4103K1B08':;

SECTION_NUMBER 1
 '@T6G_MB_LIB.T6G(SCH_1):PAGE82_I108@PURE_QUANTA.Q_CAP(CHIPS)':
 C_PATH='@t6g_mb_lib.t6g(sch_1):page82_i108@pure_quanta.q_cap(chips)',
 P_PATH='@t6g_mb_lib.t6g(sch_1):page83_i108@pure_quanta.q_cap(chips)',
 PATH='I108',
 DRAWING='@T6G_MB_LIB.T6G(SCH_1):PAGE82',
 TOLERANCE='10%',
 MATERIAL='X7R',
 PHYS_PAGE='83',
 XY='(-1200,1225)',
 ROT='0',
 VER='2',
 PACK_TYPE='C0402',
 LOCATION='C355',
 CDS_LIB='pure_quanta',
 CDS_PART_NAME='Q_CAP_C0402-0.1UF,16V,10%,X7R,CH4103K1B08',
 VOLTAGE='16V',
 PART_NUMBER='CH4103K1B08',
 VALUE='0.1UF',
 PRIM_FILE='./archive_libs/logical/q_cap/chips/chips.prt';

PART_NAME
 C356 'Q_CAP_C0402-0.1UF,16V,10%,X7R,CH4103K1B08':;

SECTION_NUMBER 1
 '@T6G_MB_LIB.T6G(SCH_1):PAGE82_I107@PURE_QUANTA.Q_CAP(CHIPS)':
 C_PATH='@t6g_mb_lib.t6g(sch_1):page82_i107@pure_quanta.q_cap(chips)',
 P_PATH='@t6g_mb_lib.t6g(sch_1):page83_i107@pure_quanta.q_cap(chips)',
 PATH='I107',
 DRAWING='@T6G_MB_LIB.T6G(SCH_1):PAGE82',
 TOLERANCE='10%',
 MATERIAL='X7R',
 PHYS_PAGE='83',
 XY='(-1200,1125)',
 ROT='0',
 VER='2',
 PACK_TYPE='C0402',
 LOCATION='C356',
 CDS_LIB='pure_quanta',
 CDS_PART_NAME='Q_CAP_C0402-0.1UF,16V,10%,X7R,CH4103K1B08',
 VOLTAGE='16V',
 PART_NUMBER='CH4103K1B08',
 VALUE='0.1UF',
 PRIM_FILE='./archive_libs/logical/q_cap/chips/chips.prt';

PART_NAME
 C357 'Q_CAP_C0402-0.1UF,16V,10%,X7R,CH4103K1B08':;

SECTION_NUMBER 1
 '@T6G_MB_LIB.T6G(SCH_1):PAGE82_I106@PURE_QUANTA.Q_CAP(CHIPS)':
 C_PATH='@t6g_mb_lib.t6g(sch_1):page82_i106@pure_quanta.q_cap(chips)',
 P_PATH='@t6g_mb_lib.t6g(sch_1):page83_i106@pure_quanta.q_cap(chips)',
 PATH='I106',
 DRAWING='@T6G_MB_LIB.T6G(SCH_1):PAGE82',
 TOLERANCE='10%',
 MATERIAL='X7R',
 PHYS_PAGE='83',
 XY='(-1200,1025)',
 ROT='0',
 VER='2',
 PACK_TYPE='C0402',
 LOCATION='C357',
 CDS_LIB='pure_quanta',
 CDS_PART_NAME='Q_CAP_C0402-0.1UF,16V,10%,X7R,CH4103K1B08',
 VOLTAGE='16V',
 PART_NUMBER='CH4103K1B08',
 VALUE='0.1UF',
 PRIM_FILE='./archive_libs/logical/q_cap/chips/chips.prt';

PART_NAME
 C358 'Q_CAP_C0402-0.1UF,16V,10%,X7R,CH4103K1B08':;

SECTION_NUMBER 1
 '@T6G_MB_LIB.T6G(SCH_1):PAGE82_I105@PURE_QUANTA.Q_CAP(CHIPS)':
 C_PATH='@t6g_mb_lib.t6g(sch_1):page82_i105@pure_quanta.q_cap(chips)',
 P_PATH='@t6g_mb_lib.t6g(sch_1):page83_i105@pure_quanta.q_cap(chips)',
 PATH='I105',
 DRAWING='@T6G_MB_LIB.T6G(SCH_1):PAGE82',
 TOLERANCE='10%',
 MATERIAL='X7R',
 PHYS_PAGE='83',
 XY='(-1200,925)',
 ROT='0',
 VER='2',
 PACK_TYPE='C0402',
 LOCATION='C358',
 CDS_LIB='pure_quanta',
 CDS_PART_NAME='Q_CAP_C0402-0.1UF,16V,10%,X7R,CH4103K1B08',
 VOLTAGE='16V',
 PART_NUMBER='CH4103K1B08',
 VALUE='0.1UF',
 PRIM_FILE='./archive_libs/logical/q_cap/chips/chips.prt';

PART_NAME
 C359 'Q_CAP_C0402-0.1UF,16V,10%,X7R,CH4103K1B08':;

SECTION_NUMBER 1
 '@T6G_MB_LIB.T6G(SCH_1):PAGE82_I135@PURE_QUANTA.Q_CAP(CHIPS)':
 C_PATH='@t6g_mb_lib.t6g(sch_1):page82_i135@pure_quanta.q_cap(chips)',
 P_PATH='@t6g_mb_lib.t6g(sch_1):page83_i135@pure_quanta.q_cap(chips)',
 PATH='I135',
 DRAWING='@T6G_MB_LIB.T6G(SCH_1):PAGE82',
 TOLERANCE='10%',
 MATERIAL='X7R',
 PHYS_PAGE='83',
 XY='(-1200,825)',
 ROT='0',
 VER='2',
 PACK_TYPE='C0402',
 LOCATION='C359',
 CDS_LIB='pure_quanta',
 CDS_PART_NAME='Q_CAP_C0402-0.1UF,16V,10%,X7R,CH4103K1B08',
 VOLTAGE='16V',
 PART_NUMBER='CH4103K1B08',
 VALUE='0.1UF',
 PRIM_FILE='./archive_libs/logical/q_cap/chips/chips.prt';

PART_NAME
 C360 'Q_CAP_C0402-0.1UF,16V,10%,X7R,CH4103K1B08':;

SECTION_NUMBER 1
 '@T6G_MB_LIB.T6G(SCH_1):PAGE82_I103@PURE_QUANTA.Q_CAP(CHIPS)':
 C_PATH='@t6g_mb_lib.t6g(sch_1):page82_i103@pure_quanta.q_cap(chips)',
 P_PATH='@t6g_mb_lib.t6g(sch_1):page83_i103@pure_quanta.q_cap(chips)',
 PATH='I103',
 DRAWING='@T6G_MB_LIB.T6G(SCH_1):PAGE82',
 TOLERANCE='10%',
 MATERIAL='X7R',
 PHYS_PAGE='83',
 XY='(-1200,725)',
 ROT='0',
 VER='2',
 PACK_TYPE='C0402',
 LOCATION='C360',
 CDS_LIB='pure_quanta',
 CDS_PART_NAME='Q_CAP_C0402-0.1UF,16V,10%,X7R,CH4103K1B08',
 VOLTAGE='16V',
 PART_NUMBER='CH4103K1B08',
 VALUE='0.1UF',
 PRIM_FILE='./archive_libs/logical/q_cap/chips/chips.prt';

PART_NAME
 C361 'Q_CAP_C0402-0.1UF,16V,10%,X7R,CH4103K1B08':;

SECTION_NUMBER 1
 '@T6G_MB_LIB.T6G(SCH_1):PAGE82_I104@PURE_QUANTA.Q_CAP(CHIPS)':
 C_PATH='@t6g_mb_lib.t6g(sch_1):page82_i104@pure_quanta.q_cap(chips)',
 P_PATH='@t6g_mb_lib.t6g(sch_1):page83_i104@pure_quanta.q_cap(chips)',
 PATH='I104',
 DRAWING='@T6G_MB_LIB.T6G(SCH_1):PAGE82',
 TOLERANCE='10%',
 MATERIAL='X7R',
 PHYS_PAGE='83',
 XY='(-1200,625)',
 ROT='0',
 VER='2',
 PACK_TYPE='C0402',
 LOCATION='C361',
 CDS_LIB='pure_quanta',
 CDS_PART_NAME='Q_CAP_C0402-0.1UF,16V,10%,X7R,CH4103K1B08',
 VOLTAGE='16V',
 PART_NUMBER='CH4103K1B08',
 VALUE='0.1UF',
 PRIM_FILE='./archive_libs/logical/q_cap/chips/chips.prt';

PART_NAME
 C362 'Q_CAP_C0402-0.1UF,16V,10%,X7R,CH4103K1B08':;

SECTION_NUMBER 1
 '@T6G_MB_LIB.T6G(SCH_1):PAGE82_I102@PURE_QUANTA.Q_CAP(CHIPS)':
 C_PATH='@t6g_mb_lib.t6g(sch_1):page82_i102@pure_quanta.q_cap(chips)',
 P_PATH='@t6g_mb_lib.t6g(sch_1):page83_i102@pure_quanta.q_cap(chips)',
 PATH='I102',
 DRAWING='@T6G_MB_LIB.T6G(SCH_1):PAGE82',
 TOLERANCE='10%',
 MATERIAL='X7R',
 PHYS_PAGE='83',
 XY='(-1200,525)',
 ROT='0',
 VER='2',
 PACK_TYPE='C0402',
 LOCATION='C362',
 CDS_LIB='pure_quanta',
 CDS_PART_NAME='Q_CAP_C0402-0.1UF,16V,10%,X7R,CH4103K1B08',
 VOLTAGE='16V',
 PART_NUMBER='CH4103K1B08',
 VALUE='0.1UF',
 PRIM_FILE='./archive_libs/logical/q_cap/chips/chips.prt';

PART_NAME
 C363 'Q_CAP_C0402-220PF,50V,5%,C0G,CH12206JB00':;

SECTION_NUMBER 1
 '@T6G_MB_LIB.T6G(SCH_1):PAGE141_I190@PURE_QUANTA.Q_CAP(CHIPS)':
 C_PATH='@t6g_mb_lib.t6g(sch_1):page141_i190@pure_quanta.q_cap(chips)',
 P_PATH='@t6g_mb_lib.t6g(sch_1):page164_i190@pure_quanta.q_cap(chips)',
 PATH='I190',
 DRAWING='@T6G_MB_LIB.T6G(SCH_1):PAGE141',
 TOLERANCE='5%',
 MATERIAL='C0G',
 PHYS_PAGE='164',
 XY='(-2775,1150)',
 ROT='0',
 VER='1',
 PACK_TYPE='C0402',
 LOCATION='C363',
 CDS_LIB='pure_quanta',
 CDS_PART_NAME='Q_CAP_C0402-220PF,50V,5%,C0G,CH12206JB00',
 VOLTAGE='50V',
 PART_NUMBER='CH12206JB00',
 VALUE='220PF',
 PRIM_FILE='./archive_libs/logical/q_cap/chips/chips.prt';

PART_NAME
 C364 'Q_CAP_C0402-220PF,50V,5%,C0G,CH12206JB00':;

SECTION_NUMBER 1
 '@T6G_MB_LIB.T6G(SCH_1):PAGE141_I187@PURE_QUANTA.Q_CAP(CHIPS)':
 C_PATH='@t6g_mb_lib.t6g(sch_1):page141_i187@pure_quanta.q_cap(chips)',
 P_PATH='@t6g_mb_lib.t6g(sch_1):page164_i187@pure_quanta.q_cap(chips)',
 PATH='I187',
 DRAWING='@T6G_MB_LIB.T6G(SCH_1):PAGE141',
 TOLERANCE='5%',
 MATERIAL='C0G',
 PHYS_PAGE='164',
 XY='(-2575,1150)',
 ROT='0',
 VER='1',
 PACK_TYPE='C0402',
 LOCATION='C364',
 CDS_LIB='pure_quanta',
 CDS_PART_NAME='Q_CAP_C0402-220PF,50V,5%,C0G,CH12206JB00',
 VOLTAGE='50V',
 PART_NUMBER='CH12206JB00',
 VALUE='220PF',
 PRIM_FILE='./archive_libs/logical/q_cap/chips/chips.prt';

PART_NAME
 C365 'Q_CAP_C0201-0.1UF,10V,10%,X7S,CH4102K6E00':;

SECTION_NUMBER 1
 '@T6G_MB_LIB.T6G(SCH_1):PAGE377_I55@PURE_QUANTA.Q_CAP(CHIPS)':
 C_PATH='@t6g_mb_lib.t6g(sch_1):page377_i55@pure_quanta.q_cap(chips)',
 P_PATH='@t6g_mb_lib.t6g(sch_1):page185_i55@pure_quanta.q_cap(chips)',
 PATH='I55',
 DRAWING='@T6G_MB_LIB.T6G(SCH_1):PAGE377',
 TOLERANCE='10%',
 MATERIAL='X7S',
 PHYS_PAGE='185',
 XY='(-5575,6200)',
 ROT='2',
 VER='1',
 PACK_TYPE='C0201',
 LOCATION='C365',
 CDS_LIB='pure_quanta',
 CDS_PART_NAME='Q_CAP_C0201-0.1UF,10V,10%,X7S,CH4102K6E00',
 VOLTAGE='10V',
 PART_NUMBER='CH4102K6E00',
 VALUE='0.1UF',
 PRIM_FILE='./archive_libs/logical/q_cap/chips/chips.prt';

PART_NAME
 C366 'Q_CAP_C0805-100UF,4V,20%,X6S,CH710KMEA01':;

SECTION_NUMBER 1
 '@T6G_MB_LIB.T6G(SCH_1):PAGE454_I24@PURE_QUANTA.Q_CAP(CHIPS)':
 C_PATH='@t6g_mb_lib.t6g(sch_1):page454_i24@pure_quanta.q_cap(chips)',
 P_PATH='@t6g_mb_lib.t6g(sch_1):page345_i24@pure_quanta.q_cap(chips)',
 PATH='I24',
 DRAWING='@T6G_MB_LIB.T6G(SCH_1):PAGE454',
 TOLERANCE='20%',
 MATERIAL='X6S',
 PHYS_PAGE='345',
 XY='(-7000,5150)',
 ROT='0',
 VER='1',
 PACK_TYPE='C0805',
 LOCATION='C366',
 CDS_LIB='pure_quanta',
 CDS_PART_NAME='Q_CAP_C0805-100UF,4V,20%,X6S,CH710KMEA01',
 VOLTAGE='4V',
 PART_NUMBER='CH710KMEA01',
 VALUE='100UF',
 PRIM_FILE='./archive_libs/logical/q_cap/chips/chips.prt';

PART_NAME
 C367 'Q_CAP_C0805-100UF,4V,20%,X6S,CH710KMEA01':;

SECTION_NUMBER 1
 '@T6G_MB_LIB.T6G(SCH_1):PAGE454_I5@PURE_QUANTA.Q_CAP(CHIPS)':
 C_PATH='@t6g_mb_lib.t6g(sch_1):page454_i5@pure_quanta.q_cap(chips)',
 P_PATH='@t6g_mb_lib.t6g(sch_1):page345_i5@pure_quanta.q_cap(chips)',
 PATH='I5',
 DRAWING='@T6G_MB_LIB.T6G(SCH_1):PAGE454',
 TOLERANCE='20%',
 MATERIAL='X6S',
 PHYS_PAGE='345',
 XY='(-7150,4325)',
 ROT='0',
 VER='1',
 PACK_TYPE='C0805',
 LOCATION='C367',
 CDS_LIB='pure_quanta',
 CDS_PART_NAME='Q_CAP_C0805-100UF,4V,20%,X6S,CH710KMEA01',
 VOLTAGE='4V',
 PART_NUMBER='CH710KMEA01',
 VALUE='100UF',
 PRIM_FILE='./archive_libs/logical/q_cap/chips/chips.prt';

PART_NAME
 C368 'Q_CAP_C0402-22UF,4V,20%,X6S,CH622KMEB02':;

SECTION_NUMBER 1
 '@T6G_MB_LIB.T6G(SCH_1):PAGE454_I25@PURE_QUANTA.Q_CAP(CHIPS)':
 C_PATH='@t6g_mb_lib.t6g(sch_1):page454_i25@pure_quanta.q_cap(chips)',
 P_PATH='@t6g_mb_lib.t6g(sch_1):page345_i25@pure_quanta.q_cap(chips)',
 PATH='I25',
 DRAWING='@T6G_MB_LIB.T6G(SCH_1):PAGE454',
 TOLERANCE='20%',
 MATERIAL='X6S',
 PHYS_PAGE='345',
 XY='(-6750,5150)',
 ROT='0',
 VER='1',
 PACK_TYPE='C0402',
 LOCATION='C368',
 CDS_LIB='pure_quanta',
 CDS_PART_NAME='Q_CAP_C0402-22UF,4V,20%,X6S,CH622KMEB02',
 VOLTAGE='4V',
 PART_NUMBER='CH622KMEB02',
 VALUE='22UF',
 PRIM_FILE='./archive_libs/logical/q_cap/chips/chips.prt';

PART_NAME
 C369 'Q_CAP_C0402-22UF,4V,20%,X6S,CH622KMEB02':;

SECTION_NUMBER 1
 '@T6G_MB_LIB.T6G(SCH_1):PAGE454_I10@PURE_QUANTA.Q_CAP(CHIPS)':
 C_PATH='@t6g_mb_lib.t6g(sch_1):page454_i10@pure_quanta.q_cap(chips)',
 P_PATH='@t6g_mb_lib.t6g(sch_1):page345_i10@pure_quanta.q_cap(chips)',
 PATH='I10',
 DRAWING='@T6G_MB_LIB.T6G(SCH_1):PAGE454',
 TOLERANCE='20%',
 MATERIAL='X6S',
 PHYS_PAGE='345',
 XY='(-6925,4325)',
 ROT='0',
 VER='1',
 PACK_TYPE='C0402',
 LOCATION='C369',
 CDS_LIB='pure_quanta',
 CDS_PART_NAME='Q_CAP_C0402-22UF,4V,20%,X6S,CH622KMEB02',
 VOLTAGE='4V',
 PART_NUMBER='CH622KMEB02',
 VALUE='22UF',
 PRIM_FILE='./archive_libs/logical/q_cap/chips/chips.prt';

PART_NAME
 C370 'Q_CAP_C0402-10UF,6.3V,20%,X6S,CH6101MEB01':;

SECTION_NUMBER 1
 '@T6G_MB_LIB.T6G(SCH_1):PAGE454_I27@PURE_QUANTA.Q_CAP(CHIPS)':
 C_PATH='@t6g_mb_lib.t6g(sch_1):page454_i27@pure_quanta.q_cap(chips)',
 P_PATH='@t6g_mb_lib.t6g(sch_1):page345_i27@pure_quanta.q_cap(chips)',
 PATH='I27',
 DRAWING='@T6G_MB_LIB.T6G(SCH_1):PAGE454',
 TOLERANCE='20%',
 MATERIAL='X6S',
 PHYS_PAGE='345',
 XY='(-6500,5125)',
 ROT='0',
 VER='1',
 PACK_TYPE='C0402',
 LOCATION='C370',
 CDS_LIB='pure_quanta',
 CDS_PART_NAME='Q_CAP_C0402-10UF,6.3V,20%,X6S,CH6101MEB01',
 VOLTAGE='6.3V',
 PART_NUMBER='CH6101MEB01',
 VALUE='10UF',
 PRIM_FILE='./archive_libs/logical/q_cap/chips/chips.prt';

PART_NAME
 C371 'Q_CAP_0402-4.7UF,6.3V,20%,X6S,CH5471MEB01':;

SECTION_NUMBER 1
 '@T6G_MB_LIB.T6G(SCH_1):PAGE454_I12@PURE_QUANTA.Q_CAP(CHIPS)':
 C_PATH='@t6g_mb_lib.t6g(sch_1):page454_i12@pure_quanta.q_cap(chips)',
 P_PATH='@t6g_mb_lib.t6g(sch_1):page345_i12@pure_quanta.q_cap(chips)',
 PATH='I12',
 DRAWING='@T6G_MB_LIB.T6G(SCH_1):PAGE454',
 TOLERANCE='20%',
 MATERIAL='X6S',
 PHYS_PAGE='345',
 XY='(-6525,4325)',
 ROT='0',
 VER='1',
 PACK_TYPE='0402',
 LOCATION='C371',
 CDS_LIB='pure_quanta',
 CDS_PART_NAME='Q_CAP_0402-4.7UF,6.3V,20%,X6S,CH5471MEB01',
 VOLTAGE='6.3V',
 PART_NUMBER='CH5471MEB01',
 VALUE='4.7UF',
 PRIM_FILE='./archive_libs/logical/q_cap/chips/chips.prt';

PART_NAME
 C372 'Q_CAP_C0402-10UF,6.3V,20%,X6S,CH6101MEB01':;

SECTION_NUMBER 1
 '@T6G_MB_LIB.T6G(SCH_1):PAGE454_I11@PURE_QUANTA.Q_CAP(CHIPS)':
 C_PATH='@t6g_mb_lib.t6g(sch_1):page454_i11@pure_quanta.q_cap(chips)',
 P_PATH='@t6g_mb_lib.t6g(sch_1):page345_i11@pure_quanta.q_cap(chips)',
 PATH='I11',
 DRAWING='@T6G_MB_LIB.T6G(SCH_1):PAGE454',
 TOLERANCE='20%',
 MATERIAL='X6S',
 PHYS_PAGE='345',
 XY='(-6725,4325)',
 ROT='0',
 VER='1',
 PACK_TYPE='C0402',
 LOCATION='C372',
 CDS_LIB='pure_quanta',
 CDS_PART_NAME='Q_CAP_C0402-10UF,6.3V,20%,X6S,CH6101MEB01',
 VOLTAGE='6.3V',
 PART_NUMBER='CH6101MEB01',
 VALUE='10UF',
 PRIM_FILE='./archive_libs/logical/q_cap/chips/chips.prt';

PART_NAME
 C373 'Q_CAP_0402-4.7UF,6.3V,20%,X6S,CH5471MEB01':;

SECTION_NUMBER 1
 '@T6G_MB_LIB.T6G(SCH_1):PAGE454_I28@PURE_QUANTA.Q_CAP(CHIPS)':
 C_PATH='@t6g_mb_lib.t6g(sch_1):page454_i28@pure_quanta.q_cap(chips)',
 P_PATH='@t6g_mb_lib.t6g(sch_1):page345_i28@pure_quanta.q_cap(chips)',
 PATH='I28',
 DRAWING='@T6G_MB_LIB.T6G(SCH_1):PAGE454',
 TOLERANCE='20%',
 MATERIAL='X6S',
 PHYS_PAGE='345',
 XY='(-6250,5125)',
 ROT='0',
 VER='1',
 PACK_TYPE='0402',
 LOCATION='C373',
 CDS_LIB='pure_quanta',
 CDS_PART_NAME='Q_CAP_0402-4.7UF,6.3V,20%,X6S,CH5471MEB01',
 VOLTAGE='6.3V',
 PART_NUMBER='CH5471MEB01',
 VALUE='4.7UF',
 PRIM_FILE='./archive_libs/logical/q_cap/chips/chips.prt';

PART_NAME
 C374 'Q_CAP_0201-1UF,4V,20%,X6S,CH-10KMEE00':;

SECTION_NUMBER 1
 '@T6G_MB_LIB.T6G(SCH_1):PAGE454_I13@PURE_QUANTA.Q_CAP(CHIPS)':
 C_PATH='@t6g_mb_lib.t6g(sch_1):page454_i13@pure_quanta.q_cap(chips)',
 P_PATH='@t6g_mb_lib.t6g(sch_1):page345_i13@pure_quanta.q_cap(chips)',
 PATH='I13',
 DRAWING='@T6G_MB_LIB.T6G(SCH_1):PAGE454',
 TOLERANCE='20%',
 MATERIAL='X6S',
 PHYS_PAGE='345',
 XY='(-6300,4325)',
 ROT='0',
 VER='1',
 PACK_TYPE='0201',
 LOCATION='C374',
 CDS_LIB='pure_quanta',
 CDS_PART_NAME='Q_CAP_0201-1UF,4V,20%,X6S,CH-10KMEE00',
 VOLTAGE='4V',
 PART_NUMBER='CH-10KMEE00',
 VALUE='1UF',
 PRIM_FILE='./archive_libs/logical/q_cap/chips/chips.prt';

PART_NAME
 C375 'Q_CAP_0201-1UF,4V,20%,X6S,CH-10KMEE00':;

SECTION_NUMBER 1
 '@T6G_MB_LIB.T6G(SCH_1):PAGE454_I6@PURE_QUANTA.Q_CAP(CHIPS)':
 C_PATH='@t6g_mb_lib.t6g(sch_1):page454_i6@pure_quanta.q_cap(chips)',
 P_PATH='@t6g_mb_lib.t6g(sch_1):page345_i6@pure_quanta.q_cap(chips)',
 PATH='I6',
 DRAWING='@T6G_MB_LIB.T6G(SCH_1):PAGE454',
 TOLERANCE='20%',
 MATERIAL='X6S',
 PHYS_PAGE='345',
 XY='(-6725,3250)',
 ROT='0',
 VER='1',
 PACK_TYPE='0201',
 LOCATION='C375',
 CDS_LIB='pure_quanta',
 CDS_PART_NAME='Q_CAP_0201-1UF,4V,20%,X6S,CH-10KMEE00',
 VOLTAGE='4V',
 PART_NUMBER='CH-10KMEE00',
 VALUE='1UF',
 PRIM_FILE='./archive_libs/logical/q_cap/chips/chips.prt';

PART_NAME
 C376 'Q_CAP_0201-1UF,4V,20%,X6S,CH-10KMEE00':;

SECTION_NUMBER 1
 '@T6G_MB_LIB.T6G(SCH_1):PAGE454_I15@PURE_QUANTA.Q_CAP(CHIPS)':
 C_PATH='@t6g_mb_lib.t6g(sch_1):page454_i15@pure_quanta.q_cap(chips)',
 P_PATH='@t6g_mb_lib.t6g(sch_1):page345_i15@pure_quanta.q_cap(chips)',
 PATH='I15',
 DRAWING='@T6G_MB_LIB.T6G(SCH_1):PAGE454',
 TOLERANCE='20%',
 MATERIAL='X6S',
 PHYS_PAGE='345',
 XY='(-6100,4325)',
 ROT='0',
 VER='1',
 PACK_TYPE='0201',
 LOCATION='C376',
 CDS_LIB='pure_quanta',
 CDS_PART_NAME='Q_CAP_0201-1UF,4V,20%,X6S,CH-10KMEE00',
 VOLTAGE='4V',
 PART_NUMBER='CH-10KMEE00',
 VALUE='1UF',
 PRIM_FILE='./archive_libs/logical/q_cap/chips/chips.prt';

PART_NAME
 C377 'Q_CAP_C0201-0.1UF,10V,10%,X7S,CH4102K6E00':;

SECTION_NUMBER 1
 '@T6G_MB_LIB.T6G(SCH_1):PAGE454_I16@PURE_QUANTA.Q_CAP(CHIPS)':
 C_PATH='@t6g_mb_lib.t6g(sch_1):page454_i16@pure_quanta.q_cap(chips)',
 P_PATH='@t6g_mb_lib.t6g(sch_1):page345_i16@pure_quanta.q_cap(chips)',
 PATH='I16',
 DRAWING='@T6G_MB_LIB.T6G(SCH_1):PAGE454',
 TOLERANCE='10%',
 MATERIAL='X7S',
 PHYS_PAGE='345',
 XY='(-5875,4325)',
 ROT='0',
 VER='1',
 PACK_TYPE='C0201',
 LOCATION='C377',
 CDS_LIB='pure_quanta',
 CDS_PART_NAME='Q_CAP_C0201-0.1UF,10V,10%,X7S,CH4102K6E00',
 VOLTAGE='10V',
 PART_NUMBER='CH4102K6E00',
 VALUE='0.1UF',
 PRIM_FILE='./archive_libs/logical/q_cap/chips/chips.prt';

PART_NAME
 C378 'Q_CAP_C0201-0.1UF,10V,10%,X7S,CH4102K6E00':;

SECTION_NUMBER 1
 '@T6G_MB_LIB.T6G(SCH_1):PAGE454_I8@PURE_QUANTA.Q_CAP(CHIPS)':
 C_PATH='@t6g_mb_lib.t6g(sch_1):page454_i8@pure_quanta.q_cap(chips)',
 P_PATH='@t6g_mb_lib.t6g(sch_1):page345_i8@pure_quanta.q_cap(chips)',
 PATH='I8',
 DRAWING='@T6G_MB_LIB.T6G(SCH_1):PAGE454',
 TOLERANCE='10%',
 MATERIAL='X7S',
 PHYS_PAGE='345',
 XY='(-6450,3225)',
 ROT='0',
 VER='1',
 PACK_TYPE='C0201',
 LOCATION='C378',
 CDS_LIB='pure_quanta',
 CDS_PART_NAME='Q_CAP_C0201-0.1UF,10V,10%,X7S,CH4102K6E00',
 VOLTAGE='10V',
 PART_NUMBER='CH4102K6E00',
 VALUE='0.1UF',
 PRIM_FILE='./archive_libs/logical/q_cap/chips/chips.prt';

PART_NAME
 C379 'Q_CAP_C0201-0.1UF,10V,10%,X7S,CH4102K6E00':;

SECTION_NUMBER 1
 '@T6G_MB_LIB.T6G(SCH_1):PAGE454_I17@PURE_QUANTA.Q_CAP(CHIPS)':
 C_PATH='@t6g_mb_lib.t6g(sch_1):page454_i17@pure_quanta.q_cap(chips)',
 P_PATH='@t6g_mb_lib.t6g(sch_1):page345_i17@pure_quanta.q_cap(chips)',
 PATH='I17',
 DRAWING='@T6G_MB_LIB.T6G(SCH_1):PAGE454',
 TOLERANCE='10%',
 MATERIAL='X7S',
 PHYS_PAGE='345',
 XY='(-5625,4325)',
 ROT='0',
 VER='1',
 PACK_TYPE='C0201',
 LOCATION='C379',
 CDS_LIB='pure_quanta',
 CDS_PART_NAME='Q_CAP_C0201-0.1UF,10V,10%,X7S,CH4102K6E00',
 VOLTAGE='10V',
 PART_NUMBER='CH4102K6E00',
 VALUE='0.1UF',
 PRIM_FILE='./archive_libs/logical/q_cap/chips/chips.prt';

PART_NAME
 C380 'Q_CAP_C0201-0.1UF,10V,10%,X7S,CH4102K6E00':;

SECTION_NUMBER 1
 '@T6G_MB_LIB.T6G(SCH_1):PAGE454_I18@PURE_QUANTA.Q_CAP(CHIPS)':
 C_PATH='@t6g_mb_lib.t6g(sch_1):page454_i18@pure_quanta.q_cap(chips)',
 P_PATH='@t6g_mb_lib.t6g(sch_1):page345_i18@pure_quanta.q_cap(chips)',
 PATH='I18',
 DRAWING='@T6G_MB_LIB.T6G(SCH_1):PAGE454',
 TOLERANCE='10%',
 MATERIAL='X7S',
 PHYS_PAGE='345',
 XY='(-5375,4325)',
 ROT='0',
 VER='1',
 PACK_TYPE='C0201',
 LOCATION='C380',
 CDS_LIB='pure_quanta',
 CDS_PART_NAME='Q_CAP_C0201-0.1UF,10V,10%,X7S,CH4102K6E00',
 VOLTAGE='10V',
 PART_NUMBER='CH4102K6E00',
 VALUE='0.1UF',
 PRIM_FILE='./archive_libs/logical/q_cap/chips/chips.prt';

PART_NAME
 C381 'Q_CAP_C0201-0.1UF,10V,10%,X7S,CH4102K6E00':;

SECTION_NUMBER 1
 '@T6G_MB_LIB.T6G(SCH_1):PAGE454_I19@PURE_QUANTA.Q_CAP(CHIPS)':
 C_PATH='@t6g_mb_lib.t6g(sch_1):page454_i19@pure_quanta.q_cap(chips)',
 P_PATH='@t6g_mb_lib.t6g(sch_1):page345_i19@pure_quanta.q_cap(chips)',
 PATH='I19',
 DRAWING='@T6G_MB_LIB.T6G(SCH_1):PAGE454',
 TOLERANCE='10%',
 MATERIAL='X7S',
 PHYS_PAGE='345',
 XY='(-5100,4325)',
 ROT='0',
 VER='1',
 PACK_TYPE='C0201',
 LOCATION='C381',
 CDS_LIB='pure_quanta',
 CDS_PART_NAME='Q_CAP_C0201-0.1UF,10V,10%,X7S,CH4102K6E00',
 VOLTAGE='10V',
 PART_NUMBER='CH4102K6E00',
 VALUE='0.1UF',
 PRIM_FILE='./archive_libs/logical/q_cap/chips/chips.prt';

PART_NAME
 C382 'Q_CAP_0201-1UF,4V,20%,X6S,CH-10KMEE00':;

SECTION_NUMBER 1
 '@T6G_MB_LIB.T6G(SCH_1):PAGE454_I71@PURE_QUANTA.Q_CAP(CHIPS)':
 C_PATH='@t6g_mb_lib.t6g(sch_1):page454_i71@pure_quanta.q_cap(chips)',
 P_PATH='@t6g_mb_lib.t6g(sch_1):page345_i71@pure_quanta.q_cap(chips)',
 PATH='I71',
 DRAWING='@T6G_MB_LIB.T6G(SCH_1):PAGE454',
 TOLERANCE='20%',
 MATERIAL='X6S',
 PHYS_PAGE='345',
 XY='(-1350,3700)',
 ROT='0',
 VER='1',
 PACK_TYPE='0201',
 LOCATION='C382',
 CDS_LIB='pure_quanta',
 CDS_PART_NAME='Q_CAP_0201-1UF,4V,20%,X6S,CH-10KMEE00',
 VOLTAGE='4V',
 PART_NUMBER='CH-10KMEE00',
 VALUE='1UF',
 PRIM_FILE='./archive_libs/logical/q_cap/chips/chips.prt';

PART_NAME
 C383 'Q_CAP_C0201-0.1UF,10V,10%,X7S,CH4102K6E00':;

SECTION_NUMBER 1
 '@T6G_MB_LIB.T6G(SCH_1):PAGE454_I82@PURE_QUANTA.Q_CAP(CHIPS)':
 C_PATH='@t6g_mb_lib.t6g(sch_1):page454_i82@pure_quanta.q_cap(chips)',
 P_PATH='@t6g_mb_lib.t6g(sch_1):page345_i82@pure_quanta.q_cap(chips)',
 PATH='I82',
 DRAWING='@T6G_MB_LIB.T6G(SCH_1):PAGE454',
 TOLERANCE='10%',
 MATERIAL='X7S',
 PHYS_PAGE='345',
 XY='(-2600,5575)',
 ROT='0',
 VER='1',
 PACK_TYPE='C0201',
 LOCATION='C383',
 CDS_LIB='pure_quanta',
 CDS_PART_NAME='Q_CAP_C0201-0.1UF,10V,10%,X7S,CH4102K6E00',
 VOLTAGE='10V',
 PART_NUMBER='CH4102K6E00',
 VALUE='0.1UF',
 PRIM_FILE='./archive_libs/logical/q_cap/chips/chips.prt';

PART_NAME
 C384 'Q_CAP_0201-1UF,4V,20%,X6S,CH-10KMEE00':;

SECTION_NUMBER 1
 '@T6G_MB_LIB.T6G(SCH_1):PAGE454_I42@PURE_QUANTA.Q_CAP(CHIPS)':
 C_PATH='@t6g_mb_lib.t6g(sch_1):page454_i42@pure_quanta.q_cap(chips)',
 P_PATH='@t6g_mb_lib.t6g(sch_1):page345_i42@pure_quanta.q_cap(chips)',
 PATH='I42',
 DRAWING='@T6G_MB_LIB.T6G(SCH_1):PAGE454',
 TOLERANCE='20%',
 MATERIAL='X6S',
 PHYS_PAGE='345',
 XY='(-3425,3075)',
 ROT='0',
 VER='1',
 PACK_TYPE='0201',
 LOCATION='C384',
 CDS_LIB='pure_quanta',
 CDS_PART_NAME='Q_CAP_0201-1UF,4V,20%,X6S,CH-10KMEE00',
 VOLTAGE='4V',
 PART_NUMBER='CH-10KMEE00',
 VALUE='1UF',
 PRIM_FILE='./archive_libs/logical/q_cap/chips/chips.prt';

PART_NAME
 C385 'Q_CAP_C0201-0.1UF,10V,10%,X7S,CH4102K6E00':;

SECTION_NUMBER 1
 '@T6G_MB_LIB.T6G(SCH_1):PAGE454_I83@PURE_QUANTA.Q_CAP(CHIPS)':
 C_PATH='@t6g_mb_lib.t6g(sch_1):page454_i83@pure_quanta.q_cap(chips)',
 P_PATH='@t6g_mb_lib.t6g(sch_1):page345_i83@pure_quanta.q_cap(chips)',
 PATH='I83',
 DRAWING='@T6G_MB_LIB.T6G(SCH_1):PAGE454',
 TOLERANCE='10%',
 MATERIAL='X7S',
 PHYS_PAGE='345',
 XY='(-2325,5575)',
 ROT='0',
 VER='1',
 PACK_TYPE='C0201',
 LOCATION='C385',
 CDS_LIB='pure_quanta',
 CDS_PART_NAME='Q_CAP_C0201-0.1UF,10V,10%,X7S,CH4102K6E00',
 VOLTAGE='10V',
 PART_NUMBER='CH4102K6E00',
 VALUE='0.1UF',
 PRIM_FILE='./archive_libs/logical/q_cap/chips/chips.prt';

PART_NAME
 C386 'Q_CAP_0201-1UF,4V,20%,X6S,CH-10KMEE00':;

SECTION_NUMBER 1
 '@T6G_MB_LIB.T6G(SCH_1):PAGE454_I58@PURE_QUANTA.Q_CAP(CHIPS)':
 C_PATH='@t6g_mb_lib.t6g(sch_1):page454_i58@pure_quanta.q_cap(chips)',
 P_PATH='@t6g_mb_lib.t6g(sch_1):page345_i58@pure_quanta.q_cap(chips)',
 PATH='I58',
 DRAWING='@T6G_MB_LIB.T6G(SCH_1):PAGE454',
 TOLERANCE='20%',
 MATERIAL='X6S',
 PHYS_PAGE='345',
 XY='(-2050,3700)',
 ROT='0',
 VER='1',
 PACK_TYPE='0201',
 LOCATION='C386',
 CDS_LIB='pure_quanta',
 CDS_PART_NAME='Q_CAP_0201-1UF,4V,20%,X6S,CH-10KMEE00',
 VOLTAGE='4V',
 PART_NUMBER='CH-10KMEE00',
 VALUE='1UF',
 PRIM_FILE='./archive_libs/logical/q_cap/chips/chips.prt';

PART_NAME
 C387 'Q_CAP_0201-1UF,4V,20%,X6S,CH-10KMEE00':;

SECTION_NUMBER 1
 '@T6G_MB_LIB.T6G(SCH_1):PAGE454_I43@PURE_QUANTA.Q_CAP(CHIPS)':
 C_PATH='@t6g_mb_lib.t6g(sch_1):page454_i43@pure_quanta.q_cap(chips)',
 P_PATH='@t6g_mb_lib.t6g(sch_1):page345_i43@pure_quanta.q_cap(chips)',
 PATH='I43',
 DRAWING='@T6G_MB_LIB.T6G(SCH_1):PAGE454',
 TOLERANCE='20%',
 MATERIAL='X6S',
 PHYS_PAGE='345',
 XY='(-3200,3075)',
 ROT='0',
 VER='1',
 PACK_TYPE='0201',
 LOCATION='C387',
 CDS_LIB='pure_quanta',
 CDS_PART_NAME='Q_CAP_0201-1UF,4V,20%,X6S,CH-10KMEE00',
 VOLTAGE='4V',
 PART_NUMBER='CH-10KMEE00',
 VALUE='1UF',
 PRIM_FILE='./archive_libs/logical/q_cap/chips/chips.prt';

PART_NAME
 C388 'Q_CAP_C0201-0.1UF,10V,10%,X7S,CH4102K6E00':;

SECTION_NUMBER 1
 '@T6G_MB_LIB.T6G(SCH_1):PAGE454_I84@PURE_QUANTA.Q_CAP(CHIPS)':
 C_PATH='@t6g_mb_lib.t6g(sch_1):page454_i84@pure_quanta.q_cap(chips)',
 P_PATH='@t6g_mb_lib.t6g(sch_1):page345_i84@pure_quanta.q_cap(chips)',
 PATH='I84',
 DRAWING='@T6G_MB_LIB.T6G(SCH_1):PAGE454',
 TOLERANCE='10%',
 MATERIAL='X7S',
 PHYS_PAGE='345',
 XY='(-2075,5575)',
 ROT='0',
 VER='1',
 PACK_TYPE='C0201',
 LOCATION='C388',
 CDS_LIB='pure_quanta',
 CDS_PART_NAME='Q_CAP_C0201-0.1UF,10V,10%,X7S,CH4102K6E00',
 VOLTAGE='10V',
 PART_NUMBER='CH4102K6E00',
 VALUE='0.1UF',
 PRIM_FILE='./archive_libs/logical/q_cap/chips/chips.prt';

PART_NAME
 C389 'Q_CAP_0201-1UF,4V,20%,X6S,CH-10KMEE00':;

SECTION_NUMBER 1
 '@T6G_MB_LIB.T6G(SCH_1):PAGE454_I68@PURE_QUANTA.Q_CAP(CHIPS)':
 C_PATH='@t6g_mb_lib.t6g(sch_1):page454_i68@pure_quanta.q_cap(chips)',
 P_PATH='@t6g_mb_lib.t6g(sch_1):page345_i68@pure_quanta.q_cap(chips)',
 PATH='I68',
 DRAWING='@T6G_MB_LIB.T6G(SCH_1):PAGE454',
 TOLERANCE='20%',
 MATERIAL='X6S',
 PHYS_PAGE='345',
 XY='(-1600,3700)',
 ROT='0',
 VER='1',
 PACK_TYPE='0201',
 LOCATION='C389',
 CDS_LIB='pure_quanta',
 CDS_PART_NAME='Q_CAP_0201-1UF,4V,20%,X6S,CH-10KMEE00',
 VOLTAGE='4V',
 PART_NUMBER='CH-10KMEE00',
 VALUE='1UF',
 PRIM_FILE='./archive_libs/logical/q_cap/chips/chips.prt';

PART_NAME
 C390 'Q_CAP_0201-1UF,4V,20%,X6S,CH-10KMEE00':;

SECTION_NUMBER 1
 '@T6G_MB_LIB.T6G(SCH_1):PAGE454_I90@PURE_QUANTA.Q_CAP(CHIPS)':
 C_PATH='@t6g_mb_lib.t6g(sch_1):page454_i90@pure_quanta.q_cap(chips)',
 P_PATH='@t6g_mb_lib.t6g(sch_1):page345_i90@pure_quanta.q_cap(chips)',
 PATH='I90',
 DRAWING='@T6G_MB_LIB.T6G(SCH_1):PAGE454',
 TOLERANCE='20%',
 MATERIAL='X6S',
 PHYS_PAGE='345',
 XY='(-2975,1275)',
 ROT='0',
 VER='1',
 PACK_TYPE='0201',
 LOCATION='C390',
 CDS_LIB='pure_quanta',
 CDS_PART_NAME='Q_CAP_0201-1UF,4V,20%,X6S,CH-10KMEE00',
 VOLTAGE='4V',
 PART_NUMBER='CH-10KMEE00',
 VALUE='1UF',
 PRIM_FILE='./archive_libs/logical/q_cap/chips/chips.prt';

PART_NAME
 C391 'Q_CAP_0201-1UF,4V,20%,X6S,CH-10KMEE00':;

SECTION_NUMBER 1
 '@T6G_MB_LIB.T6G(SCH_1):PAGE454_I50@PURE_QUANTA.Q_CAP(CHIPS)':
 C_PATH='@t6g_mb_lib.t6g(sch_1):page454_i50@pure_quanta.q_cap(chips)',
 P_PATH='@t6g_mb_lib.t6g(sch_1):page345_i50@pure_quanta.q_cap(chips)',
 PATH='I50',
 DRAWING='@T6G_MB_LIB.T6G(SCH_1):PAGE454',
 TOLERANCE='20%',
 MATERIAL='X6S',
 PHYS_PAGE='345',
 XY='(-2725,3075)',
 ROT='0',
 VER='1',
 PACK_TYPE='0201',
 LOCATION='C391',
 CDS_LIB='pure_quanta',
 CDS_PART_NAME='Q_CAP_0201-1UF,4V,20%,X6S,CH-10KMEE00',
 VOLTAGE='4V',
 PART_NUMBER='CH-10KMEE00',
 VALUE='1UF',
 PRIM_FILE='./archive_libs/logical/q_cap/chips/chips.prt';

PART_NAME
 C392 'Q_CAP_C0201-0.1UF,10V,10%,X7S,CH4102K6E00':;

SECTION_NUMBER 1
 '@T6G_MB_LIB.T6G(SCH_1):PAGE454_I85@PURE_QUANTA.Q_CAP(CHIPS)':
 C_PATH='@t6g_mb_lib.t6g(sch_1):page454_i85@pure_quanta.q_cap(chips)',
 P_PATH='@t6g_mb_lib.t6g(sch_1):page345_i85@pure_quanta.q_cap(chips)',
 PATH='I85',
 DRAWING='@T6G_MB_LIB.T6G(SCH_1):PAGE454',
 TOLERANCE='10%',
 MATERIAL='X7S',
 PHYS_PAGE='345',
 XY='(-1800,5575)',
 ROT='0',
 VER='1',
 PACK_TYPE='C0201',
 LOCATION='C392',
 CDS_LIB='pure_quanta',
 CDS_PART_NAME='Q_CAP_C0201-0.1UF,10V,10%,X7S,CH4102K6E00',
 VOLTAGE='10V',
 PART_NUMBER='CH4102K6E00',
 VALUE='0.1UF',
 PRIM_FILE='./archive_libs/logical/q_cap/chips/chips.prt';

PART_NAME
 C393 'Q_CAP_C0201-0.1UF,10V,10%,X7S,CH4102K6E00':;

SECTION_NUMBER 1
 '@T6G_MB_LIB.T6G(SCH_1):PAGE454_I38@PURE_QUANTA.Q_CAP(CHIPS)':
 C_PATH='@t6g_mb_lib.t6g(sch_1):page454_i38@pure_quanta.q_cap(chips)',
 P_PATH='@t6g_mb_lib.t6g(sch_1):page345_i38@pure_quanta.q_cap(chips)',
 PATH='I38',
 DRAWING='@T6G_MB_LIB.T6G(SCH_1):PAGE454',
 TOLERANCE='10%',
 MATERIAL='X7S',
 PHYS_PAGE='345',
 XY='(-2625,2375)',
 ROT='0',
 VER='1',
 PACK_TYPE='C0201',
 LOCATION='C393',
 CDS_LIB='pure_quanta',
 CDS_PART_NAME='Q_CAP_C0201-0.1UF,10V,10%,X7S,CH4102K6E00',
 VOLTAGE='10V',
 PART_NUMBER='CH4102K6E00',
 VALUE='0.1UF',
 PRIM_FILE='./archive_libs/logical/q_cap/chips/chips.prt';

PART_NAME
 C394 'Q_CAP_0201-1UF,4V,20%,X6S,CH-10KMEE00':;

SECTION_NUMBER 1
 '@T6G_MB_LIB.T6G(SCH_1):PAGE454_I91@PURE_QUANTA.Q_CAP(CHIPS)':
 C_PATH='@t6g_mb_lib.t6g(sch_1):page454_i91@pure_quanta.q_cap(chips)',
 P_PATH='@t6g_mb_lib.t6g(sch_1):page345_i91@pure_quanta.q_cap(chips)',
 PATH='I91',
 DRAWING='@T6G_MB_LIB.T6G(SCH_1):PAGE454',
 TOLERANCE='20%',
 MATERIAL='X6S',
 PHYS_PAGE='345',
 XY='(-2725,1275)',
 ROT='0',
 VER='1',
 PACK_TYPE='0201',
 LOCATION='C394',
 CDS_LIB='pure_quanta',
 CDS_PART_NAME='Q_CAP_0201-1UF,4V,20%,X6S,CH-10KMEE00',
 VOLTAGE='4V',
 PART_NUMBER='CH-10KMEE00',
 VALUE='1UF',
 PRIM_FILE='./archive_libs/logical/q_cap/chips/chips.prt';

PART_NAME
 C395 'Q_CAP_C0201-0.1UF,10V,10%,X7S,CH4102K6E00':;

SECTION_NUMBER 1
 '@T6G_MB_LIB.T6G(SCH_1):PAGE454_I64@PURE_QUANTA.Q_CAP(CHIPS)':
 C_PATH='@t6g_mb_lib.t6g(sch_1):page454_i64@pure_quanta.q_cap(chips)',
 P_PATH='@t6g_mb_lib.t6g(sch_1):page345_i64@pure_quanta.q_cap(chips)',
 PATH='I64',
 DRAWING='@T6G_MB_LIB.T6G(SCH_1):PAGE454',
 TOLERANCE='10%',
 MATERIAL='X7S',
 PHYS_PAGE='345',
 XY='(-1325,2375)',
 ROT='0',
 VER='1',
 PACK_TYPE='C0201',
 LOCATION='C395',
 CDS_LIB='pure_quanta',
 CDS_PART_NAME='Q_CAP_C0201-0.1UF,10V,10%,X7S,CH4102K6E00',
 VOLTAGE='10V',
 PART_NUMBER='CH4102K6E00',
 VALUE='0.1UF',
 PRIM_FILE='./archive_libs/logical/q_cap/chips/chips.prt';

PART_NAME
 C396 'Q_CAP_C0201-0.1UF,10V,10%,X7S,CH4102K6E00':;

SECTION_NUMBER 1
 '@T6G_MB_LIB.T6G(SCH_1):PAGE454_I35@PURE_QUANTA.Q_CAP(CHIPS)':
 C_PATH='@t6g_mb_lib.t6g(sch_1):page454_i35@pure_quanta.q_cap(chips)',
 P_PATH='@t6g_mb_lib.t6g(sch_1):page345_i35@pure_quanta.q_cap(chips)',
 PATH='I35',
 DRAWING='@T6G_MB_LIB.T6G(SCH_1):PAGE454',
 TOLERANCE='10%',
 MATERIAL='X7S',
 PHYS_PAGE='345',
 XY='(-2425,1275)',
 ROT='0',
 VER='1',
 PACK_TYPE='C0201',
 LOCATION='C396',
 CDS_LIB='pure_quanta',
 CDS_PART_NAME='Q_CAP_C0201-0.1UF,10V,10%,X7S,CH4102K6E00',
 VOLTAGE='10V',
 PART_NUMBER='CH4102K6E00',
 VALUE='0.1UF',
 PRIM_FILE='./archive_libs/logical/q_cap/chips/chips.prt';

PART_NAME
 C397 'Q_CAP_C0201-0.1UF,10V,10%,X7S,CH4102K6E00':;

SECTION_NUMBER 1
 '@T6G_MB_LIB.T6G(SCH_1):PAGE454_I36@PURE_QUANTA.Q_CAP(CHIPS)':
 C_PATH='@t6g_mb_lib.t6g(sch_1):page454_i36@pure_quanta.q_cap(chips)',
 P_PATH='@t6g_mb_lib.t6g(sch_1):page345_i36@pure_quanta.q_cap(chips)',
 PATH='I36',
 DRAWING='@T6G_MB_LIB.T6G(SCH_1):PAGE454',
 TOLERANCE='10%',
 MATERIAL='X7S',
 PHYS_PAGE='345',
 XY='(-2175,1275)',
 ROT='0',
 VER='1',
 PACK_TYPE='C0201',
 LOCATION='C397',
 CDS_LIB='pure_quanta',
 CDS_PART_NAME='Q_CAP_C0201-0.1UF,10V,10%,X7S,CH4102K6E00',
 VOLTAGE='10V',
 PART_NUMBER='CH4102K6E00',
 VALUE='0.1UF',
 PRIM_FILE='./archive_libs/logical/q_cap/chips/chips.prt';

PART_NAME
 C398 'Q_CAP_C0805-100UF,4V,20%,X6S,CH710KMEA01':;

SECTION_NUMBER 1
 '@T6G_MB_LIB.T6G(SCH_1):PAGE454_I46@PURE_QUANTA.Q_CAP(CHIPS)':
 C_PATH='@t6g_mb_lib.t6g(sch_1):page454_i46@pure_quanta.q_cap(chips)',
 P_PATH='@t6g_mb_lib.t6g(sch_1):page345_i46@pure_quanta.q_cap(chips)',
 PATH='I46',
 DRAWING='@T6G_MB_LIB.T6G(SCH_1):PAGE454',
 TOLERANCE='20%',
 MATERIAL='X6S',
 PHYS_PAGE='345',
 XY='(-3425,4325)',
 ROT='0',
 VER='1',
 PACK_TYPE='C0805',
 LOCATION='C398',
 CDS_LIB='pure_quanta',
 CDS_PART_NAME='Q_CAP_C0805-100UF,4V,20%,X6S,CH710KMEA01',
 VOLTAGE='4V',
 PART_NUMBER='CH710KMEA01',
 VALUE='100UF',
 PRIM_FILE='./archive_libs/logical/q_cap/chips/chips.prt';

PART_NAME
 C399 'Q_CAP_C0402-22UF,4V,20%,X6S,CH622KMEB02':;

SECTION_NUMBER 1
 '@T6G_MB_LIB.T6G(SCH_1):PAGE454_I59@PURE_QUANTA.Q_CAP(CHIPS)':
 C_PATH='@t6g_mb_lib.t6g(sch_1):page454_i59@pure_quanta.q_cap(chips)',
 P_PATH='@t6g_mb_lib.t6g(sch_1):page345_i59@pure_quanta.q_cap(chips)',
 PATH='I59',
 DRAWING='@T6G_MB_LIB.T6G(SCH_1):PAGE454',
 TOLERANCE='20%',
 MATERIAL='X6S',
 PHYS_PAGE='345',
 XY='(-2275,4325)',
 ROT='0',
 VER='1',
 PACK_TYPE='C0402',
 LOCATION='C399',
 CDS_LIB='pure_quanta',
 CDS_PART_NAME='Q_CAP_C0402-22UF,4V,20%,X6S,CH622KMEB02',
 VOLTAGE='4V',
 PART_NUMBER='CH622KMEB02',
 VALUE='22UF',
 PRIM_FILE='./archive_libs/logical/q_cap/chips/chips.prt';

PART_NAME
 C400 'Q_CAP_C0201-0.1UF,10V,10%,X7S,CH4102K6E00':;

SECTION_NUMBER 1
 '@T6G_MB_LIB.T6G(SCH_1):PAGE454_I40@PURE_QUANTA.Q_CAP(CHIPS)':
 C_PATH='@t6g_mb_lib.t6g(sch_1):page454_i40@pure_quanta.q_cap(chips)',
 P_PATH='@t6g_mb_lib.t6g(sch_1):page345_i40@pure_quanta.q_cap(chips)',
 PATH='I40',
 DRAWING='@T6G_MB_LIB.T6G(SCH_1):PAGE454',
 TOLERANCE='10%',
 MATERIAL='X7S',
 PHYS_PAGE='345',
 XY='(-2125,2375)',
 ROT='0',
 VER='1',
 PACK_TYPE='C0201',
 LOCATION='C400',
 CDS_LIB='pure_quanta',
 CDS_PART_NAME='Q_CAP_C0201-0.1UF,10V,10%,X7S,CH4102K6E00',
 VOLTAGE='10V',
 PART_NUMBER='CH4102K6E00',
 VALUE='0.1UF',
 PRIM_FILE='./archive_libs/logical/q_cap/chips/chips.prt';

PART_NAME
 C401 'Q_CAP_C0805-100UF,4V,20%,X6S,CH710KMEA01':;

SECTION_NUMBER 1
 '@T6G_MB_LIB.T6G(SCH_1):PAGE454_I47@PURE_QUANTA.Q_CAP(CHIPS)':
 C_PATH='@t6g_mb_lib.t6g(sch_1):page454_i47@pure_quanta.q_cap(chips)',
 P_PATH='@t6g_mb_lib.t6g(sch_1):page345_i47@pure_quanta.q_cap(chips)',
 PATH='I47',
 DRAWING='@T6G_MB_LIB.T6G(SCH_1):PAGE454',
 TOLERANCE='20%',
 MATERIAL='X6S',
 PHYS_PAGE='345',
 XY='(-3200,4325)',
 ROT='0',
 VER='1',
 PACK_TYPE='C0805',
 LOCATION='C401',
 CDS_LIB='pure_quanta',
 CDS_PART_NAME='Q_CAP_C0805-100UF,4V,20%,X6S,CH710KMEA01',
 VOLTAGE='4V',
 PART_NUMBER='CH710KMEA01',
 VALUE='100UF',
 PRIM_FILE='./archive_libs/logical/q_cap/chips/chips.prt';

PART_NAME
 C402 'Q_CAP_C0402-22UF,4V,20%,X6S,CH622KMEB02':;

SECTION_NUMBER 1
 '@T6G_MB_LIB.T6G(SCH_1):PAGE454_I60@PURE_QUANTA.Q_CAP(CHIPS)':
 C_PATH='@t6g_mb_lib.t6g(sch_1):page454_i60@pure_quanta.q_cap(chips)',
 P_PATH='@t6g_mb_lib.t6g(sch_1):page345_i60@pure_quanta.q_cap(chips)',
 PATH='I60',
 DRAWING='@T6G_MB_LIB.T6G(SCH_1):PAGE454',
 TOLERANCE='20%',
 MATERIAL='X6S',
 PHYS_PAGE='345',
 XY='(-2050,4325)',
 ROT='0',
 VER='1',
 PACK_TYPE='C0402',
 LOCATION='C402',
 CDS_LIB='pure_quanta',
 CDS_PART_NAME='Q_CAP_C0402-22UF,4V,20%,X6S,CH622KMEB02',
 VOLTAGE='4V',
 PART_NUMBER='CH622KMEB02',
 VALUE='22UF',
 PRIM_FILE='./archive_libs/logical/q_cap/chips/chips.prt';

PART_NAME
 C403 'Q_CAP_C0201-0.1UF,10V,10%,X7S,CH4102K6E00':;

SECTION_NUMBER 1
 '@T6G_MB_LIB.T6G(SCH_1):PAGE454_I61@PURE_QUANTA.Q_CAP(CHIPS)':
 C_PATH='@t6g_mb_lib.t6g(sch_1):page454_i61@pure_quanta.q_cap(chips)',
 P_PATH='@t6g_mb_lib.t6g(sch_1):page345_i61@pure_quanta.q_cap(chips)',
 PATH='I61',
 DRAWING='@T6G_MB_LIB.T6G(SCH_1):PAGE454',
 TOLERANCE='10%',
 MATERIAL='X7S',
 PHYS_PAGE='345',
 XY='(-1850,2375)',
 ROT='0',
 VER='1',
 PACK_TYPE='C0201',
 LOCATION='C403',
 CDS_LIB='pure_quanta',
 CDS_PART_NAME='Q_CAP_C0201-0.1UF,10V,10%,X7S,CH4102K6E00',
 VOLTAGE='10V',
 PART_NUMBER='CH4102K6E00',
 VALUE='0.1UF',
 PRIM_FILE='./archive_libs/logical/q_cap/chips/chips.prt';

PART_NAME
 C404 'Q_CAP_C0805-100UF,4V,20%,X6S,CH710KMEA01':;

SECTION_NUMBER 1
 '@T6G_MB_LIB.T6G(SCH_1):PAGE454_I76@PURE_QUANTA.Q_CAP(CHIPS)':
 C_PATH='@t6g_mb_lib.t6g(sch_1):page454_i76@pure_quanta.q_cap(chips)',
 P_PATH='@t6g_mb_lib.t6g(sch_1):page345_i76@pure_quanta.q_cap(chips)',
 PATH='I76',
 DRAWING='@T6G_MB_LIB.T6G(SCH_1):PAGE454',
 TOLERANCE='20%',
 MATERIAL='X6S',
 PHYS_PAGE='345',
 XY='(-4100,5625)',
 ROT='0',
 VER='1',
 PACK_TYPE='C0805',
 LOCATION='C404',
 CDS_LIB='pure_quanta',
 CDS_PART_NAME='Q_CAP_C0805-100UF,4V,20%,X6S,CH710KMEA01',
 VOLTAGE='4V',
 PART_NUMBER='CH710KMEA01',
 VALUE='100UF',
 PRIM_FILE='./archive_libs/logical/q_cap/chips/chips.prt';

PART_NAME
 C405 'Q_CAP_C0805-100UF,4V,20%,X6S,CH710KMEA01':;

SECTION_NUMBER 1
 '@T6G_MB_LIB.T6G(SCH_1):PAGE454_I86@PURE_QUANTA.Q_CAP(CHIPS)':
 C_PATH='@t6g_mb_lib.t6g(sch_1):page454_i86@pure_quanta.q_cap(chips)',
 P_PATH='@t6g_mb_lib.t6g(sch_1):page345_i86@pure_quanta.q_cap(chips)',
 PATH='I86',
 DRAWING='@T6G_MB_LIB.T6G(SCH_1):PAGE454',
 TOLERANCE='20%',
 MATERIAL='X6S',
 PHYS_PAGE='345',
 XY='(-2975,4325)',
 ROT='0',
 VER='1',
 PACK_TYPE='C0805',
 LOCATION='C405',
 CDS_LIB='pure_quanta',
 CDS_PART_NAME='Q_CAP_C0805-100UF,4V,20%,X6S,CH710KMEA01',
 VOLTAGE='4V',
 PART_NUMBER='CH710KMEA01',
 VALUE='100UF',
 PRIM_FILE='./archive_libs/logical/q_cap/chips/chips.prt';

PART_NAME
 C406 'Q_CAP_0402-4.7UF,6.3V,20%,X6S,CH5471MEB01':;

SECTION_NUMBER 1
 '@T6G_MB_LIB.T6G(SCH_1):PAGE454_I48@PURE_QUANTA.Q_CAP(CHIPS)':
 C_PATH='@t6g_mb_lib.t6g(sch_1):page454_i48@pure_quanta.q_cap(chips)',
 P_PATH='@t6g_mb_lib.t6g(sch_1):page345_i48@pure_quanta.q_cap(chips)',
 PATH='I48',
 DRAWING='@T6G_MB_LIB.T6G(SCH_1):PAGE454',
 TOLERANCE='20%',
 MATERIAL='X6S',
 PHYS_PAGE='345',
 XY='(-2975,3700)',
 ROT='0',
 VER='1',
 PACK_TYPE='0402',
 LOCATION='C406',
 CDS_LIB='pure_quanta',
 CDS_PART_NAME='Q_CAP_0402-4.7UF,6.3V,20%,X6S,CH5471MEB01',
 VOLTAGE='6.3V',
 PART_NUMBER='CH5471MEB01',
 VALUE='4.7UF',
 PRIM_FILE='./archive_libs/logical/q_cap/chips/chips.prt';

PART_NAME
 C407 'Q_CAP_0201-1UF,4V,20%,X6S,CH-10KMEE00':;

SECTION_NUMBER 1
 '@T6G_MB_LIB.T6G(SCH_1):PAGE454_I49@PURE_QUANTA.Q_CAP(CHIPS)':
 C_PATH='@t6g_mb_lib.t6g(sch_1):page454_i49@pure_quanta.q_cap(chips)',
 P_PATH='@t6g_mb_lib.t6g(sch_1):page345_i49@pure_quanta.q_cap(chips)',
 PATH='I49',
 DRAWING='@T6G_MB_LIB.T6G(SCH_1):PAGE454',
 TOLERANCE='20%',
 MATERIAL='X6S',
 PHYS_PAGE='345',
 XY='(-2950,3075)',
 ROT='0',
 VER='1',
 PACK_TYPE='0201',
 LOCATION='C407',
 CDS_LIB='pure_quanta',
 CDS_PART_NAME='Q_CAP_0201-1UF,4V,20%,X6S,CH-10KMEE00',
 VOLTAGE='4V',
 PART_NUMBER='CH-10KMEE00',
 VALUE='1UF',
 PRIM_FILE='./archive_libs/logical/q_cap/chips/chips.prt';

PART_NAME
 C408 'Q_CAP_C0402-22UF,4V,20%,X6S,CH622KMEB02':;

SECTION_NUMBER 1
 '@T6G_MB_LIB.T6G(SCH_1):PAGE454_I77@PURE_QUANTA.Q_CAP(CHIPS)':
 C_PATH='@t6g_mb_lib.t6g(sch_1):page454_i77@pure_quanta.q_cap(chips)',
 P_PATH='@t6g_mb_lib.t6g(sch_1):page345_i77@pure_quanta.q_cap(chips)',
 PATH='I77',
 DRAWING='@T6G_MB_LIB.T6G(SCH_1):PAGE454',
 TOLERANCE='20%',
 MATERIAL='X6S',
 PHYS_PAGE='345',
 XY='(-3825,5625)',
 ROT='0',
 VER='1',
 PACK_TYPE='C0402',
 LOCATION='C408',
 CDS_LIB='pure_quanta',
 CDS_PART_NAME='Q_CAP_C0402-22UF,4V,20%,X6S,CH622KMEB02',
 VOLTAGE='4V',
 PART_NUMBER='CH622KMEB02',
 VALUE='22UF',
 PRIM_FILE='./archive_libs/logical/q_cap/chips/chips.prt';

PART_NAME
 C409 'Q_CAP_C0805-100UF,4V,20%,X6S,CH710KMEA01':;

SECTION_NUMBER 1
 '@T6G_MB_LIB.T6G(SCH_1):PAGE454_I87@PURE_QUANTA.Q_CAP(CHIPS)':
 C_PATH='@t6g_mb_lib.t6g(sch_1):page454_i87@pure_quanta.q_cap(chips)',
 P_PATH='@t6g_mb_lib.t6g(sch_1):page345_i87@pure_quanta.q_cap(chips)',
 PATH='I87',
 DRAWING='@T6G_MB_LIB.T6G(SCH_1):PAGE454',
 TOLERANCE='20%',
 MATERIAL='X6S',
 PHYS_PAGE='345',
 XY='(-2750,4325)',
 ROT='0',
 VER='1',
 PACK_TYPE='C0805',
 LOCATION='C409',
 CDS_LIB='pure_quanta',
 CDS_PART_NAME='Q_CAP_C0805-100UF,4V,20%,X6S,CH710KMEA01',
 VOLTAGE='4V',
 PART_NUMBER='CH710KMEA01',
 VALUE='100UF',
 PRIM_FILE='./archive_libs/logical/q_cap/chips/chips.prt';

PART_NAME
 C410 'Q_CAP_C0402-10UF,6.3V,20%,X6S,CH6101MEB01':;

SECTION_NUMBER 1
 '@T6G_MB_LIB.T6G(SCH_1):PAGE454_I44@PURE_QUANTA.Q_CAP(CHIPS)':
 C_PATH='@t6g_mb_lib.t6g(sch_1):page454_i44@pure_quanta.q_cap(chips)',
 P_PATH='@t6g_mb_lib.t6g(sch_1):page345_i44@pure_quanta.q_cap(chips)',
 PATH='I44',
 DRAWING='@T6G_MB_LIB.T6G(SCH_1):PAGE454',
 TOLERANCE='20%',
 MATERIAL='X6S',
 PHYS_PAGE='345',
 XY='(-3425,3700)',
 ROT='0',
 VER='1',
 PACK_TYPE='C0402',
 LOCATION='C410',
 CDS_LIB='pure_quanta',
 CDS_PART_NAME='Q_CAP_C0402-10UF,6.3V,20%,X6S,CH6101MEB01',
 VOLTAGE='6.3V',
 PART_NUMBER='CH6101MEB01',
 VALUE='10UF',
 PRIM_FILE='./archive_libs/logical/q_cap/chips/chips.prt';

PART_NAME
 C411 'Q_CAP_C0201-0.1UF,10V,10%,X7S,CH4102K6E00':;

SECTION_NUMBER 1
 '@T6G_MB_LIB.T6G(SCH_1):PAGE454_I62@PURE_QUANTA.Q_CAP(CHIPS)':
 C_PATH='@t6g_mb_lib.t6g(sch_1):page454_i62@pure_quanta.q_cap(chips)',
 P_PATH='@t6g_mb_lib.t6g(sch_1):page345_i62@pure_quanta.q_cap(chips)',
 PATH='I62',
 DRAWING='@T6G_MB_LIB.T6G(SCH_1):PAGE454',
 TOLERANCE='10%',
 MATERIAL='X7S',
 PHYS_PAGE='345',
 XY='(-1575,2375)',
 ROT='0',
 VER='1',
 PACK_TYPE='C0201',
 LOCATION='C411',
 CDS_LIB='pure_quanta',
 CDS_PART_NAME='Q_CAP_C0201-0.1UF,10V,10%,X7S,CH4102K6E00',
 VOLTAGE='10V',
 PART_NUMBER='CH4102K6E00',
 VALUE='0.1UF',
 PRIM_FILE='./archive_libs/logical/q_cap/chips/chips.prt';

PART_NAME
 C412 'Q_CAP_0402-4.7UF,6.3V,20%,X6S,CH5471MEB01':;

SECTION_NUMBER 1
 '@T6G_MB_LIB.T6G(SCH_1):PAGE454_I57@PURE_QUANTA.Q_CAP(CHIPS)':
 C_PATH='@t6g_mb_lib.t6g(sch_1):page454_i57@pure_quanta.q_cap(chips)',
 P_PATH='@t6g_mb_lib.t6g(sch_1):page345_i57@pure_quanta.q_cap(chips)',
 PATH='I57',
 DRAWING='@T6G_MB_LIB.T6G(SCH_1):PAGE454',
 TOLERANCE='20%',
 MATERIAL='X6S',
 PHYS_PAGE='345',
 XY='(-2275,3700)',
 ROT='0',
 VER='1',
 PACK_TYPE='0402',
 LOCATION='C412',
 CDS_LIB='pure_quanta',
 CDS_PART_NAME='Q_CAP_0402-4.7UF,6.3V,20%,X6S,CH5471MEB01',
 VOLTAGE='6.3V',
 PART_NUMBER='CH5471MEB01',
 VALUE='4.7UF',
 PRIM_FILE='./archive_libs/logical/q_cap/chips/chips.prt';

PART_NAME
 C413 'Q_CAP_0402-4.7UF,6.3V,20%,X6S,CH5471MEB01':;

SECTION_NUMBER 1
 '@T6G_MB_LIB.T6G(SCH_1):PAGE454_I55@PURE_QUANTA.Q_CAP(CHIPS)':
 C_PATH='@t6g_mb_lib.t6g(sch_1):page454_i55@pure_quanta.q_cap(chips)',
 P_PATH='@t6g_mb_lib.t6g(sch_1):page345_i55@pure_quanta.q_cap(chips)',
 PATH='I55',
 DRAWING='@T6G_MB_LIB.T6G(SCH_1):PAGE454',
 TOLERANCE='20%',
 MATERIAL='X6S',
 PHYS_PAGE='345',
 XY='(-2500,3700)',
 ROT='0',
 VER='1',
 PACK_TYPE='0402',
 LOCATION='C413',
 CDS_LIB='pure_quanta',
 CDS_PART_NAME='Q_CAP_0402-4.7UF,6.3V,20%,X6S,CH5471MEB01',
 VOLTAGE='6.3V',
 PART_NUMBER='CH5471MEB01',
 VALUE='4.7UF',
 PRIM_FILE='./archive_libs/logical/q_cap/chips/chips.prt';

PART_NAME
 C414 'Q_CAP_C0402-10UF,6.3V,20%,X6S,CH6101MEB01':;

SECTION_NUMBER 1
 '@T6G_MB_LIB.T6G(SCH_1):PAGE454_I78@PURE_QUANTA.Q_CAP(CHIPS)':
 C_PATH='@t6g_mb_lib.t6g(sch_1):page454_i78@pure_quanta.q_cap(chips)',
 P_PATH='@t6g_mb_lib.t6g(sch_1):page345_i78@pure_quanta.q_cap(chips)',
 PATH='I78',
 DRAWING='@T6G_MB_LIB.T6G(SCH_1):PAGE454',
 TOLERANCE='20%',
 MATERIAL='X6S',
 PHYS_PAGE='345',
 XY='(-3500,5600)',
 ROT='0',
 VER='1',
 PACK_TYPE='C0402',
 LOCATION='C414',
 CDS_LIB='pure_quanta',
 CDS_PART_NAME='Q_CAP_C0402-10UF,6.3V,20%,X6S,CH6101MEB01',
 VOLTAGE='6.3V',
 PART_NUMBER='CH6101MEB01',
 VALUE='10UF',
 PRIM_FILE='./archive_libs/logical/q_cap/chips/chips.prt';

PART_NAME
 C415 'Q_CAP_0201-1UF,4V,20%,X6S,CH-10KMEE00':;

SECTION_NUMBER 1
 '@T6G_MB_LIB.T6G(SCH_1):PAGE454_I51@PURE_QUANTA.Q_CAP(CHIPS)':
 C_PATH='@t6g_mb_lib.t6g(sch_1):page454_i51@pure_quanta.q_cap(chips)',
 P_PATH='@t6g_mb_lib.t6g(sch_1):page345_i51@pure_quanta.q_cap(chips)',
 PATH='I51',
 DRAWING='@T6G_MB_LIB.T6G(SCH_1):PAGE454',
 TOLERANCE='20%',
 MATERIAL='X6S',
 PHYS_PAGE='345',
 XY='(-2475,3075)',
 ROT='0',
 VER='1',
 PACK_TYPE='0201',
 LOCATION='C415',
 CDS_LIB='pure_quanta',
 CDS_PART_NAME='Q_CAP_0201-1UF,4V,20%,X6S,CH-10KMEE00',
 VOLTAGE='4V',
 PART_NUMBER='CH-10KMEE00',
 VALUE='1UF',
 PRIM_FILE='./archive_libs/logical/q_cap/chips/chips.prt';

PART_NAME
 C416 'Q_CAP_0402-4.7UF,6.3V,20%,X6S,CH5471MEB01':;

SECTION_NUMBER 1
 '@T6G_MB_LIB.T6G(SCH_1):PAGE454_I54@PURE_QUANTA.Q_CAP(CHIPS)':
 C_PATH='@t6g_mb_lib.t6g(sch_1):page454_i54@pure_quanta.q_cap(chips)',
 P_PATH='@t6g_mb_lib.t6g(sch_1):page345_i54@pure_quanta.q_cap(chips)',
 PATH='I54',
 DRAWING='@T6G_MB_LIB.T6G(SCH_1):PAGE454',
 TOLERANCE='20%',
 MATERIAL='X6S',
 PHYS_PAGE='345',
 XY='(-2750,3700)',
 ROT='0',
 VER='1',
 PACK_TYPE='0402',
 LOCATION='C416',
 CDS_LIB='pure_quanta',
 CDS_PART_NAME='Q_CAP_0402-4.7UF,6.3V,20%,X6S,CH5471MEB01',
 VOLTAGE='6.3V',
 PART_NUMBER='CH5471MEB01',
 VALUE='4.7UF',
 PRIM_FILE='./archive_libs/logical/q_cap/chips/chips.prt';

PART_NAME
 C417 'Q_CAP_C0402-22UF,4V,20%,X6S,CH622KMEB02':;

SECTION_NUMBER 1
 '@T6G_MB_LIB.T6G(SCH_1):PAGE454_I56@PURE_QUANTA.Q_CAP(CHIPS)':
 C_PATH='@t6g_mb_lib.t6g(sch_1):page454_i56@pure_quanta.q_cap(chips)',
 P_PATH='@t6g_mb_lib.t6g(sch_1):page345_i56@pure_quanta.q_cap(chips)',
 PATH='I56',
 DRAWING='@T6G_MB_LIB.T6G(SCH_1):PAGE454',
 TOLERANCE='20%',
 MATERIAL='X6S',
 PHYS_PAGE='345',
 XY='(-2500,4325)',
 ROT='0',
 VER='1',
 PACK_TYPE='C0402',
 LOCATION='C417',
 CDS_LIB='pure_quanta',
 CDS_PART_NAME='Q_CAP_C0402-22UF,4V,20%,X6S,CH622KMEB02',
 VOLTAGE='4V',
 PART_NUMBER='CH622KMEB02',
 VALUE='22UF',
 PRIM_FILE='./archive_libs/logical/q_cap/chips/chips.prt';

PART_NAME
 C418 'Q_CAP_0201-1UF,4V,20%,X6S,CH-10KMEE00':;

SECTION_NUMBER 1
 '@T6G_MB_LIB.T6G(SCH_1):PAGE454_I52@PURE_QUANTA.Q_CAP(CHIPS)':
 C_PATH='@t6g_mb_lib.t6g(sch_1):page454_i52@pure_quanta.q_cap(chips)',
 P_PATH='@t6g_mb_lib.t6g(sch_1):page345_i52@pure_quanta.q_cap(chips)',
 PATH='I52',
 DRAWING='@T6G_MB_LIB.T6G(SCH_1):PAGE454',
 TOLERANCE='20%',
 MATERIAL='X6S',
 PHYS_PAGE='345',
 XY='(-2250,3050)',
 ROT='0',
 VER='1',
 PACK_TYPE='0201',
 LOCATION='C418',
 CDS_LIB='pure_quanta',
 CDS_PART_NAME='Q_CAP_0201-1UF,4V,20%,X6S,CH-10KMEE00',
 VOLTAGE='4V',
 PART_NUMBER='CH-10KMEE00',
 VALUE='1UF',
 PRIM_FILE='./archive_libs/logical/q_cap/chips/chips.prt';

PART_NAME
 C419 'Q_CAP_0402-4.7UF,6.3V,20%,X6S,CH5471MEB01':;

SECTION_NUMBER 1
 '@T6G_MB_LIB.T6G(SCH_1):PAGE454_I79@PURE_QUANTA.Q_CAP(CHIPS)':
 C_PATH='@t6g_mb_lib.t6g(sch_1):page454_i79@pure_quanta.q_cap(chips)',
 P_PATH='@t6g_mb_lib.t6g(sch_1):page345_i79@pure_quanta.q_cap(chips)',
 PATH='I79',
 DRAWING='@T6G_MB_LIB.T6G(SCH_1):PAGE454',
 TOLERANCE='20%',
 MATERIAL='X6S',
 PHYS_PAGE='345',
 XY='(-3200,5600)',
 ROT='0',
 VER='1',
 PACK_TYPE='0402',
 LOCATION='C419',
 CDS_LIB='pure_quanta',
 CDS_PART_NAME='Q_CAP_0402-4.7UF,6.3V,20%,X6S,CH5471MEB01',
 VOLTAGE='6.3V',
 PART_NUMBER='CH5471MEB01',
 VALUE='4.7UF',
 PRIM_FILE='./archive_libs/logical/q_cap/chips/chips.prt';

PART_NAME
 C420 'Q_CAP_C0402-10UF,6.3V,20%,X6S,CH6101MEB01':;

SECTION_NUMBER 1
 '@T6G_MB_LIB.T6G(SCH_1):PAGE454_I45@PURE_QUANTA.Q_CAP(CHIPS)':
 C_PATH='@t6g_mb_lib.t6g(sch_1):page454_i45@pure_quanta.q_cap(chips)',
 P_PATH='@t6g_mb_lib.t6g(sch_1):page345_i45@pure_quanta.q_cap(chips)',
 PATH='I45',
 DRAWING='@T6G_MB_LIB.T6G(SCH_1):PAGE454',
 TOLERANCE='20%',
 MATERIAL='X6S',
 PHYS_PAGE='345',
 XY='(-3200,3700)',
 ROT='0',
 VER='1',
 PACK_TYPE='C0402',
 LOCATION='C420',
 CDS_LIB='pure_quanta',
 CDS_PART_NAME='Q_CAP_C0402-10UF,6.3V,20%,X6S,CH6101MEB01',
 VOLTAGE='6.3V',
 PART_NUMBER='CH6101MEB01',
 VALUE='10UF',
 PRIM_FILE='./archive_libs/logical/q_cap/chips/chips.prt';

PART_NAME
 C421 'Q_CAP_C0201-0.1UF,10V,10%,X7S,CH4102K6E00':;

SECTION_NUMBER 1
 '@T6G_MB_LIB.T6G(SCH_1):PAGE454_I31@PURE_QUANTA.Q_CAP(CHIPS)':
 C_PATH='@t6g_mb_lib.t6g(sch_1):page454_i31@pure_quanta.q_cap(chips)',
 P_PATH='@t6g_mb_lib.t6g(sch_1):page345_i31@pure_quanta.q_cap(chips)',
 PATH='I31',
 DRAWING='@T6G_MB_LIB.T6G(SCH_1):PAGE454',
 TOLERANCE='10%',
 MATERIAL='X7S',
 PHYS_PAGE='345',
 XY='(-3150,2375)',
 ROT='0',
 VER='1',
 PACK_TYPE='C0201',
 LOCATION='C421',
 CDS_LIB='pure_quanta',
 CDS_PART_NAME='Q_CAP_C0201-0.1UF,10V,10%,X7S,CH4102K6E00',
 VOLTAGE='10V',
 PART_NUMBER='CH4102K6E00',
 VALUE='0.1UF',
 PRIM_FILE='./archive_libs/logical/q_cap/chips/chips.prt';

PART_NAME
 C422 'Q_CAP_0201-1UF,4V,20%,X6S,CH-10KMEE00':;

SECTION_NUMBER 1
 '@T6G_MB_LIB.T6G(SCH_1):PAGE454_I53@PURE_QUANTA.Q_CAP(CHIPS)':
 C_PATH='@t6g_mb_lib.t6g(sch_1):page454_i53@pure_quanta.q_cap(chips)',
 P_PATH='@t6g_mb_lib.t6g(sch_1):page345_i53@pure_quanta.q_cap(chips)',
 PATH='I53',
 DRAWING='@T6G_MB_LIB.T6G(SCH_1):PAGE454',
 TOLERANCE='20%',
 MATERIAL='X6S',
 PHYS_PAGE='345',
 XY='(-2025,3050)',
 ROT='0',
 VER='1',
 PACK_TYPE='0201',
 LOCATION='C422',
 CDS_LIB='pure_quanta',
 CDS_PART_NAME='Q_CAP_0201-1UF,4V,20%,X6S,CH-10KMEE00',
 VOLTAGE='4V',
 PART_NUMBER='CH-10KMEE00',
 VALUE='1UF',
 PRIM_FILE='./archive_libs/logical/q_cap/chips/chips.prt';

PART_NAME
 C423 'Q_CAP_0201-1UF,4V,20%,X6S,CH-10KMEE00':;

SECTION_NUMBER 1
 '@T6G_MB_LIB.T6G(SCH_1):PAGE454_I80@PURE_QUANTA.Q_CAP(CHIPS)':
 C_PATH='@t6g_mb_lib.t6g(sch_1):page454_i80@pure_quanta.q_cap(chips)',
 P_PATH='@t6g_mb_lib.t6g(sch_1):page345_i80@pure_quanta.q_cap(chips)',
 PATH='I80',
 DRAWING='@T6G_MB_LIB.T6G(SCH_1):PAGE454',
 TOLERANCE='20%',
 MATERIAL='X6S',
 PHYS_PAGE='345',
 XY='(-2900,5600)',
 ROT='0',
 VER='1',
 PACK_TYPE='0201',
 LOCATION='C423',
 CDS_LIB='pure_quanta',
 CDS_PART_NAME='Q_CAP_0201-1UF,4V,20%,X6S,CH-10KMEE00',
 VOLTAGE='4V',
 PART_NUMBER='CH-10KMEE00',
 VALUE='1UF',
 PRIM_FILE='./archive_libs/logical/q_cap/chips/chips.prt';

PART_NAME
 C424 'Q_CAP_C0402-22UF,4V,20%,X6S,CH622KMEB02':;

SECTION_NUMBER 1
 '@T6G_MB_LIB.T6G(SCH_1):PAGE454_I69@PURE_QUANTA.Q_CAP(CHIPS)':
 C_PATH='@t6g_mb_lib.t6g(sch_1):page454_i69@pure_quanta.q_cap(chips)',
 P_PATH='@t6g_mb_lib.t6g(sch_1):page345_i69@pure_quanta.q_cap(chips)',
 PATH='I69',
 DRAWING='@T6G_MB_LIB.T6G(SCH_1):PAGE454',
 TOLERANCE='20%',
 MATERIAL='X6S',
 PHYS_PAGE='345',
 XY='(-1825,4325)',
 ROT='0',
 VER='1',
 PACK_TYPE='C0402',
 LOCATION='C424',
 CDS_LIB='pure_quanta',
 CDS_PART_NAME='Q_CAP_C0402-22UF,4V,20%,X6S,CH622KMEB02',
 VOLTAGE='4V',
 PART_NUMBER='CH622KMEB02',
 VALUE='22UF',
 PRIM_FILE='./archive_libs/logical/q_cap/chips/chips.prt';

PART_NAME
 C425 'Q_CAP_0201-1UF,4V,20%,X6S,CH-10KMEE00':;

SECTION_NUMBER 1
 '@T6G_MB_LIB.T6G(SCH_1):PAGE454_I67@PURE_QUANTA.Q_CAP(CHIPS)':
 C_PATH='@t6g_mb_lib.t6g(sch_1):page454_i67@pure_quanta.q_cap(chips)',
 P_PATH='@t6g_mb_lib.t6g(sch_1):page345_i67@pure_quanta.q_cap(chips)',
 PATH='I67',
 DRAWING='@T6G_MB_LIB.T6G(SCH_1):PAGE454',
 TOLERANCE='20%',
 MATERIAL='X6S',
 PHYS_PAGE='345',
 XY='(-1825,3700)',
 ROT='0',
 VER='1',
 PACK_TYPE='0201',
 LOCATION='C425',
 CDS_LIB='pure_quanta',
 CDS_PART_NAME='Q_CAP_0201-1UF,4V,20%,X6S,CH-10KMEE00',
 VOLTAGE='4V',
 PART_NUMBER='CH-10KMEE00',
 VALUE='1UF',
 PRIM_FILE='./archive_libs/logical/q_cap/chips/chips.prt';

PART_NAME
 C426 'Q_CAP_C0201-0.1UF,10V,10%,X7S,CH4102K6E00':;

SECTION_NUMBER 1
 '@T6G_MB_LIB.T6G(SCH_1):PAGE454_I92@PURE_QUANTA.Q_CAP(CHIPS)':
 C_PATH='@t6g_mb_lib.t6g(sch_1):page454_i92@pure_quanta.q_cap(chips)',
 P_PATH='@t6g_mb_lib.t6g(sch_1):page345_i92@pure_quanta.q_cap(chips)',
 PATH='I92',
 DRAWING='@T6G_MB_LIB.T6G(SCH_1):PAGE454',
 TOLERANCE='10%',
 MATERIAL='X7S',
 PHYS_PAGE='345',
 XY='(-1800,3050)',
 ROT='0',
 VER='1',
 PACK_TYPE='C0201',
 LOCATION='C426',
 CDS_LIB='pure_quanta',
 CDS_PART_NAME='Q_CAP_C0201-0.1UF,10V,10%,X7S,CH4102K6E00',
 VOLTAGE='10V',
 PART_NUMBER='CH4102K6E00',
 VALUE='0.1UF',
 PRIM_FILE='./archive_libs/logical/q_cap/chips/chips.prt';

PART_NAME
 C427 'Q_CAP_C0201-0.1UF,10V,10%,X7S,CH4102K6E00':;

SECTION_NUMBER 1
 '@T6G_MB_LIB.T6G(SCH_1):PAGE454_I37@PURE_QUANTA.Q_CAP(CHIPS)':
 C_PATH='@t6g_mb_lib.t6g(sch_1):page454_i37@pure_quanta.q_cap(chips)',
 P_PATH='@t6g_mb_lib.t6g(sch_1):page345_i37@pure_quanta.q_cap(chips)',
 PATH='I37',
 DRAWING='@T6G_MB_LIB.T6G(SCH_1):PAGE454',
 TOLERANCE='10%',
 MATERIAL='X7S',
 PHYS_PAGE='345',
 XY='(-2850,2375)',
 ROT='0',
 VER='1',
 PACK_TYPE='C0201',
 LOCATION='C427',
 CDS_LIB='pure_quanta',
 CDS_PART_NAME='Q_CAP_C0201-0.1UF,10V,10%,X7S,CH4102K6E00',
 VOLTAGE='10V',
 PART_NUMBER='CH4102K6E00',
 VALUE='0.1UF',
 PRIM_FILE='./archive_libs/logical/q_cap/chips/chips.prt';

PART_NAME
 C428 'Q_CAP_C0201-0.1UF,10V,10%,X7S,CH4102K6E00':;

SECTION_NUMBER 1
 '@T6G_MB_LIB.T6G(SCH_1):PAGE454_I93@PURE_QUANTA.Q_CAP(CHIPS)':
 C_PATH='@t6g_mb_lib.t6g(sch_1):page454_i93@pure_quanta.q_cap(chips)',
 P_PATH='@t6g_mb_lib.t6g(sch_1):page345_i93@pure_quanta.q_cap(chips)',
 PATH='I93',
 DRAWING='@T6G_MB_LIB.T6G(SCH_1):PAGE454',
 TOLERANCE='10%',
 MATERIAL='X7S',
 PHYS_PAGE='345',
 XY='(-1550,3050)',
 ROT='0',
 VER='1',
 PACK_TYPE='C0201',
 LOCATION='C428',
 CDS_LIB='pure_quanta',
 CDS_PART_NAME='Q_CAP_C0201-0.1UF,10V,10%,X7S,CH4102K6E00',
 VOLTAGE='10V',
 PART_NUMBER='CH4102K6E00',
 VALUE='0.1UF',
 PRIM_FILE='./archive_libs/logical/q_cap/chips/chips.prt';

PART_NAME
 C429 'Q_CAP_C0402-10UF,6.3V,20%,X6S,CH6101MEB01':;

SECTION_NUMBER 1
 '@T6G_MB_LIB.T6G(SCH_1):PAGE454_I70@PURE_QUANTA.Q_CAP(CHIPS)':
 C_PATH='@t6g_mb_lib.t6g(sch_1):page454_i70@pure_quanta.q_cap(chips)',
 P_PATH='@t6g_mb_lib.t6g(sch_1):page345_i70@pure_quanta.q_cap(chips)',
 PATH='I70',
 DRAWING='@T6G_MB_LIB.T6G(SCH_1):PAGE454',
 TOLERANCE='20%',
 MATERIAL='X6S',
 PHYS_PAGE='345',
 XY='(-1525,4325)',
 ROT='0',
 VER='1',
 PACK_TYPE='C0402',
 LOCATION='C429',
 CDS_LIB='pure_quanta',
 CDS_PART_NAME='Q_CAP_C0402-10UF,6.3V,20%,X6S,CH6101MEB01',
 VOLTAGE='6.3V',
 PART_NUMBER='CH6101MEB01',
 VALUE='10UF',
 PRIM_FILE='./archive_libs/logical/q_cap/chips/chips.prt';

PART_NAME
 C430 'Q_CAP_C0201-0.1UF,10V,10%,X7S,CH4102K6E00':;

SECTION_NUMBER 1
 '@T6G_MB_LIB.T6G(SCH_1):PAGE454_I39@PURE_QUANTA.Q_CAP(CHIPS)':
 C_PATH='@t6g_mb_lib.t6g(sch_1):page454_i39@pure_quanta.q_cap(chips)',
 P_PATH='@t6g_mb_lib.t6g(sch_1):page345_i39@pure_quanta.q_cap(chips)',
 PATH='I39',
 DRAWING='@T6G_MB_LIB.T6G(SCH_1):PAGE454',
 TOLERANCE='10%',
 MATERIAL='X7S',
 PHYS_PAGE='345',
 XY='(-2375,2375)',
 ROT='0',
 VER='1',
 PACK_TYPE='C0201',
 LOCATION='C430',
 CDS_LIB='pure_quanta',
 CDS_PART_NAME='Q_CAP_C0201-0.1UF,10V,10%,X7S,CH4102K6E00',
 VOLTAGE='10V',
 PART_NUMBER='CH4102K6E00',
 VALUE='0.1UF',
 PRIM_FILE='./archive_libs/logical/q_cap/chips/chips.prt';

PART_NAME
 C431 'Q_CAP_C0402-10UF,6.3V,20%,X6S,CH6101MEB01':;

SECTION_NUMBER 1
 '@T6G_MB_LIB.T6G(SCH_1):PAGE454_I72@PURE_QUANTA.Q_CAP(CHIPS)':
 C_PATH='@t6g_mb_lib.t6g(sch_1):page454_i72@pure_quanta.q_cap(chips)',
 P_PATH='@t6g_mb_lib.t6g(sch_1):page345_i72@pure_quanta.q_cap(chips)',
 PATH='I72',
 DRAWING='@T6G_MB_LIB.T6G(SCH_1):PAGE454',
 TOLERANCE='20%',
 MATERIAL='X6S',
 PHYS_PAGE='345',
 XY='(-1225,4325)',
 ROT='0',
 VER='1',
 PACK_TYPE='C0402',
 LOCATION='C431',
 CDS_LIB='pure_quanta',
 CDS_PART_NAME='Q_CAP_C0402-10UF,6.3V,20%,X6S,CH6101MEB01',
 VOLTAGE='6.3V',
 PART_NUMBER='CH6101MEB01',
 VALUE='10UF',
 PRIM_FILE='./archive_libs/logical/q_cap/chips/chips.prt';

PART_NAME
 C432 'Q_CAP_C0805-100UF,4V,20%,X6S,CH710KMEA01':;

SECTION_NUMBER 1
 '@T6G_MB_LIB.T6G(SCH_1):PAGE465_I17@PURE_QUANTA.Q_CAP(CHIPS)':
 C_PATH='@t6g_mb_lib.t6g(sch_1):page465_i17@pure_quanta.q_cap(chips)',
 P_PATH='@t6g_mb_lib.t6g(sch_1):page356_i17@pure_quanta.q_cap(chips)',
 PATH='I17',
 DRAWING='@T6G_MB_LIB.T6G(SCH_1):PAGE465',
 TOLERANCE='20%',
 MATERIAL='X6S',
 PHYS_PAGE='356',
 XY='(-7050,4975)',
 ROT='0',
 VER='1',
 PACK_TYPE='C0805',
 LOCATION='C432',
 CDS_LIB='pure_quanta',
 CDS_PART_NAME='Q_CAP_C0805-100UF,4V,20%,X6S,CH710KMEA01',
 VOLTAGE='4V',
 PART_NUMBER='CH710KMEA01',
 VALUE='100UF',
 PRIM_FILE='./archive_libs/logical/q_cap/chips/chips.prt';

PART_NAME
 C433 'Q_CAP_C0805-100UF,4V,20%,X6S,CH710KMEA01':;

SECTION_NUMBER 1
 '@T6G_MB_LIB.T6G(SCH_1):PAGE465_I14@PURE_QUANTA.Q_CAP(CHIPS)':
 C_PATH='@t6g_mb_lib.t6g(sch_1):page465_i14@pure_quanta.q_cap(chips)',
 P_PATH='@t6g_mb_lib.t6g(sch_1):page356_i14@pure_quanta.q_cap(chips)',
 PATH='I14',
 DRAWING='@T6G_MB_LIB.T6G(SCH_1):PAGE465',
 TOLERANCE='20%',
 MATERIAL='X6S',
 PHYS_PAGE='356',
 XY='(-7200,4150)',
 ROT='0',
 VER='1',
 PACK_TYPE='C0805',
 LOCATION='C433',
 CDS_LIB='pure_quanta',
 CDS_PART_NAME='Q_CAP_C0805-100UF,4V,20%,X6S,CH710KMEA01',
 VOLTAGE='4V',
 PART_NUMBER='CH710KMEA01',
 VALUE='100UF',
 PRIM_FILE='./archive_libs/logical/q_cap/chips/chips.prt';

PART_NAME
 C434 'Q_CAP_C0402-22UF,4V,20%,X6S,CH622KMEB02':;

SECTION_NUMBER 1
 '@T6G_MB_LIB.T6G(SCH_1):PAGE465_I18@PURE_QUANTA.Q_CAP(CHIPS)':
 C_PATH='@t6g_mb_lib.t6g(sch_1):page465_i18@pure_quanta.q_cap(chips)',
 P_PATH='@t6g_mb_lib.t6g(sch_1):page356_i18@pure_quanta.q_cap(chips)',
 PATH='I18',
 DRAWING='@T6G_MB_LIB.T6G(SCH_1):PAGE465',
 TOLERANCE='20%',
 MATERIAL='X6S',
 PHYS_PAGE='356',
 XY='(-6800,4975)',
 ROT='0',
 VER='1',
 PACK_TYPE='C0402',
 LOCATION='C434',
 CDS_LIB='pure_quanta',
 CDS_PART_NAME='Q_CAP_C0402-22UF,4V,20%,X6S,CH622KMEB02',
 VOLTAGE='4V',
 PART_NUMBER='CH622KMEB02',
 VALUE='22UF',
 PRIM_FILE='./archive_libs/logical/q_cap/chips/chips.prt';

PART_NAME
 C435 'Q_CAP_C0402-22UF,4V,20%,X6S,CH622KMEB02':;

SECTION_NUMBER 1
 '@T6G_MB_LIB.T6G(SCH_1):PAGE465_I15@PURE_QUANTA.Q_CAP(CHIPS)':
 C_PATH='@t6g_mb_lib.t6g(sch_1):page465_i15@pure_quanta.q_cap(chips)',
 P_PATH='@t6g_mb_lib.t6g(sch_1):page356_i15@pure_quanta.q_cap(chips)',
 PATH='I15',
 DRAWING='@T6G_MB_LIB.T6G(SCH_1):PAGE465',
 TOLERANCE='20%',
 MATERIAL='X6S',
 PHYS_PAGE='356',
 XY='(-6975,4150)',
 ROT='0',
 VER='1',
 PACK_TYPE='C0402',
 LOCATION='C435',
 CDS_LIB='pure_quanta',
 CDS_PART_NAME='Q_CAP_C0402-22UF,4V,20%,X6S,CH622KMEB02',
 VOLTAGE='4V',
 PART_NUMBER='CH622KMEB02',
 VALUE='22UF',
 PRIM_FILE='./archive_libs/logical/q_cap/chips/chips.prt';

PART_NAME
 C436 'Q_CAP_C0402-10UF,6.3V,20%,X6S,CH6101MEB01':;

SECTION_NUMBER 1
 '@T6G_MB_LIB.T6G(SCH_1):PAGE465_I21@PURE_QUANTA.Q_CAP(CHIPS)':
 C_PATH='@t6g_mb_lib.t6g(sch_1):page465_i21@pure_quanta.q_cap(chips)',
 P_PATH='@t6g_mb_lib.t6g(sch_1):page356_i21@pure_quanta.q_cap(chips)',
 PATH='I21',
 DRAWING='@T6G_MB_LIB.T6G(SCH_1):PAGE465',
 TOLERANCE='20%',
 MATERIAL='X6S',
 PHYS_PAGE='356',
 XY='(-6550,4950)',
 ROT='0',
 VER='1',
 PACK_TYPE='C0402',
 LOCATION='C436',
 CDS_LIB='pure_quanta',
 CDS_PART_NAME='Q_CAP_C0402-10UF,6.3V,20%,X6S,CH6101MEB01',
 VOLTAGE='6.3V',
 PART_NUMBER='CH6101MEB01',
 VALUE='10UF',
 PRIM_FILE='./archive_libs/logical/q_cap/chips/chips.prt';

PART_NAME
 C437 'Q_CAP_C0402-10UF,6.3V,20%,X6S,CH6101MEB01':;

SECTION_NUMBER 1
 '@T6G_MB_LIB.T6G(SCH_1):PAGE465_I16@PURE_QUANTA.Q_CAP(CHIPS)':
 C_PATH='@t6g_mb_lib.t6g(sch_1):page465_i16@pure_quanta.q_cap(chips)',
 P_PATH='@t6g_mb_lib.t6g(sch_1):page356_i16@pure_quanta.q_cap(chips)',
 PATH='I16',
 DRAWING='@T6G_MB_LIB.T6G(SCH_1):PAGE465',
 TOLERANCE='20%',
 MATERIAL='X6S',
 PHYS_PAGE='356',
 XY='(-6775,4150)',
 ROT='0',
 VER='1',
 PACK_TYPE='C0402',
 LOCATION='C437',
 CDS_LIB='pure_quanta',
 CDS_PART_NAME='Q_CAP_C0402-10UF,6.3V,20%,X6S,CH6101MEB01',
 VOLTAGE='6.3V',
 PART_NUMBER='CH6101MEB01',
 VALUE='10UF',
 PRIM_FILE='./archive_libs/logical/q_cap/chips/chips.prt';

PART_NAME
 C438 'Q_CAP_0402-4.7UF,6.3V,20%,X6S,CH5471MEB01':;

SECTION_NUMBER 1
 '@T6G_MB_LIB.T6G(SCH_1):PAGE465_I19@PURE_QUANTA.Q_CAP(CHIPS)':
 C_PATH='@t6g_mb_lib.t6g(sch_1):page465_i19@pure_quanta.q_cap(chips)',
 P_PATH='@t6g_mb_lib.t6g(sch_1):page356_i19@pure_quanta.q_cap(chips)',
 PATH='I19',
 DRAWING='@T6G_MB_LIB.T6G(SCH_1):PAGE465',
 TOLERANCE='20%',
 MATERIAL='X6S',
 PHYS_PAGE='356',
 XY='(-6575,4150)',
 ROT='0',
 VER='1',
 PACK_TYPE='0402',
 LOCATION='C438',
 CDS_LIB='pure_quanta',
 CDS_PART_NAME='Q_CAP_0402-4.7UF,6.3V,20%,X6S,CH5471MEB01',
 VOLTAGE='6.3V',
 PART_NUMBER='CH5471MEB01',
 VALUE='4.7UF',
 PRIM_FILE='./archive_libs/logical/q_cap/chips/chips.prt';

PART_NAME
 C439 'Q_CAP_0402-4.7UF,6.3V,20%,X6S,CH5471MEB01':;

SECTION_NUMBER 1
 '@T6G_MB_LIB.T6G(SCH_1):PAGE465_I23@PURE_QUANTA.Q_CAP(CHIPS)':
 C_PATH='@t6g_mb_lib.t6g(sch_1):page465_i23@pure_quanta.q_cap(chips)',
 P_PATH='@t6g_mb_lib.t6g(sch_1):page356_i23@pure_quanta.q_cap(chips)',
 PATH='I23',
 DRAWING='@T6G_MB_LIB.T6G(SCH_1):PAGE465',
 TOLERANCE='20%',
 MATERIAL='X6S',
 PHYS_PAGE='356',
 XY='(-6300,4950)',
 ROT='0',
 VER='1',
 PACK_TYPE='0402',
 LOCATION='C439',
 CDS_LIB='pure_quanta',
 CDS_PART_NAME='Q_CAP_0402-4.7UF,6.3V,20%,X6S,CH5471MEB01',
 VOLTAGE='6.3V',
 PART_NUMBER='CH5471MEB01',
 VALUE='4.7UF',
 PRIM_FILE='./archive_libs/logical/q_cap/chips/chips.prt';

PART_NAME
 C440 'Q_CAP_0201-1UF,4V,20%,X6S,CH-10KMEE00':;

SECTION_NUMBER 1
 '@T6G_MB_LIB.T6G(SCH_1):PAGE465_I20@PURE_QUANTA.Q_CAP(CHIPS)':
 C_PATH='@t6g_mb_lib.t6g(sch_1):page465_i20@pure_quanta.q_cap(chips)',
 P_PATH='@t6g_mb_lib.t6g(sch_1):page356_i20@pure_quanta.q_cap(chips)',
 PATH='I20',
 DRAWING='@T6G_MB_LIB.T6G(SCH_1):PAGE465',
 TOLERANCE='20%',
 MATERIAL='X6S',
 PHYS_PAGE='356',
 XY='(-6350,4150)',
 ROT='0',
 VER='1',
 PACK_TYPE='0201',
 LOCATION='C440',
 CDS_LIB='pure_quanta',
 CDS_PART_NAME='Q_CAP_0201-1UF,4V,20%,X6S,CH-10KMEE00',
 VOLTAGE='4V',
 PART_NUMBER='CH-10KMEE00',
 VALUE='1UF',
 PRIM_FILE='./archive_libs/logical/q_cap/chips/chips.prt';

PART_NAME
 C441 'Q_CAP_0201-1UF,4V,20%,X6S,CH-10KMEE00':;

SECTION_NUMBER 1
 '@T6G_MB_LIB.T6G(SCH_1):PAGE465_I4@PURE_QUANTA.Q_CAP(CHIPS)':
 C_PATH='@t6g_mb_lib.t6g(sch_1):page465_i4@pure_quanta.q_cap(chips)',
 P_PATH='@t6g_mb_lib.t6g(sch_1):page356_i4@pure_quanta.q_cap(chips)',
 PATH='I4',
 DRAWING='@T6G_MB_LIB.T6G(SCH_1):PAGE465',
 TOLERANCE='20%',
 MATERIAL='X6S',
 PHYS_PAGE='356',
 XY='(-6775,3075)',
 ROT='0',
 VER='1',
 PACK_TYPE='0201',
 LOCATION='C441',
 CDS_LIB='pure_quanta',
 CDS_PART_NAME='Q_CAP_0201-1UF,4V,20%,X6S,CH-10KMEE00',
 VOLTAGE='4V',
 PART_NUMBER='CH-10KMEE00',
 VALUE='1UF',
 PRIM_FILE='./archive_libs/logical/q_cap/chips/chips.prt';

PART_NAME
 C442 'Q_CAP_0201-1UF,4V,20%,X6S,CH-10KMEE00':;

SECTION_NUMBER 1
 '@T6G_MB_LIB.T6G(SCH_1):PAGE465_I24@PURE_QUANTA.Q_CAP(CHIPS)':
 C_PATH='@t6g_mb_lib.t6g(sch_1):page465_i24@pure_quanta.q_cap(chips)',
 P_PATH='@t6g_mb_lib.t6g(sch_1):page356_i24@pure_quanta.q_cap(chips)',
 PATH='I24',
 DRAWING='@T6G_MB_LIB.T6G(SCH_1):PAGE465',
 TOLERANCE='20%',
 MATERIAL='X6S',
 PHYS_PAGE='356',
 XY='(-6150,4150)',
 ROT='0',
 VER='1',
 PACK_TYPE='0201',
 LOCATION='C442',
 CDS_LIB='pure_quanta',
 CDS_PART_NAME='Q_CAP_0201-1UF,4V,20%,X6S,CH-10KMEE00',
 VOLTAGE='4V',
 PART_NUMBER='CH-10KMEE00',
 VALUE='1UF',
 PRIM_FILE='./archive_libs/logical/q_cap/chips/chips.prt';

PART_NAME
 C443 'Q_CAP_C0201-0.1UF,10V,10%,X7S,CH4102K6E00':;

SECTION_NUMBER 1
 '@T6G_MB_LIB.T6G(SCH_1):PAGE465_I25@PURE_QUANTA.Q_CAP(CHIPS)':
 C_PATH='@t6g_mb_lib.t6g(sch_1):page465_i25@pure_quanta.q_cap(chips)',
 P_PATH='@t6g_mb_lib.t6g(sch_1):page356_i25@pure_quanta.q_cap(chips)',
 PATH='I25',
 DRAWING='@T6G_MB_LIB.T6G(SCH_1):PAGE465',
 TOLERANCE='10%',
 MATERIAL='X7S',
 PHYS_PAGE='356',
 XY='(-5925,4150)',
 ROT='0',
 VER='1',
 PACK_TYPE='C0201',
 LOCATION='C443',
 CDS_LIB='pure_quanta',
 CDS_PART_NAME='Q_CAP_C0201-0.1UF,10V,10%,X7S,CH4102K6E00',
 VOLTAGE='10V',
 PART_NUMBER='CH4102K6E00',
 VALUE='0.1UF',
 PRIM_FILE='./archive_libs/logical/q_cap/chips/chips.prt';

PART_NAME
 C444 'Q_CAP_C0201-0.1UF,10V,10%,X7S,CH4102K6E00':;

SECTION_NUMBER 1
 '@T6G_MB_LIB.T6G(SCH_1):PAGE465_I6@PURE_QUANTA.Q_CAP(CHIPS)':
 C_PATH='@t6g_mb_lib.t6g(sch_1):page465_i6@pure_quanta.q_cap(chips)',
 P_PATH='@t6g_mb_lib.t6g(sch_1):page356_i6@pure_quanta.q_cap(chips)',
 PATH='I6',
 DRAWING='@T6G_MB_LIB.T6G(SCH_1):PAGE465',
 TOLERANCE='10%',
 MATERIAL='X7S',
 PHYS_PAGE='356',
 XY='(-6500,3050)',
 ROT='0',
 VER='1',
 PACK_TYPE='C0201',
 LOCATION='C444',
 CDS_LIB='pure_quanta',
 CDS_PART_NAME='Q_CAP_C0201-0.1UF,10V,10%,X7S,CH4102K6E00',
 VOLTAGE='10V',
 PART_NUMBER='CH4102K6E00',
 VALUE='0.1UF',
 PRIM_FILE='./archive_libs/logical/q_cap/chips/chips.prt';

PART_NAME
 C445 'Q_CAP_C0201-0.1UF,10V,10%,X7S,CH4102K6E00':;

SECTION_NUMBER 1
 '@T6G_MB_LIB.T6G(SCH_1):PAGE465_I26@PURE_QUANTA.Q_CAP(CHIPS)':
 C_PATH='@t6g_mb_lib.t6g(sch_1):page465_i26@pure_quanta.q_cap(chips)',
 P_PATH='@t6g_mb_lib.t6g(sch_1):page356_i26@pure_quanta.q_cap(chips)',
 PATH='I26',
 DRAWING='@T6G_MB_LIB.T6G(SCH_1):PAGE465',
 TOLERANCE='10%',
 MATERIAL='X7S',
 PHYS_PAGE='356',
 XY='(-5675,4150)',
 ROT='0',
 VER='1',
 PACK_TYPE='C0201',
 LOCATION='C445',
 CDS_LIB='pure_quanta',
 CDS_PART_NAME='Q_CAP_C0201-0.1UF,10V,10%,X7S,CH4102K6E00',
 VOLTAGE='10V',
 PART_NUMBER='CH4102K6E00',
 VALUE='0.1UF',
 PRIM_FILE='./archive_libs/logical/q_cap/chips/chips.prt';

PART_NAME
 C446 'Q_CAP_C0201-0.1UF,10V,10%,X7S,CH4102K6E00':;

SECTION_NUMBER 1
 '@T6G_MB_LIB.T6G(SCH_1):PAGE465_I27@PURE_QUANTA.Q_CAP(CHIPS)':
 C_PATH='@t6g_mb_lib.t6g(sch_1):page465_i27@pure_quanta.q_cap(chips)',
 P_PATH='@t6g_mb_lib.t6g(sch_1):page356_i27@pure_quanta.q_cap(chips)',
 PATH='I27',
 DRAWING='@T6G_MB_LIB.T6G(SCH_1):PAGE465',
 TOLERANCE='10%',
 MATERIAL='X7S',
 PHYS_PAGE='356',
 XY='(-5425,4150)',
 ROT='0',
 VER='1',
 PACK_TYPE='C0201',
 LOCATION='C446',
 CDS_LIB='pure_quanta',
 CDS_PART_NAME='Q_CAP_C0201-0.1UF,10V,10%,X7S,CH4102K6E00',
 VOLTAGE='10V',
 PART_NUMBER='CH4102K6E00',
 VALUE='0.1UF',
 PRIM_FILE='./archive_libs/logical/q_cap/chips/chips.prt';

PART_NAME
 C447 'Q_CAP_C0201-0.1UF,10V,10%,X7S,CH4102K6E00':;

SECTION_NUMBER 1
 '@T6G_MB_LIB.T6G(SCH_1):PAGE465_I28@PURE_QUANTA.Q_CAP(CHIPS)':
 C_PATH='@t6g_mb_lib.t6g(sch_1):page465_i28@pure_quanta.q_cap(chips)',
 P_PATH='@t6g_mb_lib.t6g(sch_1):page356_i28@pure_quanta.q_cap(chips)',
 PATH='I28',
 DRAWING='@T6G_MB_LIB.T6G(SCH_1):PAGE465',
 TOLERANCE='10%',
 MATERIAL='X7S',
 PHYS_PAGE='356',
 XY='(-5150,4150)',
 ROT='0',
 VER='1',
 PACK_TYPE='C0201',
 LOCATION='C447',
 CDS_LIB='pure_quanta',
 CDS_PART_NAME='Q_CAP_C0201-0.1UF,10V,10%,X7S,CH4102K6E00',
 VOLTAGE='10V',
 PART_NUMBER='CH4102K6E00',
 VALUE='0.1UF',
 PRIM_FILE='./archive_libs/logical/q_cap/chips/chips.prt';

PART_NAME
 C448 'Q_CAP_0201-1UF,4V,20%,X6S,CH-10KMEE00':;

SECTION_NUMBER 1
 '@T6G_MB_LIB.T6G(SCH_1):PAGE465_I44@PURE_QUANTA.Q_CAP(CHIPS)':
 C_PATH='@t6g_mb_lib.t6g(sch_1):page465_i44@pure_quanta.q_cap(chips)',
 P_PATH='@t6g_mb_lib.t6g(sch_1):page356_i44@pure_quanta.q_cap(chips)',
 PATH='I44',
 DRAWING='@T6G_MB_LIB.T6G(SCH_1):PAGE465',
 TOLERANCE='20%',
 MATERIAL='X6S',
 PHYS_PAGE='356',
 XY='(-3000,2900)',
 ROT='0',
 VER='1',
 PACK_TYPE='0201',
 LOCATION='C448',
 CDS_LIB='pure_quanta',
 CDS_PART_NAME='Q_CAP_0201-1UF,4V,20%,X6S,CH-10KMEE00',
 VOLTAGE='4V',
 PART_NUMBER='CH-10KMEE00',
 VALUE='1UF',
 PRIM_FILE='./archive_libs/logical/q_cap/chips/chips.prt';

PART_NAME
 C449 'Q_CAP_C0201-0.1UF,10V,10%,X7S,CH4102K6E00':;

SECTION_NUMBER 1
 '@T6G_MB_LIB.T6G(SCH_1):PAGE465_I78@PURE_QUANTA.Q_CAP(CHIPS)':
 C_PATH='@t6g_mb_lib.t6g(sch_1):page465_i78@pure_quanta.q_cap(chips)',
 P_PATH='@t6g_mb_lib.t6g(sch_1):page356_i78@pure_quanta.q_cap(chips)',
 PATH='I78',
 DRAWING='@T6G_MB_LIB.T6G(SCH_1):PAGE465',
 TOLERANCE='10%',
 MATERIAL='X7S',
 PHYS_PAGE='356',
 XY='(-1925,5375)',
 ROT='0',
 VER='1',
 PACK_TYPE='C0201',
 LOCATION='C449',
 CDS_LIB='pure_quanta',
 CDS_PART_NAME='Q_CAP_C0201-0.1UF,10V,10%,X7S,CH4102K6E00',
 VOLTAGE='10V',
 PART_NUMBER='CH4102K6E00',
 VALUE='0.1UF',
 PRIM_FILE='./archive_libs/logical/q_cap/chips/chips.prt';

PART_NAME
 C450 'Q_CAP_C0201-0.1UF,10V,10%,X7S,CH4102K6E00':;

SECTION_NUMBER 1
 '@T6G_MB_LIB.T6G(SCH_1):PAGE465_I47@PURE_QUANTA.Q_CAP(CHIPS)':
 C_PATH='@t6g_mb_lib.t6g(sch_1):page465_i47@pure_quanta.q_cap(chips)',
 P_PATH='@t6g_mb_lib.t6g(sch_1):page356_i47@pure_quanta.q_cap(chips)',
 PATH='I47',
 DRAWING='@T6G_MB_LIB.T6G(SCH_1):PAGE465',
 TOLERANCE='10%',
 MATERIAL='X7S',
 PHYS_PAGE='356',
 XY='(-2175,2200)',
 ROT='0',
 VER='1',
 PACK_TYPE='C0201',
 LOCATION='C450',
 CDS_LIB='pure_quanta',
 CDS_PART_NAME='Q_CAP_C0201-0.1UF,10V,10%,X7S,CH4102K6E00',
 VOLTAGE='10V',
 PART_NUMBER='CH4102K6E00',
 VALUE='0.1UF',
 PRIM_FILE='./archive_libs/logical/q_cap/chips/chips.prt';

PART_NAME
 C451 'Q_CAP_C0201-0.1UF,10V,10%,X7S,CH4102K6E00':;

SECTION_NUMBER 1
 '@T6G_MB_LIB.T6G(SCH_1):PAGE465_I79@PURE_QUANTA.Q_CAP(CHIPS)':
 C_PATH='@t6g_mb_lib.t6g(sch_1):page465_i79@pure_quanta.q_cap(chips)',
 P_PATH='@t6g_mb_lib.t6g(sch_1):page356_i79@pure_quanta.q_cap(chips)',
 PATH='I79',
 DRAWING='@T6G_MB_LIB.T6G(SCH_1):PAGE465',
 TOLERANCE='10%',
 MATERIAL='X7S',
 PHYS_PAGE='356',
 XY='(-1650,5375)',
 ROT='0',
 VER='1',
 PACK_TYPE='C0201',
 LOCATION='C451',
 CDS_LIB='pure_quanta',
 CDS_PART_NAME='Q_CAP_C0201-0.1UF,10V,10%,X7S,CH4102K6E00',
 VOLTAGE='10V',
 PART_NUMBER='CH4102K6E00',
 VALUE='0.1UF',
 PRIM_FILE='./archive_libs/logical/q_cap/chips/chips.prt';

PART_NAME
 C452 'Q_CAP_0201-1UF,4V,20%,X6S,CH-10KMEE00':;

SECTION_NUMBER 1
 '@T6G_MB_LIB.T6G(SCH_1):PAGE465_I84@PURE_QUANTA.Q_CAP(CHIPS)':
 C_PATH='@t6g_mb_lib.t6g(sch_1):page465_i84@pure_quanta.q_cap(chips)',
 P_PATH='@t6g_mb_lib.t6g(sch_1):page356_i84@pure_quanta.q_cap(chips)',
 PATH='I84',
 DRAWING='@T6G_MB_LIB.T6G(SCH_1):PAGE465',
 TOLERANCE='20%',
 MATERIAL='X6S',
 PHYS_PAGE='356',
 XY='(-1875,3525)',
 ROT='0',
 VER='1',
 PACK_TYPE='0201',
 LOCATION='C452',
 CDS_LIB='pure_quanta',
 CDS_PART_NAME='Q_CAP_0201-1UF,4V,20%,X6S,CH-10KMEE00',
 VOLTAGE='4V',
 PART_NUMBER='CH-10KMEE00',
 VALUE='1UF',
 PRIM_FILE='./archive_libs/logical/q_cap/chips/chips.prt';

PART_NAME
 C453 'Q_CAP_0201-1UF,4V,20%,X6S,CH-10KMEE00':;

SECTION_NUMBER 1
 '@T6G_MB_LIB.T6G(SCH_1):PAGE465_I45@PURE_QUANTA.Q_CAP(CHIPS)':
 C_PATH='@t6g_mb_lib.t6g(sch_1):page465_i45@pure_quanta.q_cap(chips)',
 P_PATH='@t6g_mb_lib.t6g(sch_1):page356_i45@pure_quanta.q_cap(chips)',
 PATH='I45',
 DRAWING='@T6G_MB_LIB.T6G(SCH_1):PAGE465',
 TOLERANCE='20%',
 MATERIAL='X6S',
 PHYS_PAGE='356',
 XY='(-2775,2900)',
 ROT='0',
 VER='1',
 PACK_TYPE='0201',
 LOCATION='C453',
 CDS_LIB='pure_quanta',
 CDS_PART_NAME='Q_CAP_0201-1UF,4V,20%,X6S,CH-10KMEE00',
 VOLTAGE='4V',
 PART_NUMBER='CH-10KMEE00',
 VALUE='1UF',
 PRIM_FILE='./archive_libs/logical/q_cap/chips/chips.prt';

PART_NAME
 C454 'Q_CAP_0201-1UF,4V,20%,X6S,CH-10KMEE00':;

SECTION_NUMBER 1
 '@T6G_MB_LIB.T6G(SCH_1):PAGE465_I74@PURE_QUANTA.Q_CAP(CHIPS)':
 C_PATH='@t6g_mb_lib.t6g(sch_1):page465_i74@pure_quanta.q_cap(chips)',
 P_PATH='@t6g_mb_lib.t6g(sch_1):page356_i74@pure_quanta.q_cap(chips)',
 PATH='I74',
 DRAWING='@T6G_MB_LIB.T6G(SCH_1):PAGE465',
 TOLERANCE='20%',
 MATERIAL='X6S',
 PHYS_PAGE='356',
 XY='(-2225,5400)',
 ROT='0',
 VER='1',
 PACK_TYPE='0201',
 LOCATION='C454',
 CDS_LIB='pure_quanta',
 CDS_PART_NAME='Q_CAP_0201-1UF,4V,20%,X6S,CH-10KMEE00',
 VOLTAGE='4V',
 PART_NUMBER='CH-10KMEE00',
 VALUE='1UF',
 PRIM_FILE='./archive_libs/logical/q_cap/chips/chips.prt';

PART_NAME
 C455 'Q_CAP_0201-1UF,4V,20%,X6S,CH-10KMEE00':;

SECTION_NUMBER 1
 '@T6G_MB_LIB.T6G(SCH_1):PAGE465_I61@PURE_QUANTA.Q_CAP(CHIPS)':
 C_PATH='@t6g_mb_lib.t6g(sch_1):page465_i61@pure_quanta.q_cap(chips)',
 P_PATH='@t6g_mb_lib.t6g(sch_1):page356_i61@pure_quanta.q_cap(chips)',
 PATH='I61',
 DRAWING='@T6G_MB_LIB.T6G(SCH_1):PAGE465',
 TOLERANCE='20%',
 MATERIAL='X6S',
 PHYS_PAGE='356',
 XY='(-1400,3525)',
 ROT='0',
 VER='1',
 PACK_TYPE='0201',
 LOCATION='C455',
 CDS_LIB='pure_quanta',
 CDS_PART_NAME='Q_CAP_0201-1UF,4V,20%,X6S,CH-10KMEE00',
 VOLTAGE='4V',
 PART_NUMBER='CH-10KMEE00',
 VALUE='1UF',
 PRIM_FILE='./archive_libs/logical/q_cap/chips/chips.prt';

PART_NAME
 C456 'Q_CAP_0201-1UF,4V,20%,X6S,CH-10KMEE00':;

SECTION_NUMBER 1
 '@T6G_MB_LIB.T6G(SCH_1):PAGE465_I90@PURE_QUANTA.Q_CAP(CHIPS)':
 C_PATH='@t6g_mb_lib.t6g(sch_1):page465_i90@pure_quanta.q_cap(chips)',
 P_PATH='@t6g_mb_lib.t6g(sch_1):page356_i90@pure_quanta.q_cap(chips)',
 PATH='I90',
 DRAWING='@T6G_MB_LIB.T6G(SCH_1):PAGE465',
 TOLERANCE='20%',
 MATERIAL='X6S',
 PHYS_PAGE='356',
 XY='(-3025,1100)',
 ROT='0',
 VER='1',
 PACK_TYPE='0201',
 LOCATION='C456',
 CDS_LIB='pure_quanta',
 CDS_PART_NAME='Q_CAP_0201-1UF,4V,20%,X6S,CH-10KMEE00',
 VOLTAGE='4V',
 PART_NUMBER='CH-10KMEE00',
 VALUE='1UF',
 PRIM_FILE='./archive_libs/logical/q_cap/chips/chips.prt';

PART_NAME
 C457 'Q_CAP_C0201-0.1UF,10V,10%,X7S,CH4102K6E00':;

SECTION_NUMBER 1
 '@T6G_MB_LIB.T6G(SCH_1):PAGE465_I57@PURE_QUANTA.Q_CAP(CHIPS)':
 C_PATH='@t6g_mb_lib.t6g(sch_1):page465_i57@pure_quanta.q_cap(chips)',
 P_PATH='@t6g_mb_lib.t6g(sch_1):page356_i57@pure_quanta.q_cap(chips)',
 PATH='I57',
 DRAWING='@T6G_MB_LIB.T6G(SCH_1):PAGE465',
 TOLERANCE='10%',
 MATERIAL='X7S',
 PHYS_PAGE='356',
 XY='(-1625,2200)',
 ROT='0',
 VER='1',
 PACK_TYPE='C0201',
 LOCATION='C457',
 CDS_LIB='pure_quanta',
 CDS_PART_NAME='Q_CAP_C0201-0.1UF,10V,10%,X7S,CH4102K6E00',
 VOLTAGE='10V',
 PART_NUMBER='CH4102K6E00',
 VALUE='0.1UF',
 PRIM_FILE='./archive_libs/logical/q_cap/chips/chips.prt';

PART_NAME
 C458 'Q_CAP_C0201-0.1UF,10V,10%,X7S,CH4102K6E00':;

SECTION_NUMBER 1
 '@T6G_MB_LIB.T6G(SCH_1):PAGE465_I82@PURE_QUANTA.Q_CAP(CHIPS)':
 C_PATH='@t6g_mb_lib.t6g(sch_1):page465_i82@pure_quanta.q_cap(chips)',
 P_PATH='@t6g_mb_lib.t6g(sch_1):page356_i82@pure_quanta.q_cap(chips)',
 PATH='I82',
 DRAWING='@T6G_MB_LIB.T6G(SCH_1):PAGE465',
 TOLERANCE='10%',
 MATERIAL='X7S',
 PHYS_PAGE='356',
 XY='(-1125,5375)',
 ROT='0',
 VER='1',
 PACK_TYPE='C0201',
 LOCATION='C458',
 CDS_LIB='pure_quanta',
 CDS_PART_NAME='Q_CAP_C0201-0.1UF,10V,10%,X7S,CH4102K6E00',
 VOLTAGE='10V',
 PART_NUMBER='CH4102K6E00',
 VALUE='0.1UF',
 PRIM_FILE='./archive_libs/logical/q_cap/chips/chips.prt';

PART_NAME
 C459 'Q_CAP_0201-1UF,4V,20%,X6S,CH-10KMEE00':;

SECTION_NUMBER 1
 '@T6G_MB_LIB.T6G(SCH_1):PAGE465_I39@PURE_QUANTA.Q_CAP(CHIPS)':
 C_PATH='@t6g_mb_lib.t6g(sch_1):page465_i39@pure_quanta.q_cap(chips)',
 P_PATH='@t6g_mb_lib.t6g(sch_1):page356_i39@pure_quanta.q_cap(chips)',
 PATH='I39',
 DRAWING='@T6G_MB_LIB.T6G(SCH_1):PAGE465',
 TOLERANCE='20%',
 MATERIAL='X6S',
 PHYS_PAGE='356',
 XY='(-3250,2900)',
 ROT='0',
 VER='1',
 PACK_TYPE='0201',
 LOCATION='C459',
 CDS_LIB='pure_quanta',
 CDS_PART_NAME='Q_CAP_0201-1UF,4V,20%,X6S,CH-10KMEE00',
 VOLTAGE='4V',
 PART_NUMBER='CH-10KMEE00',
 VALUE='1UF',
 PRIM_FILE='./archive_libs/logical/q_cap/chips/chips.prt';

PART_NAME
 C460 'Q_CAP_0201-1UF,4V,20%,X6S,CH-10KMEE00':;

SECTION_NUMBER 1
 '@T6G_MB_LIB.T6G(SCH_1):PAGE465_I91@PURE_QUANTA.Q_CAP(CHIPS)':
 C_PATH='@t6g_mb_lib.t6g(sch_1):page465_i91@pure_quanta.q_cap(chips)',
 P_PATH='@t6g_mb_lib.t6g(sch_1):page356_i91@pure_quanta.q_cap(chips)',
 PATH='I91',
 DRAWING='@T6G_MB_LIB.T6G(SCH_1):PAGE465',
 TOLERANCE='20%',
 MATERIAL='X6S',
 PHYS_PAGE='356',
 XY='(-2775,1100)',
 ROT='0',
 VER='1',
 PACK_TYPE='0201',
 LOCATION='C460',
 CDS_LIB='pure_quanta',
 CDS_PART_NAME='Q_CAP_0201-1UF,4V,20%,X6S,CH-10KMEE00',
 VOLTAGE='4V',
 PART_NUMBER='CH-10KMEE00',
 VALUE='1UF',
 PRIM_FILE='./archive_libs/logical/q_cap/chips/chips.prt';

PART_NAME
 C461 'Q_CAP_0402-1000PF,50V,5%,X7R,TMP_QCH21006JB10':;

SECTION_NUMBER 1
 '@T6G_MB_LIB.T6G(SCH_1):PAGE168_I13@PURE_QUANTA.Q_CAP(CHIPS)':
 C_PATH='@t6g_mb_lib.t6g(sch_1):page168_i13@pure_quanta.q_cap(chips)',
 P_PATH='@t6g_mb_lib.t6g(sch_1):page193_i13@pure_quanta.q_cap(chips)',
 PATH='I13',
 DRAWING='@T6G_MB_LIB.T6G(SCH_1):PAGE168',
 TOLERANCE='5%',
 MATERIAL='X7R',
 PHYS_PAGE='193',
 XY='(-7675,1600)',
 ROT='0',
 VER='1',
 PACK_TYPE='0402',
 LOCATION='C461',
 CDS_LIB='pure_quanta',
 CDS_PART_NAME='Q_CAP_0402-1000PF,50V,5%,X7R,TMP_QCH21006JB10',
 VOLTAGE='50V',
 PART_NUMBER='TMP_QCH21006JB10',
 VALUE='1000PF',
 PRIM_FILE='./archive_libs/logical/q_cap/chips/chips.prt';

PART_NAME
 C462 'Q_CAP_C0201-0.1UF,10V,10%,X7S,CH4102K6E00':;

SECTION_NUMBER 1
 '@T6G_MB_LIB.T6G(SCH_1):PAGE465_I83@PURE_QUANTA.Q_CAP(CHIPS)':
 C_PATH='@t6g_mb_lib.t6g(sch_1):page465_i83@pure_quanta.q_cap(chips)',
 P_PATH='@t6g_mb_lib.t6g(sch_1):page356_i83@pure_quanta.q_cap(chips)',
 PATH='I83',
 DRAWING='@T6G_MB_LIB.T6G(SCH_1):PAGE465',
 TOLERANCE='10%',
 MATERIAL='X7S',
 PHYS_PAGE='356',
 XY='(-1375,2200)',
 ROT='0',
 VER='1',
 PACK_TYPE='C0201',
 LOCATION='C462',
 CDS_LIB='pure_quanta',
 CDS_PART_NAME='Q_CAP_C0201-0.1UF,10V,10%,X7S,CH4102K6E00',
 VOLTAGE='10V',
 PART_NUMBER='CH4102K6E00',
 VALUE='0.1UF',
 PRIM_FILE='./archive_libs/logical/q_cap/chips/chips.prt';

PART_NAME
 C463 'Q_CAP_C0201-0.1UF,10V,10%,X7S,CH4102K6E00':;

SECTION_NUMBER 1
 '@T6G_MB_LIB.T6G(SCH_1):PAGE465_I34@PURE_QUANTA.Q_CAP(CHIPS)':
 C_PATH='@t6g_mb_lib.t6g(sch_1):page465_i34@pure_quanta.q_cap(chips)',
 P_PATH='@t6g_mb_lib.t6g(sch_1):page356_i34@pure_quanta.q_cap(chips)',
 PATH='I34',
 DRAWING='@T6G_MB_LIB.T6G(SCH_1):PAGE465',
 TOLERANCE='10%',
 MATERIAL='X7S',
 PHYS_PAGE='356',
 XY='(-2475,1100)',
 ROT='0',
 VER='1',
 PACK_TYPE='C0201',
 LOCATION='C463',
 CDS_LIB='pure_quanta',
 CDS_PART_NAME='Q_CAP_C0201-0.1UF,10V,10%,X7S,CH4102K6E00',
 VOLTAGE='10V',
 PART_NUMBER='CH4102K6E00',
 VALUE='0.1UF',
 PRIM_FILE='./archive_libs/logical/q_cap/chips/chips.prt';

PART_NAME
 C464 'Q_CAP_C0201-0.1UF,10V,10%,X7S,CH4102K6E00':;

SECTION_NUMBER 1
 '@T6G_MB_LIB.T6G(SCH_1):PAGE465_I35@PURE_QUANTA.Q_CAP(CHIPS)':
 C_PATH='@t6g_mb_lib.t6g(sch_1):page465_i35@pure_quanta.q_cap(chips)',
 P_PATH='@t6g_mb_lib.t6g(sch_1):page356_i35@pure_quanta.q_cap(chips)',
 PATH='I35',
 DRAWING='@T6G_MB_LIB.T6G(SCH_1):PAGE465',
 TOLERANCE='10%',
 MATERIAL='X7S',
 PHYS_PAGE='356',
 XY='(-2225,1100)',
 ROT='0',
 VER='1',
 PACK_TYPE='C0201',
 LOCATION='C464',
 CDS_LIB='pure_quanta',
 CDS_PART_NAME='Q_CAP_C0201-0.1UF,10V,10%,X7S,CH4102K6E00',
 VOLTAGE='10V',
 PART_NUMBER='CH4102K6E00',
 VALUE='0.1UF',
 PRIM_FILE='./archive_libs/logical/q_cap/chips/chips.prt';

PART_NAME
 C465 'Q_CAP_0402-1000PF,50V,5%,EMPTY,TMP_QCH21006JB10':;

SECTION_NUMBER 1
 '@T6G_MB_LIB.T6G(SCH_1):PAGE168_I51@PURE_QUANTA.Q_CAP(CHIPS)':
 C_PATH='@t6g_mb_lib.t6g(sch_1):page168_i51@pure_quanta.q_cap(chips)',
 P_PATH='@t6g_mb_lib.t6g(sch_1):page193_i51@pure_quanta.q_cap(chips)',
 PATH='I51',
 DRAWING='@T6G_MB_LIB.T6G(SCH_1):PAGE168',
 TOLERANCE='5%',
 MATERIAL='EMPTY',
 PHYS_PAGE='193',
 XY='(-5225,1650)',
 ROT='0',
 VER='2',
 PACK_TYPE='0402',
 LOCATION='C465',
 CDS_LIB='pure_quanta',
 CDS_PART_NAME='Q_CAP_0402-1000PF,50V,5%,EMPTY,TMP_QCH21006JB10',
 VOLTAGE='50V',
 PART_NUMBER='TMP_QCH21006JB10',
 VALUE='1000PF',
 PRIM_FILE='./archive_libs/logical/q_cap/chips/chips.prt';

PART_NAME
 C466 'Q_CAP_C0805-100UF,4V,20%,X6S,CH710KMEA01':;

SECTION_NUMBER 1
 '@T6G_MB_LIB.T6G(SCH_1):PAGE465_I64@PURE_QUANTA.Q_CAP(CHIPS)':
 C_PATH='@t6g_mb_lib.t6g(sch_1):page465_i64@pure_quanta.q_cap(chips)',
 P_PATH='@t6g_mb_lib.t6g(sch_1):page356_i64@pure_quanta.q_cap(chips)',
 PATH='I64',
 DRAWING='@T6G_MB_LIB.T6G(SCH_1):PAGE465',
 TOLERANCE='20%',
 MATERIAL='X6S',
 PHYS_PAGE='356',
 XY='(-3475,4150)',
 ROT='0',
 VER='1',
 PACK_TYPE='C0805',
 LOCATION='C466',
 CDS_LIB='pure_quanta',
 CDS_PART_NAME='Q_CAP_C0805-100UF,4V,20%,X6S,CH710KMEA01',
 VOLTAGE='4V',
 PART_NUMBER='CH710KMEA01',
 VALUE='100UF',
 PRIM_FILE='./archive_libs/logical/q_cap/chips/chips.prt';

PART_NAME
 C467 'Q_CAP_0402-1000PF,50V,5%,EMPTY,TMP_QCH21006JB10':;

SECTION_NUMBER 1
 '@T6G_MB_LIB.T6G(SCH_1):PAGE168_I92@PURE_QUANTA.Q_CAP(CHIPS)':
 C_PATH='@t6g_mb_lib.t6g(sch_1):page168_i92@pure_quanta.q_cap(chips)',
 P_PATH='@t6g_mb_lib.t6g(sch_1):page193_i92@pure_quanta.q_cap(chips)',
 PATH='I92',
 DRAWING='@T6G_MB_LIB.T6G(SCH_1):PAGE168',
 TOLERANCE='5%',
 MATERIAL='EMPTY',
 PHYS_PAGE='193',
 XY='(-4825,6775)',
 ROT='0',
 VER='2',
 PACK_TYPE='0402',
 LOCATION='C467',
 CDS_LIB='pure_quanta',
 CDS_PART_NAME='Q_CAP_0402-1000PF,50V,5%,EMPTY,TMP_QCH21006JB10',
 VOLTAGE='50V',
 PART_NUMBER='TMP_QCH21006JB10',
 VALUE='1000PF',
 PRIM_FILE='./archive_libs/logical/q_cap/chips/chips.prt';

PART_NAME
 C468 'Q_CAP_0402-1000PF,50V,5%,X7R,TMP_QCH21006JB10':;

SECTION_NUMBER 1
 '@T6G_MB_LIB.T6G(SCH_1):PAGE168_I90@PURE_QUANTA.Q_CAP(CHIPS)':
 C_PATH='@t6g_mb_lib.t6g(sch_1):page168_i90@pure_quanta.q_cap(chips)',
 P_PATH='@t6g_mb_lib.t6g(sch_1):page193_i90@pure_quanta.q_cap(chips)',
 PATH='I90',
 DRAWING='@T6G_MB_LIB.T6G(SCH_1):PAGE168',
 TOLERANCE='5%',
 MATERIAL='X7R',
 PHYS_PAGE='193',
 XY='(-4800,6225)',
 ROT='0',
 VER='2',
 PACK_TYPE='0402',
 LOCATION='C468',
 CDS_LIB='pure_quanta',
 CDS_PART_NAME='Q_CAP_0402-1000PF,50V,5%,X7R,TMP_QCH21006JB10',
 VOLTAGE='50V',
 PART_NUMBER='TMP_QCH21006JB10',
 VALUE='1000PF',
 PRIM_FILE='./archive_libs/logical/q_cap/chips/chips.prt';

PART_NAME
 C469 'Q_CAP_0402-4.7UF,6.3V,20%,X6S,CH5471MEB01':;

SECTION_NUMBER 1
 '@T6G_MB_LIB.T6G(SCH_1):PAGE465_I51@PURE_QUANTA.Q_CAP(CHIPS)':
 C_PATH='@t6g_mb_lib.t6g(sch_1):page465_i51@pure_quanta.q_cap(chips)',
 P_PATH='@t6g_mb_lib.t6g(sch_1):page356_i51@pure_quanta.q_cap(chips)',
 PATH='I51',
 DRAWING='@T6G_MB_LIB.T6G(SCH_1):PAGE465',
 TOLERANCE='20%',
 MATERIAL='X6S',
 PHYS_PAGE='356',
 XY='(-2800,3525)',
 ROT='0',
 VER='1',
 PACK_TYPE='0402',
 LOCATION='C469',
 CDS_LIB='pure_quanta',
 CDS_PART_NAME='Q_CAP_0402-4.7UF,6.3V,20%,X6S,CH5471MEB01',
 VOLTAGE='6.3V',
 PART_NUMBER='CH5471MEB01',
 VALUE='4.7UF',
 PRIM_FILE='./archive_libs/logical/q_cap/chips/chips.prt';

PART_NAME
 C470 'Q_CAP_0201-1UF,4V,20%,X6S,CH-10KMEE00':;

SECTION_NUMBER 1
 '@T6G_MB_LIB.T6G(SCH_1):PAGE465_I38@PURE_QUANTA.Q_CAP(CHIPS)':
 C_PATH='@t6g_mb_lib.t6g(sch_1):page465_i38@pure_quanta.q_cap(chips)',
 P_PATH='@t6g_mb_lib.t6g(sch_1):page356_i38@pure_quanta.q_cap(chips)',
 PATH='I38',
 DRAWING='@T6G_MB_LIB.T6G(SCH_1):PAGE465',
 TOLERANCE='20%',
 MATERIAL='X6S',
 PHYS_PAGE='356',
 XY='(-3475,2900)',
 ROT='0',
 VER='1',
 PACK_TYPE='0201',
 LOCATION='C470',
 CDS_LIB='pure_quanta',
 CDS_PART_NAME='Q_CAP_0201-1UF,4V,20%,X6S,CH-10KMEE00',
 VOLTAGE='4V',
 PART_NUMBER='CH-10KMEE00',
 VALUE='1UF',
 PRIM_FILE='./archive_libs/logical/q_cap/chips/chips.prt';

PART_NAME
 C471 'Q_CAP_C0805-100UF,4V,20%,X6S,CH710KMEA01':;

SECTION_NUMBER 1
 '@T6G_MB_LIB.T6G(SCH_1):PAGE465_I65@PURE_QUANTA.Q_CAP(CHIPS)':
 C_PATH='@t6g_mb_lib.t6g(sch_1):page465_i65@pure_quanta.q_cap(chips)',
 P_PATH='@t6g_mb_lib.t6g(sch_1):page356_i65@pure_quanta.q_cap(chips)',
 PATH='I65',
 DRAWING='@T6G_MB_LIB.T6G(SCH_1):PAGE465',
 TOLERANCE='20%',
 MATERIAL='X6S',
 PHYS_PAGE='356',
 XY='(-3250,4150)',
 ROT='0',
 VER='1',
 PACK_TYPE='C0805',
 LOCATION='C471',
 CDS_LIB='pure_quanta',
 CDS_PART_NAME='Q_CAP_C0805-100UF,4V,20%,X6S,CH710KMEA01',
 VOLTAGE='4V',
 PART_NUMBER='CH710KMEA01',
 VALUE='100UF',
 PRIM_FILE='./archive_libs/logical/q_cap/chips/chips.prt';

PART_NAME
 C472 'Q_CAP_0402-4.7UF,6.3V,20%,X6S,CH5471MEB01':;

SECTION_NUMBER 1
 '@T6G_MB_LIB.T6G(SCH_1):PAGE465_I50@PURE_QUANTA.Q_CAP(CHIPS)':
 C_PATH='@t6g_mb_lib.t6g(sch_1):page465_i50@pure_quanta.q_cap(chips)',
 P_PATH='@t6g_mb_lib.t6g(sch_1):page356_i50@pure_quanta.q_cap(chips)',
 PATH='I50',
 DRAWING='@T6G_MB_LIB.T6G(SCH_1):PAGE465',
 TOLERANCE='20%',
 MATERIAL='X6S',
 PHYS_PAGE='356',
 XY='(-3025,3525)',
 ROT='0',
 VER='1',
 PACK_TYPE='0402',
 LOCATION='C472',
 CDS_LIB='pure_quanta',
 CDS_PART_NAME='Q_CAP_0402-4.7UF,6.3V,20%,X6S,CH5471MEB01',
 VOLTAGE='6.3V',
 PART_NUMBER='CH5471MEB01',
 VALUE='4.7UF',
 PRIM_FILE='./archive_libs/logical/q_cap/chips/chips.prt';

PART_NAME
 C473 'Q_CAP_C0201-0.1UF,10V,10%,X7S,CH4102K6E00':;

SECTION_NUMBER 1
 '@T6G_MB_LIB.T6G(SCH_1):PAGE465_I43@PURE_QUANTA.Q_CAP(CHIPS)':
 C_PATH='@t6g_mb_lib.t6g(sch_1):page465_i43@pure_quanta.q_cap(chips)',
 P_PATH='@t6g_mb_lib.t6g(sch_1):page356_i43@pure_quanta.q_cap(chips)',
 PATH='I43',
 DRAWING='@T6G_MB_LIB.T6G(SCH_1):PAGE465',
 TOLERANCE='10%',
 MATERIAL='X7S',
 PHYS_PAGE='356',
 XY='(-2675,2200)',
 ROT='0',
 VER='1',
 PACK_TYPE='C0201',
 LOCATION='C473',
 CDS_LIB='pure_quanta',
 CDS_PART_NAME='Q_CAP_C0201-0.1UF,10V,10%,X7S,CH4102K6E00',
 VOLTAGE='10V',
 PART_NUMBER='CH4102K6E00',
 VALUE='0.1UF',
 PRIM_FILE='./archive_libs/logical/q_cap/chips/chips.prt';

PART_NAME
 C474 'Q_CAP_C0805-100UF,4V,20%,X6S,CH710KMEA01':;

SECTION_NUMBER 1
 '@T6G_MB_LIB.T6G(SCH_1):PAGE465_I67@PURE_QUANTA.Q_CAP(CHIPS)':
 C_PATH='@t6g_mb_lib.t6g(sch_1):page465_i67@pure_quanta.q_cap(chips)',
 P_PATH='@t6g_mb_lib.t6g(sch_1):page356_i67@pure_quanta.q_cap(chips)',
 PATH='I67',
 DRAWING='@T6G_MB_LIB.T6G(SCH_1):PAGE465',
 TOLERANCE='20%',
 MATERIAL='X6S',
 PHYS_PAGE='356',
 XY='(-3425,5425)',
 ROT='0',
 VER='1',
 PACK_TYPE='C0805',
 LOCATION='C474',
 CDS_LIB='pure_quanta',
 CDS_PART_NAME='Q_CAP_C0805-100UF,4V,20%,X6S,CH710KMEA01',
 VOLTAGE='4V',
 PART_NUMBER='CH710KMEA01',
 VALUE='100UF',
 PRIM_FILE='./archive_libs/logical/q_cap/chips/chips.prt';

PART_NAME
 C475 'Q_CAP_C0805-100UF,4V,20%,X6S,CH710KMEA01':;

SECTION_NUMBER 1
 '@T6G_MB_LIB.T6G(SCH_1):PAGE465_I69@PURE_QUANTA.Q_CAP(CHIPS)':
 C_PATH='@t6g_mb_lib.t6g(sch_1):page465_i69@pure_quanta.q_cap(chips)',
 P_PATH='@t6g_mb_lib.t6g(sch_1):page356_i69@pure_quanta.q_cap(chips)',
 PATH='I69',
 DRAWING='@T6G_MB_LIB.T6G(SCH_1):PAGE465',
 TOLERANCE='20%',
 MATERIAL='X6S',
 PHYS_PAGE='356',
 XY='(-3025,4150)',
 ROT='0',
 VER='1',
 PACK_TYPE='C0805',
 LOCATION='C475',
 CDS_LIB='pure_quanta',
 CDS_PART_NAME='Q_CAP_C0805-100UF,4V,20%,X6S,CH710KMEA01',
 VOLTAGE='4V',
 PART_NUMBER='CH710KMEA01',
 VALUE='100UF',
 PRIM_FILE='./archive_libs/logical/q_cap/chips/chips.prt';

PART_NAME
 C476 'Q_CAP_C0402-22UF,4V,20%,X6S,CH622KMEB02':;

SECTION_NUMBER 1
 '@T6G_MB_LIB.T6G(SCH_1):PAGE465_I71@PURE_QUANTA.Q_CAP(CHIPS)':
 C_PATH='@t6g_mb_lib.t6g(sch_1):page465_i71@pure_quanta.q_cap(chips)',
 P_PATH='@t6g_mb_lib.t6g(sch_1):page356_i71@pure_quanta.q_cap(chips)',
 PATH='I71',
 DRAWING='@T6G_MB_LIB.T6G(SCH_1):PAGE465',
 TOLERANCE='20%',
 MATERIAL='X6S',
 PHYS_PAGE='356',
 XY='(-2100,4150)',
 ROT='0',
 VER='1',
 PACK_TYPE='C0402',
 LOCATION='C476',
 CDS_LIB='pure_quanta',
 CDS_PART_NAME='Q_CAP_C0402-22UF,4V,20%,X6S,CH622KMEB02',
 VOLTAGE='4V',
 PART_NUMBER='CH622KMEB02',
 VALUE='22UF',
 PRIM_FILE='./archive_libs/logical/q_cap/chips/chips.prt';

PART_NAME
 C477 'Q_CAP_C0201-0.1UF,10V,10%,X7S,CH4102K6E00':;

SECTION_NUMBER 1
 '@T6G_MB_LIB.T6G(SCH_1):PAGE465_I46@PURE_QUANTA.Q_CAP(CHIPS)':
 C_PATH='@t6g_mb_lib.t6g(sch_1):page465_i46@pure_quanta.q_cap(chips)',
 P_PATH='@t6g_mb_lib.t6g(sch_1):page356_i46@pure_quanta.q_cap(chips)',
 PATH='I46',
 DRAWING='@T6G_MB_LIB.T6G(SCH_1):PAGE465',
 TOLERANCE='10%',
 MATERIAL='X7S',
 PHYS_PAGE='356',
 XY='(-2425,2200)',
 ROT='0',
 VER='1',
 PACK_TYPE='C0201',
 LOCATION='C477',
 CDS_LIB='pure_quanta',
 CDS_PART_NAME='Q_CAP_C0201-0.1UF,10V,10%,X7S,CH4102K6E00',
 VOLTAGE='10V',
 PART_NUMBER='CH4102K6E00',
 VALUE='0.1UF',
 PRIM_FILE='./archive_libs/logical/q_cap/chips/chips.prt';

PART_NAME
 C478 'Q_CAP_C0402-22UF,4V,20%,X6S,CH622KMEB02':;

SECTION_NUMBER 1
 '@T6G_MB_LIB.T6G(SCH_1):PAGE465_I68@PURE_QUANTA.Q_CAP(CHIPS)':
 C_PATH='@t6g_mb_lib.t6g(sch_1):page465_i68@pure_quanta.q_cap(chips)',
 P_PATH='@t6g_mb_lib.t6g(sch_1):page356_i68@pure_quanta.q_cap(chips)',
 PATH='I68',
 DRAWING='@T6G_MB_LIB.T6G(SCH_1):PAGE465',
 TOLERANCE='20%',
 MATERIAL='X6S',
 PHYS_PAGE='356',
 XY='(-3150,5425)',
 ROT='0',
 VER='1',
 PACK_TYPE='C0402',
 LOCATION='C478',
 CDS_LIB='pure_quanta',
 CDS_PART_NAME='Q_CAP_C0402-22UF,4V,20%,X6S,CH622KMEB02',
 VOLTAGE='4V',
 PART_NUMBER='CH622KMEB02',
 VALUE='22UF',
 PRIM_FILE='./archive_libs/logical/q_cap/chips/chips.prt';

PART_NAME
 C479 'Q_CAP_C0805-100UF,4V,20%,X6S,CH710KMEA01':;

SECTION_NUMBER 1
 '@T6G_MB_LIB.T6G(SCH_1):PAGE465_I87@PURE_QUANTA.Q_CAP(CHIPS)':
 C_PATH='@t6g_mb_lib.t6g(sch_1):page465_i87@pure_quanta.q_cap(chips)',
 P_PATH='@t6g_mb_lib.t6g(sch_1):page356_i87@pure_quanta.q_cap(chips)',
 PATH='I87',
 DRAWING='@T6G_MB_LIB.T6G(SCH_1):PAGE465',
 TOLERANCE='20%',
 MATERIAL='X6S',
 PHYS_PAGE='356',
 XY='(-2800,4150)',
 ROT='0',
 VER='1',
 PACK_TYPE='C0805',
 LOCATION='C479',
 CDS_LIB='pure_quanta',
 CDS_PART_NAME='Q_CAP_C0805-100UF,4V,20%,X6S,CH710KMEA01',
 VOLTAGE='4V',
 PART_NUMBER='CH710KMEA01',
 VALUE='100UF',
 PRIM_FILE='./archive_libs/logical/q_cap/chips/chips.prt';

PART_NAME
 C480 'Q_CAP_C0402-10UF,6.3V,20%,X6S,CH6101MEB01':;

SECTION_NUMBER 1
 '@T6G_MB_LIB.T6G(SCH_1):PAGE465_I40@PURE_QUANTA.Q_CAP(CHIPS)':
 C_PATH='@t6g_mb_lib.t6g(sch_1):page465_i40@pure_quanta.q_cap(chips)',
 P_PATH='@t6g_mb_lib.t6g(sch_1):page356_i40@pure_quanta.q_cap(chips)',
 PATH='I40',
 DRAWING='@T6G_MB_LIB.T6G(SCH_1):PAGE465',
 TOLERANCE='20%',
 MATERIAL='X6S',
 PHYS_PAGE='356',
 XY='(-3475,3525)',
 ROT='0',
 VER='1',
 PACK_TYPE='C0402',
 LOCATION='C480',
 CDS_LIB='pure_quanta',
 CDS_PART_NAME='Q_CAP_C0402-10UF,6.3V,20%,X6S,CH6101MEB01',
 VOLTAGE='6.3V',
 PART_NUMBER='CH6101MEB01',
 VALUE='10UF',
 PRIM_FILE='./archive_libs/logical/q_cap/chips/chips.prt';

PART_NAME
 C481 'Q_CAP_C0201-0.1UF,10V,10%,X7S,CH4102K6E00':;

SECTION_NUMBER 1
 '@T6G_MB_LIB.T6G(SCH_1):PAGE465_I56@PURE_QUANTA.Q_CAP(CHIPS)':
 C_PATH='@t6g_mb_lib.t6g(sch_1):page465_i56@pure_quanta.q_cap(chips)',
 P_PATH='@t6g_mb_lib.t6g(sch_1):page356_i56@pure_quanta.q_cap(chips)',
 PATH='I56',
 DRAWING='@T6G_MB_LIB.T6G(SCH_1):PAGE465',
 TOLERANCE='10%',
 MATERIAL='X7S',
 PHYS_PAGE='356',
 XY='(-1900,2200)',
 ROT='0',
 VER='1',
 PACK_TYPE='C0201',
 LOCATION='C481',
 CDS_LIB='pure_quanta',
 CDS_PART_NAME='Q_CAP_C0201-0.1UF,10V,10%,X7S,CH4102K6E00',
 VOLTAGE='10V',
 PART_NUMBER='CH4102K6E00',
 VALUE='0.1UF',
 PRIM_FILE='./archive_libs/logical/q_cap/chips/chips.prt';

PART_NAME
 C482 'Q_CAP_C0402-10UF,6.3V,20%,X6S,CH6101MEB01':;

SECTION_NUMBER 1
 '@T6G_MB_LIB.T6G(SCH_1):PAGE465_I77@PURE_QUANTA.Q_CAP(CHIPS)':
 C_PATH='@t6g_mb_lib.t6g(sch_1):page465_i77@pure_quanta.q_cap(chips)',
 P_PATH='@t6g_mb_lib.t6g(sch_1):page356_i77@pure_quanta.q_cap(chips)',
 PATH='I77',
 DRAWING='@T6G_MB_LIB.T6G(SCH_1):PAGE465',
 TOLERANCE='20%',
 MATERIAL='X6S',
 PHYS_PAGE='356',
 XY='(-1275,4150)',
 ROT='0',
 VER='1',
 PACK_TYPE='C0402',
 LOCATION='C482',
 CDS_LIB='pure_quanta',
 CDS_PART_NAME='Q_CAP_C0402-10UF,6.3V,20%,X6S,CH6101MEB01',
 VOLTAGE='6.3V',
 PART_NUMBER='CH6101MEB01',
 VALUE='10UF',
 PRIM_FILE='./archive_libs/logical/q_cap/chips/chips.prt';

PART_NAME
 C483 'Q_CAP_0402-4.7UF,6.3V,20%,X6S,CH5471MEB01':;

SECTION_NUMBER 1
 '@T6G_MB_LIB.T6G(SCH_1):PAGE465_I86@PURE_QUANTA.Q_CAP(CHIPS)':
 C_PATH='@t6g_mb_lib.t6g(sch_1):page465_i86@pure_quanta.q_cap(chips)',
 P_PATH='@t6g_mb_lib.t6g(sch_1):page356_i86@pure_quanta.q_cap(chips)',
 PATH='I86',
 DRAWING='@T6G_MB_LIB.T6G(SCH_1):PAGE465',
 TOLERANCE='20%',
 MATERIAL='X6S',
 PHYS_PAGE='356',
 XY='(-2550,3525)',
 ROT='0',
 VER='1',
 PACK_TYPE='0402',
 LOCATION='C483',
 CDS_LIB='pure_quanta',
 CDS_PART_NAME='Q_CAP_0402-4.7UF,6.3V,20%,X6S,CH5471MEB01',
 VOLTAGE='6.3V',
 PART_NUMBER='CH5471MEB01',
 VALUE='4.7UF',
 PRIM_FILE='./archive_libs/logical/q_cap/chips/chips.prt';

PART_NAME
 C484 'Q_CAP_0402-4.7UF,6.3V,20%,X6S,CH5471MEB01':;

SECTION_NUMBER 1
 '@T6G_MB_LIB.T6G(SCH_1):PAGE465_I73@PURE_QUANTA.Q_CAP(CHIPS)':
 C_PATH='@t6g_mb_lib.t6g(sch_1):page465_i73@pure_quanta.q_cap(chips)',
 P_PATH='@t6g_mb_lib.t6g(sch_1):page356_i73@pure_quanta.q_cap(chips)',
 PATH='I73',
 DRAWING='@T6G_MB_LIB.T6G(SCH_1):PAGE465',
 TOLERANCE='20%',
 MATERIAL='X6S',
 PHYS_PAGE='356',
 XY='(-2525,5400)',
 ROT='0',
 VER='1',
 PACK_TYPE='0402',
 LOCATION='C484',
 CDS_LIB='pure_quanta',
 CDS_PART_NAME='Q_CAP_0402-4.7UF,6.3V,20%,X6S,CH5471MEB01',
 VOLTAGE='6.3V',
 PART_NUMBER='CH5471MEB01',
 VALUE='4.7UF',
 PRIM_FILE='./archive_libs/logical/q_cap/chips/chips.prt';

PART_NAME
 C485 'Q_CAP_0201-1UF,4V,20%,X6S,CH-10KMEE00':;

SECTION_NUMBER 1
 '@T6G_MB_LIB.T6G(SCH_1):PAGE465_I48@PURE_QUANTA.Q_CAP(CHIPS)':
 C_PATH='@t6g_mb_lib.t6g(sch_1):page465_i48@pure_quanta.q_cap(chips)',
 P_PATH='@t6g_mb_lib.t6g(sch_1):page356_i48@pure_quanta.q_cap(chips)',
 PATH='I48',
 DRAWING='@T6G_MB_LIB.T6G(SCH_1):PAGE465',
 TOLERANCE='20%',
 MATERIAL='X6S',
 PHYS_PAGE='356',
 XY='(-2525,2900)',
 ROT='0',
 VER='1',
 PACK_TYPE='0201',
 LOCATION='C485',
 CDS_LIB='pure_quanta',
 CDS_PART_NAME='Q_CAP_0201-1UF,4V,20%,X6S,CH-10KMEE00',
 VOLTAGE='4V',
 PART_NUMBER='CH-10KMEE00',
 VALUE='1UF',
 PRIM_FILE='./archive_libs/logical/q_cap/chips/chips.prt';

PART_NAME
 C486 'Q_CAP_C0402-22UF,4V,20%,X6S,CH622KMEB02':;

SECTION_NUMBER 1
 '@T6G_MB_LIB.T6G(SCH_1):PAGE465_I85@PURE_QUANTA.Q_CAP(CHIPS)':
 C_PATH='@t6g_mb_lib.t6g(sch_1):page465_i85@pure_quanta.q_cap(chips)',
 P_PATH='@t6g_mb_lib.t6g(sch_1):page356_i85@pure_quanta.q_cap(chips)',
 PATH='I85',
 DRAWING='@T6G_MB_LIB.T6G(SCH_1):PAGE465',
 TOLERANCE='20%',
 MATERIAL='X6S',
 PHYS_PAGE='356',
 XY='(-2325,4150)',
 ROT='0',
 VER='1',
 PACK_TYPE='C0402',
 LOCATION='C486',
 CDS_LIB='pure_quanta',
 CDS_PART_NAME='Q_CAP_C0402-22UF,4V,20%,X6S,CH622KMEB02',
 VOLTAGE='4V',
 PART_NUMBER='CH622KMEB02',
 VALUE='22UF',
 PRIM_FILE='./archive_libs/logical/q_cap/chips/chips.prt';

PART_NAME
 C487 'Q_CAP_C0402-22UF,4V,20%,X6S,CH622KMEB02':;

SECTION_NUMBER 1
 '@T6G_MB_LIB.T6G(SCH_1):PAGE465_I75@PURE_QUANTA.Q_CAP(CHIPS)':
 C_PATH='@t6g_mb_lib.t6g(sch_1):page465_i75@pure_quanta.q_cap(chips)',
 P_PATH='@t6g_mb_lib.t6g(sch_1):page356_i75@pure_quanta.q_cap(chips)',
 PATH='I75',
 DRAWING='@T6G_MB_LIB.T6G(SCH_1):PAGE465',
 TOLERANCE='20%',
 MATERIAL='X6S',
 PHYS_PAGE='356',
 XY='(-1875,4150)',
 ROT='0',
 VER='1',
 PACK_TYPE='C0402',
 LOCATION='C487',
 CDS_LIB='pure_quanta',
 CDS_PART_NAME='Q_CAP_C0402-22UF,4V,20%,X6S,CH622KMEB02',
 VOLTAGE='4V',
 PART_NUMBER='CH622KMEB02',
 VALUE='22UF',
 PRIM_FILE='./archive_libs/logical/q_cap/chips/chips.prt';

PART_NAME
 C488 'Q_CAP_0201-1UF,4V,20%,X6S,CH-10KMEE00':;

SECTION_NUMBER 1
 '@T6G_MB_LIB.T6G(SCH_1):PAGE465_I49@PURE_QUANTA.Q_CAP(CHIPS)':
 C_PATH='@t6g_mb_lib.t6g(sch_1):page465_i49@pure_quanta.q_cap(chips)',
 P_PATH='@t6g_mb_lib.t6g(sch_1):page356_i49@pure_quanta.q_cap(chips)',
 PATH='I49',
 DRAWING='@T6G_MB_LIB.T6G(SCH_1):PAGE465',
 TOLERANCE='20%',
 MATERIAL='X6S',
 PHYS_PAGE='356',
 XY='(-2300,2875)',
 ROT='0',
 VER='1',
 PACK_TYPE='0201',
 LOCATION='C488',
 CDS_LIB='pure_quanta',
 CDS_PART_NAME='Q_CAP_0201-1UF,4V,20%,X6S,CH-10KMEE00',
 VOLTAGE='4V',
 PART_NUMBER='CH-10KMEE00',
 VALUE='1UF',
 PRIM_FILE='./archive_libs/logical/q_cap/chips/chips.prt';

PART_NAME
 C489 'Q_CAP_C0402-10UF,6.3V,20%,X6S,CH6101MEB01':;

SECTION_NUMBER 1
 '@T6G_MB_LIB.T6G(SCH_1):PAGE465_I72@PURE_QUANTA.Q_CAP(CHIPS)':
 C_PATH='@t6g_mb_lib.t6g(sch_1):page465_i72@pure_quanta.q_cap(chips)',
 P_PATH='@t6g_mb_lib.t6g(sch_1):page356_i72@pure_quanta.q_cap(chips)',
 PATH='I72',
 DRAWING='@T6G_MB_LIB.T6G(SCH_1):PAGE465',
 TOLERANCE='20%',
 MATERIAL='X6S',
 PHYS_PAGE='356',
 XY='(-2825,5400)',
 ROT='0',
 VER='1',
 PACK_TYPE='C0402',
 LOCATION='C489',
 CDS_LIB='pure_quanta',
 CDS_PART_NAME='Q_CAP_C0402-10UF,6.3V,20%,X6S,CH6101MEB01',
 VOLTAGE='6.3V',
 PART_NUMBER='CH6101MEB01',
 VALUE='10UF',
 PRIM_FILE='./archive_libs/logical/q_cap/chips/chips.prt';

PART_NAME
 C490 'Q_CAP_C0402-10UF,6.3V,20%,X6S,CH6101MEB01':;

SECTION_NUMBER 1
 '@T6G_MB_LIB.T6G(SCH_1):PAGE465_I41@PURE_QUANTA.Q_CAP(CHIPS)':
 C_PATH='@t6g_mb_lib.t6g(sch_1):page465_i41@pure_quanta.q_cap(chips)',
 P_PATH='@t6g_mb_lib.t6g(sch_1):page356_i41@pure_quanta.q_cap(chips)',
 PATH='I41',
 DRAWING='@T6G_MB_LIB.T6G(SCH_1):PAGE465',
 TOLERANCE='20%',
 MATERIAL='X6S',
 PHYS_PAGE='356',
 XY='(-3250,3525)',
 ROT='0',
 VER='1',
 PACK_TYPE='C0402',
 LOCATION='C490',
 CDS_LIB='pure_quanta',
 CDS_PART_NAME='Q_CAP_C0402-10UF,6.3V,20%,X6S,CH6101MEB01',
 VOLTAGE='6.3V',
 PART_NUMBER='CH6101MEB01',
 VALUE='10UF',
 PRIM_FILE='./archive_libs/logical/q_cap/chips/chips.prt';

PART_NAME
 C491 'Q_CAP_0201-1UF,4V,20%,X6S,CH-10KMEE00':;

SECTION_NUMBER 1
 '@T6G_MB_LIB.T6G(SCH_1):PAGE465_I53@PURE_QUANTA.Q_CAP(CHIPS)':
 C_PATH='@t6g_mb_lib.t6g(sch_1):page465_i53@pure_quanta.q_cap(chips)',
 P_PATH='@t6g_mb_lib.t6g(sch_1):page356_i53@pure_quanta.q_cap(chips)',
 PATH='I53',
 DRAWING='@T6G_MB_LIB.T6G(SCH_1):PAGE465',
 TOLERANCE='20%',
 MATERIAL='X6S',
 PHYS_PAGE='356',
 XY='(-2100,3525)',
 ROT='0',
 VER='1',
 PACK_TYPE='0201',
 LOCATION='C491',
 CDS_LIB='pure_quanta',
 CDS_PART_NAME='Q_CAP_0201-1UF,4V,20%,X6S,CH-10KMEE00',
 VOLTAGE='4V',
 PART_NUMBER='CH-10KMEE00',
 VALUE='1UF',
 PRIM_FILE='./archive_libs/logical/q_cap/chips/chips.prt';

PART_NAME
 C492 'Q_CAP_0201-1UF,4V,20%,X6S,CH-10KMEE00':;

SECTION_NUMBER 1
 '@T6G_MB_LIB.T6G(SCH_1):PAGE465_I54@PURE_QUANTA.Q_CAP(CHIPS)':
 C_PATH='@t6g_mb_lib.t6g(sch_1):page465_i54@pure_quanta.q_cap(chips)',
 P_PATH='@t6g_mb_lib.t6g(sch_1):page356_i54@pure_quanta.q_cap(chips)',
 PATH='I54',
 DRAWING='@T6G_MB_LIB.T6G(SCH_1):PAGE465',
 TOLERANCE='20%',
 MATERIAL='X6S',
 PHYS_PAGE='356',
 XY='(-2075,2875)',
 ROT='0',
 VER='1',
 PACK_TYPE='0201',
 LOCATION='C492',
 CDS_LIB='pure_quanta',
 CDS_PART_NAME='Q_CAP_0201-1UF,4V,20%,X6S,CH-10KMEE00',
 VOLTAGE='4V',
 PART_NUMBER='CH-10KMEE00',
 VALUE='1UF',
 PRIM_FILE='./archive_libs/logical/q_cap/chips/chips.prt';

PART_NAME
 C493 'Q_CAP_C0201-0.1UF,10V,10%,X7S,CH4102K6E00':;

SECTION_NUMBER 1
 '@T6G_MB_LIB.T6G(SCH_1):PAGE465_I80@PURE_QUANTA.Q_CAP(CHIPS)':
 C_PATH='@t6g_mb_lib.t6g(sch_1):page465_i80@pure_quanta.q_cap(chips)',
 P_PATH='@t6g_mb_lib.t6g(sch_1):page356_i80@pure_quanta.q_cap(chips)',
 PATH='I80',
 DRAWING='@T6G_MB_LIB.T6G(SCH_1):PAGE465',
 TOLERANCE='10%',
 MATERIAL='X7S',
 PHYS_PAGE='356',
 XY='(-1400,5375)',
 ROT='0',
 VER='1',
 PACK_TYPE='C0201',
 LOCATION='C493',
 CDS_LIB='pure_quanta',
 CDS_PART_NAME='Q_CAP_C0201-0.1UF,10V,10%,X7S,CH4102K6E00',
 VOLTAGE='10V',
 PART_NUMBER='CH4102K6E00',
 VALUE='0.1UF',
 PRIM_FILE='./archive_libs/logical/q_cap/chips/chips.prt';

PART_NAME
 C494 'Q_CAP_0402-4.7UF,6.3V,20%,X6S,CH5471MEB01':;

SECTION_NUMBER 1
 '@T6G_MB_LIB.T6G(SCH_1):PAGE465_I52@PURE_QUANTA.Q_CAP(CHIPS)':
 C_PATH='@t6g_mb_lib.t6g(sch_1):page465_i52@pure_quanta.q_cap(chips)',
 P_PATH='@t6g_mb_lib.t6g(sch_1):page356_i52@pure_quanta.q_cap(chips)',
 PATH='I52',
 DRAWING='@T6G_MB_LIB.T6G(SCH_1):PAGE465',
 TOLERANCE='20%',
 MATERIAL='X6S',
 PHYS_PAGE='356',
 XY='(-2325,3525)',
 ROT='0',
 VER='1',
 PACK_TYPE='0402',
 LOCATION='C494',
 CDS_LIB='pure_quanta',
 CDS_PART_NAME='Q_CAP_0402-4.7UF,6.3V,20%,X6S,CH5471MEB01',
 VOLTAGE='6.3V',
 PART_NUMBER='CH5471MEB01',
 VALUE='4.7UF',
 PRIM_FILE='./archive_libs/logical/q_cap/chips/chips.prt';

PART_NAME
 C495 'Q_CAP_C0201-0.1UF,10V,10%,X7S,CH4102K6E00':;

SECTION_NUMBER 1
 '@T6G_MB_LIB.T6G(SCH_1):PAGE465_I37@PURE_QUANTA.Q_CAP(CHIPS)':
 C_PATH='@t6g_mb_lib.t6g(sch_1):page465_i37@pure_quanta.q_cap(chips)',
 P_PATH='@t6g_mb_lib.t6g(sch_1):page356_i37@pure_quanta.q_cap(chips)',
 PATH='I37',
 DRAWING='@T6G_MB_LIB.T6G(SCH_1):PAGE465',
 TOLERANCE='10%',
 MATERIAL='X7S',
 PHYS_PAGE='356',
 XY='(-3200,2200)',
 ROT='0',
 VER='1',
 PACK_TYPE='C0201',
 LOCATION='C495',
 CDS_LIB='pure_quanta',
 CDS_PART_NAME='Q_CAP_C0201-0.1UF,10V,10%,X7S,CH4102K6E00',
 VOLTAGE='10V',
 PART_NUMBER='CH4102K6E00',
 VALUE='0.1UF',
 PRIM_FILE='./archive_libs/logical/q_cap/chips/chips.prt';

PART_NAME
 C496 'Q_CAP_C0201-0.1UF,10V,10%,X7S,CH4102K6E00':;

SECTION_NUMBER 1
 '@T6G_MB_LIB.T6G(SCH_1):PAGE465_I92@PURE_QUANTA.Q_CAP(CHIPS)':
 C_PATH='@t6g_mb_lib.t6g(sch_1):page465_i92@pure_quanta.q_cap(chips)',
 P_PATH='@t6g_mb_lib.t6g(sch_1):page356_i92@pure_quanta.q_cap(chips)',
 PATH='I92',
 DRAWING='@T6G_MB_LIB.T6G(SCH_1):PAGE465',
 TOLERANCE='10%',
 MATERIAL='X7S',
 PHYS_PAGE='356',
 XY='(-1850,2875)',
 ROT='0',
 VER='1',
 PACK_TYPE='C0201',
 LOCATION='C496',
 CDS_LIB='pure_quanta',
 CDS_PART_NAME='Q_CAP_C0201-0.1UF,10V,10%,X7S,CH4102K6E00',
 VOLTAGE='10V',
 PART_NUMBER='CH4102K6E00',
 VALUE='0.1UF',
 PRIM_FILE='./archive_libs/logical/q_cap/chips/chips.prt';

PART_NAME
 C497 'Q_CAP_0201-1UF,4V,20%,X6S,CH-10KMEE00':;

SECTION_NUMBER 1
 '@T6G_MB_LIB.T6G(SCH_1):PAGE465_I60@PURE_QUANTA.Q_CAP(CHIPS)':
 C_PATH='@t6g_mb_lib.t6g(sch_1):page465_i60@pure_quanta.q_cap(chips)',
 P_PATH='@t6g_mb_lib.t6g(sch_1):page356_i60@pure_quanta.q_cap(chips)',
 PATH='I60',
 DRAWING='@T6G_MB_LIB.T6G(SCH_1):PAGE465',
 TOLERANCE='20%',
 MATERIAL='X6S',
 PHYS_PAGE='356',
 XY='(-1650,3525)',
 ROT='0',
 VER='1',
 PACK_TYPE='0201',
 LOCATION='C497',
 CDS_LIB='pure_quanta',
 CDS_PART_NAME='Q_CAP_0201-1UF,4V,20%,X6S,CH-10KMEE00',
 VOLTAGE='4V',
 PART_NUMBER='CH-10KMEE00',
 VALUE='1UF',
 PRIM_FILE='./archive_libs/logical/q_cap/chips/chips.prt';

PART_NAME
 C498 'Q_CAP_C0201-0.1UF,10V,10%,X7S,CH4102K6E00':;

SECTION_NUMBER 1
 '@T6G_MB_LIB.T6G(SCH_1):PAGE465_I93@PURE_QUANTA.Q_CAP(CHIPS)':
 C_PATH='@t6g_mb_lib.t6g(sch_1):page465_i93@pure_quanta.q_cap(chips)',
 P_PATH='@t6g_mb_lib.t6g(sch_1):page356_i93@pure_quanta.q_cap(chips)',
 PATH='I93',
 DRAWING='@T6G_MB_LIB.T6G(SCH_1):PAGE465',
 TOLERANCE='10%',
 MATERIAL='X7S',
 PHYS_PAGE='356',
 XY='(-1600,2875)',
 ROT='0',
 VER='1',
 PACK_TYPE='C0201',
 LOCATION='C498',
 CDS_LIB='pure_quanta',
 CDS_PART_NAME='Q_CAP_C0201-0.1UF,10V,10%,X7S,CH4102K6E00',
 VOLTAGE='10V',
 PART_NUMBER='CH4102K6E00',
 VALUE='0.1UF',
 PRIM_FILE='./archive_libs/logical/q_cap/chips/chips.prt';

PART_NAME
 C499 'Q_CAP_C0402-10UF,6.3V,20%,X6S,CH6101MEB01':;

SECTION_NUMBER 1
 '@T6G_MB_LIB.T6G(SCH_1):PAGE465_I76@PURE_QUANTA.Q_CAP(CHIPS)':
 C_PATH='@t6g_mb_lib.t6g(sch_1):page465_i76@pure_quanta.q_cap(chips)',
 P_PATH='@t6g_mb_lib.t6g(sch_1):page356_i76@pure_quanta.q_cap(chips)',
 PATH='I76',
 DRAWING='@T6G_MB_LIB.T6G(SCH_1):PAGE465',
 TOLERANCE='20%',
 MATERIAL='X6S',
 PHYS_PAGE='356',
 XY='(-1575,4150)',
 ROT='0',
 VER='1',
 PACK_TYPE='C0402',
 LOCATION='C499',
 CDS_LIB='pure_quanta',
 CDS_PART_NAME='Q_CAP_C0402-10UF,6.3V,20%,X6S,CH6101MEB01',
 VOLTAGE='6.3V',
 PART_NUMBER='CH6101MEB01',
 VALUE='10UF',
 PRIM_FILE='./archive_libs/logical/q_cap/chips/chips.prt';

PART_NAME
 C500 'Q_CAP_C0201-0.1UF,10V,10%,X7S,CH4102K6E00':;

SECTION_NUMBER 1
 '@T6G_MB_LIB.T6G(SCH_1):PAGE465_I42@PURE_QUANTA.Q_CAP(CHIPS)':
 C_PATH='@t6g_mb_lib.t6g(sch_1):page465_i42@pure_quanta.q_cap(chips)',
 P_PATH='@t6g_mb_lib.t6g(sch_1):page356_i42@pure_quanta.q_cap(chips)',
 PATH='I42',
 DRAWING='@T6G_MB_LIB.T6G(SCH_1):PAGE465',
 TOLERANCE='10%',
 MATERIAL='X7S',
 PHYS_PAGE='356',
 XY='(-2900,2200)',
 ROT='0',
 VER='1',
 PACK_TYPE='C0201',
 LOCATION='C500',
 CDS_LIB='pure_quanta',
 CDS_PART_NAME='Q_CAP_C0201-0.1UF,10V,10%,X7S,CH4102K6E00',
 VOLTAGE='10V',
 PART_NUMBER='CH4102K6E00',
 VALUE='0.1UF',
 PRIM_FILE='./archive_libs/logical/q_cap/chips/chips.prt';

PART_NAME
 C501 'Q_CAP_C0402-22UF,4V,20%,X6S,CH622KMEB02':;

SECTION_NUMBER 1
 '@T6G_MB_LIB.T6G(SCH_1):PAGE465_I70@PURE_QUANTA.Q_CAP(CHIPS)':
 C_PATH='@t6g_mb_lib.t6g(sch_1):page465_i70@pure_quanta.q_cap(chips)',
 P_PATH='@t6g_mb_lib.t6g(sch_1):page356_i70@pure_quanta.q_cap(chips)',
 PATH='I70',
 DRAWING='@T6G_MB_LIB.T6G(SCH_1):PAGE465',
 TOLERANCE='20%',
 MATERIAL='X6S',
 PHYS_PAGE='356',
 XY='(-2550,4150)',
 ROT='0',
 VER='1',
 PACK_TYPE='C0402',
 LOCATION='C501',
 CDS_LIB='pure_quanta',
 CDS_PART_NAME='Q_CAP_C0402-22UF,4V,20%,X6S,CH622KMEB02',
 VOLTAGE='4V',
 PART_NUMBER='CH622KMEB02',
 VALUE='22UF',
 PRIM_FILE='./archive_libs/logical/q_cap/chips/chips.prt';

PART_NAME
 C502 'Q_CAP_C0805-100UF,4V,20%,X6S,CH710KMEA01':;

SECTION_NUMBER 1
 '@T6G_MB_LIB.T6G(SCH_1):PAGE388_I16@PURE_QUANTA.Q_CAP(CHIPS)':
 C_PATH='@t6g_mb_lib.t6g(sch_1):page388_i16@pure_quanta.q_cap(chips)',
 P_PATH='@t6g_mb_lib.t6g(sch_1):page279_i16@pure_quanta.q_cap(chips)',
 PATH='I16',
 DRAWING='@T6G_MB_LIB.T6G(SCH_1):PAGE388',
 TOLERANCE='20%',
 MATERIAL='X6S',
 PHYS_PAGE='279',
 XY='(-7050,5025)',
 ROT='0',
 VER='1',
 PACK_TYPE='C0805',
 LOCATION='C502',
 CDS_LIB='pure_quanta',
 CDS_PART_NAME='Q_CAP_C0805-100UF,4V,20%,X6S,CH710KMEA01',
 VOLTAGE='4V',
 PART_NUMBER='CH710KMEA01',
 VALUE='100UF',
 PRIM_FILE='./archive_libs/logical/q_cap/chips/chips.prt';

PART_NAME
 C503 'Q_CAP_C0805-100UF,4V,20%,X6S,CH710KMEA01':;

SECTION_NUMBER 1
 '@T6G_MB_LIB.T6G(SCH_1):PAGE388_I13@PURE_QUANTA.Q_CAP(CHIPS)':
 C_PATH='@t6g_mb_lib.t6g(sch_1):page388_i13@pure_quanta.q_cap(chips)',
 P_PATH='@t6g_mb_lib.t6g(sch_1):page279_i13@pure_quanta.q_cap(chips)',
 PATH='I13',
 DRAWING='@T6G_MB_LIB.T6G(SCH_1):PAGE388',
 TOLERANCE='20%',
 MATERIAL='X6S',
 PHYS_PAGE='279',
 XY='(-7200,4200)',
 ROT='0',
 VER='1',
 PACK_TYPE='C0805',
 LOCATION='C503',
 CDS_LIB='pure_quanta',
 CDS_PART_NAME='Q_CAP_C0805-100UF,4V,20%,X6S,CH710KMEA01',
 VOLTAGE='4V',
 PART_NUMBER='CH710KMEA01',
 VALUE='100UF',
 PRIM_FILE='./archive_libs/logical/q_cap/chips/chips.prt';

PART_NAME
 C504 'Q_CAP_C0402-22UF,4V,20%,X6S,CH622KMEB02':;

SECTION_NUMBER 1
 '@T6G_MB_LIB.T6G(SCH_1):PAGE388_I24@PURE_QUANTA.Q_CAP(CHIPS)':
 C_PATH='@t6g_mb_lib.t6g(sch_1):page388_i24@pure_quanta.q_cap(chips)',
 P_PATH='@t6g_mb_lib.t6g(sch_1):page279_i24@pure_quanta.q_cap(chips)',
 PATH='I24',
 DRAWING='@T6G_MB_LIB.T6G(SCH_1):PAGE388',
 TOLERANCE='20%',
 MATERIAL='X6S',
 PHYS_PAGE='279',
 XY='(-6800,5025)',
 ROT='0',
 VER='1',
 PACK_TYPE='C0402',
 LOCATION='C504',
 CDS_LIB='pure_quanta',
 CDS_PART_NAME='Q_CAP_C0402-22UF,4V,20%,X6S,CH622KMEB02',
 VOLTAGE='4V',
 PART_NUMBER='CH622KMEB02',
 VALUE='22UF',
 PRIM_FILE='./archive_libs/logical/q_cap/chips/chips.prt';

PART_NAME
 C505 'Q_CAP_C0402-22UF,4V,20%,X6S,CH622KMEB02':;

SECTION_NUMBER 1
 '@T6G_MB_LIB.T6G(SCH_1):PAGE388_I14@PURE_QUANTA.Q_CAP(CHIPS)':
 C_PATH='@t6g_mb_lib.t6g(sch_1):page388_i14@pure_quanta.q_cap(chips)',
 P_PATH='@t6g_mb_lib.t6g(sch_1):page279_i14@pure_quanta.q_cap(chips)',
 PATH='I14',
 DRAWING='@T6G_MB_LIB.T6G(SCH_1):PAGE388',
 TOLERANCE='20%',
 MATERIAL='X6S',
 PHYS_PAGE='279',
 XY='(-6975,4200)',
 ROT='0',
 VER='1',
 PACK_TYPE='C0402',
 LOCATION='C505',
 CDS_LIB='pure_quanta',
 CDS_PART_NAME='Q_CAP_C0402-22UF,4V,20%,X6S,CH622KMEB02',
 VOLTAGE='4V',
 PART_NUMBER='CH622KMEB02',
 VALUE='22UF',
 PRIM_FILE='./archive_libs/logical/q_cap/chips/chips.prt';

PART_NAME
 C506 'Q_CAP_C0402-10UF,6.3V,20%,X6S,CH6101MEB01':;

SECTION_NUMBER 1
 '@T6G_MB_LIB.T6G(SCH_1):PAGE388_I25@PURE_QUANTA.Q_CAP(CHIPS)':
 C_PATH='@t6g_mb_lib.t6g(sch_1):page388_i25@pure_quanta.q_cap(chips)',
 P_PATH='@t6g_mb_lib.t6g(sch_1):page279_i25@pure_quanta.q_cap(chips)',
 PATH='I25',
 DRAWING='@T6G_MB_LIB.T6G(SCH_1):PAGE388',
 TOLERANCE='20%',
 MATERIAL='X6S',
 PHYS_PAGE='279',
 XY='(-6550,5000)',
 ROT='0',
 VER='1',
 PACK_TYPE='C0402',
 LOCATION='C506',
 CDS_LIB='pure_quanta',
 CDS_PART_NAME='Q_CAP_C0402-10UF,6.3V,20%,X6S,CH6101MEB01',
 VOLTAGE='6.3V',
 PART_NUMBER='CH6101MEB01',
 VALUE='10UF',
 PRIM_FILE='./archive_libs/logical/q_cap/chips/chips.prt';

PART_NAME
 C507 'Q_CAP_C0402-10UF,6.3V,20%,X6S,CH6101MEB01':;

SECTION_NUMBER 1
 '@T6G_MB_LIB.T6G(SCH_1):PAGE388_I17@PURE_QUANTA.Q_CAP(CHIPS)':
 C_PATH='@t6g_mb_lib.t6g(sch_1):page388_i17@pure_quanta.q_cap(chips)',
 P_PATH='@t6g_mb_lib.t6g(sch_1):page279_i17@pure_quanta.q_cap(chips)',
 PATH='I17',
 DRAWING='@T6G_MB_LIB.T6G(SCH_1):PAGE388',
 TOLERANCE='20%',
 MATERIAL='X6S',
 PHYS_PAGE='279',
 XY='(-6775,4200)',
 ROT='0',
 VER='1',
 PACK_TYPE='C0402',
 LOCATION='C507',
 CDS_LIB='pure_quanta',
 CDS_PART_NAME='Q_CAP_C0402-10UF,6.3V,20%,X6S,CH6101MEB01',
 VOLTAGE='6.3V',
 PART_NUMBER='CH6101MEB01',
 VALUE='10UF',
 PRIM_FILE='./archive_libs/logical/q_cap/chips/chips.prt';

PART_NAME
 C508 'Q_CAP_0402-0.1UF,25V,10%,X7R,CH4104K1B00':;

SECTION_NUMBER 1
 '@T6G_MB_LIB.T6G(SCH_1):PAGE297_I99@PURE_QUANTA.Q_CAP(CHIPS)':
 C_PATH='@t6g_mb_lib.t6g(sch_1):page297_i99@pure_quanta.q_cap(chips)',
 P_PATH='@t6g_mb_lib.t6g(sch_1):page145_i99@pure_quanta.q_cap(chips)',
 PATH='I99',
 DRAWING='@T6G_MB_LIB.T6G(SCH_1):PAGE297',
 TOLERANCE='10%',
 MATERIAL='X7R',
 PHYS_PAGE='145',
 XY='(-2275,700)',
 ROT='2',
 VER='1',
 PACK_TYPE='0402',
 LOCATION='C508',
 CDS_LIB='pure_quanta',
 CDS_PART_NAME='Q_CAP_0402-0.1UF,25V,10%,X7R,CH4104K1B00',
 VOLTAGE='25V',
 PART_NUMBER='CH4104K1B00',
 VALUE='0.1UF',
 PRIM_FILE='./archive_libs/logical/q_cap/chips/chips.prt';

PART_NAME
 C509 'Q_CAP_C0805-10UF,25V,10%,X6S,CH6104KEA00':
 ROOM='';

SECTION_NUMBER 1
 '@T6G_MB_LIB.T6G(SCH_1):PAGE101_I239@PURE_QUANTA.Q_CAP(CHIPS)':
 C_PATH='@t6g_mb_lib.t6g(sch_1):page101_i239@pure_quanta.q_cap(chips)',
 P_PATH='@t6g_mb_lib.t6g(sch_1):page102_i239@pure_quanta.q_cap(chips)',
 PATH='I239',
 DRAWING='@T6G_MB_LIB.T6G(SCH_1):PAGE101',
 BOM_COST='MEM',
 TOLERANCE='10%',
 MATERIAL='X6S',
 PHYS_PAGE='102',
 XY='(-2300,6175)',
 ROT='2',
 VER='1',
 PACK_TYPE='C0805',
 LOCATION='C509',
 CDS_LIB='pure_quanta',
 CDS_PART_NAME='Q_CAP_C0805-10UF,25V,10%,X6S,CH6104KEA00',
 VOLTAGE='25V',
 ROOM='',
 PART_NUMBER='CH6104KEA00',
 VALUE='10UF',
 PRIM_FILE='./archive_libs/logical/q_cap/chips/chips.prt';

PART_NAME
 C510 'Q_CAP_0402-4.7UF,6.3V,20%,X6S,CH5471MEB01':;

SECTION_NUMBER 1
 '@T6G_MB_LIB.T6G(SCH_1):PAGE388_I18@PURE_QUANTA.Q_CAP(CHIPS)':
 C_PATH='@t6g_mb_lib.t6g(sch_1):page388_i18@pure_quanta.q_cap(chips)',
 P_PATH='@t6g_mb_lib.t6g(sch_1):page279_i18@pure_quanta.q_cap(chips)',
 PATH='I18',
 DRAWING='@T6G_MB_LIB.T6G(SCH_1):PAGE388',
 TOLERANCE='20%',
 MATERIAL='X6S',
 PHYS_PAGE='279',
 XY='(-6575,4200)',
 ROT='0',
 VER='1',
 PACK_TYPE='0402',
 LOCATION='C510',
 CDS_LIB='pure_quanta',
 CDS_PART_NAME='Q_CAP_0402-4.7UF,6.3V,20%,X6S,CH5471MEB01',
 VOLTAGE='6.3V',
 PART_NUMBER='CH5471MEB01',
 VALUE='4.7UF',
 PRIM_FILE='./archive_libs/logical/q_cap/chips/chips.prt';

PART_NAME
 C511 'Q_CAP_0402-4.7UF,6.3V,20%,X6S,CH5471MEB01':;

SECTION_NUMBER 1
 '@T6G_MB_LIB.T6G(SCH_1):PAGE388_I26@PURE_QUANTA.Q_CAP(CHIPS)':
 C_PATH='@t6g_mb_lib.t6g(sch_1):page388_i26@pure_quanta.q_cap(chips)',
 P_PATH='@t6g_mb_lib.t6g(sch_1):page279_i26@pure_quanta.q_cap(chips)',
 PATH='I26',
 DRAWING='@T6G_MB_LIB.T6G(SCH_1):PAGE388',
 TOLERANCE='20%',
 MATERIAL='X6S',
 PHYS_PAGE='279',
 XY='(-6300,5000)',
 ROT='0',
 VER='1',
 PACK_TYPE='0402',
 LOCATION='C511',
 CDS_LIB='pure_quanta',
 CDS_PART_NAME='Q_CAP_0402-4.7UF,6.3V,20%,X6S,CH5471MEB01',
 VOLTAGE='6.3V',
 PART_NUMBER='CH5471MEB01',
 VALUE='4.7UF',
 PRIM_FILE='./archive_libs/logical/q_cap/chips/chips.prt';

PART_NAME
 C512 'Q_CAP_0201-1UF,4V,20%,X6S,CH-10KMEE00':;

SECTION_NUMBER 1
 '@T6G_MB_LIB.T6G(SCH_1):PAGE388_I19@PURE_QUANTA.Q_CAP(CHIPS)':
 C_PATH='@t6g_mb_lib.t6g(sch_1):page388_i19@pure_quanta.q_cap(chips)',
 P_PATH='@t6g_mb_lib.t6g(sch_1):page279_i19@pure_quanta.q_cap(chips)',
 PATH='I19',
 DRAWING='@T6G_MB_LIB.T6G(SCH_1):PAGE388',
 TOLERANCE='20%',
 MATERIAL='X6S',
 PHYS_PAGE='279',
 XY='(-6350,4200)',
 ROT='0',
 VER='1',
 PACK_TYPE='0201',
 LOCATION='C512',
 CDS_LIB='pure_quanta',
 CDS_PART_NAME='Q_CAP_0201-1UF,4V,20%,X6S,CH-10KMEE00',
 VOLTAGE='4V',
 PART_NUMBER='CH-10KMEE00',
 VALUE='1UF',
 PRIM_FILE='./archive_libs/logical/q_cap/chips/chips.prt';

PART_NAME
 C513 'Q_CAP_0201-1UF,4V,20%,X6S,CH-10KMEE00':;

SECTION_NUMBER 1
 '@T6G_MB_LIB.T6G(SCH_1):PAGE388_I8@PURE_QUANTA.Q_CAP(CHIPS)':
 C_PATH='@t6g_mb_lib.t6g(sch_1):page388_i8@pure_quanta.q_cap(chips)',
 P_PATH='@t6g_mb_lib.t6g(sch_1):page279_i8@pure_quanta.q_cap(chips)',
 PATH='I8',
 DRAWING='@T6G_MB_LIB.T6G(SCH_1):PAGE388',
 TOLERANCE='20%',
 MATERIAL='X6S',
 PHYS_PAGE='279',
 XY='(-6775,3125)',
 ROT='0',
 VER='1',
 PACK_TYPE='0201',
 LOCATION='C513',
 CDS_LIB='pure_quanta',
 CDS_PART_NAME='Q_CAP_0201-1UF,4V,20%,X6S,CH-10KMEE00',
 VOLTAGE='4V',
 PART_NUMBER='CH-10KMEE00',
 VALUE='1UF',
 PRIM_FILE='./archive_libs/logical/q_cap/chips/chips.prt';

PART_NAME
 C514 'Q_CAP_0201-1UF,4V,20%,X6S,CH-10KMEE00':;

SECTION_NUMBER 1
 '@T6G_MB_LIB.T6G(SCH_1):PAGE388_I22@PURE_QUANTA.Q_CAP(CHIPS)':
 C_PATH='@t6g_mb_lib.t6g(sch_1):page388_i22@pure_quanta.q_cap(chips)',
 P_PATH='@t6g_mb_lib.t6g(sch_1):page279_i22@pure_quanta.q_cap(chips)',
 PATH='I22',
 DRAWING='@T6G_MB_LIB.T6G(SCH_1):PAGE388',
 TOLERANCE='20%',
 MATERIAL='X6S',
 PHYS_PAGE='279',
 XY='(-6150,4200)',
 ROT='0',
 VER='1',
 PACK_TYPE='0201',
 LOCATION='C514',
 CDS_LIB='pure_quanta',
 CDS_PART_NAME='Q_CAP_0201-1UF,4V,20%,X6S,CH-10KMEE00',
 VOLTAGE='4V',
 PART_NUMBER='CH-10KMEE00',
 VALUE='1UF',
 PRIM_FILE='./archive_libs/logical/q_cap/chips/chips.prt';

PART_NAME
 C515 'Q_CAP_C0201-0.1UF,10V,10%,X7S,CH4102K6E00':;

SECTION_NUMBER 1
 '@T6G_MB_LIB.T6G(SCH_1):PAGE388_I23@PURE_QUANTA.Q_CAP(CHIPS)':
 C_PATH='@t6g_mb_lib.t6g(sch_1):page388_i23@pure_quanta.q_cap(chips)',
 P_PATH='@t6g_mb_lib.t6g(sch_1):page279_i23@pure_quanta.q_cap(chips)',
 PATH='I23',
 DRAWING='@T6G_MB_LIB.T6G(SCH_1):PAGE388',
 TOLERANCE='10%',
 MATERIAL='X7S',
 PHYS_PAGE='279',
 XY='(-5925,4200)',
 ROT='0',
 VER='1',
 PACK_TYPE='C0201',
 LOCATION='C515',
 CDS_LIB='pure_quanta',
 CDS_PART_NAME='Q_CAP_C0201-0.1UF,10V,10%,X7S,CH4102K6E00',
 VOLTAGE='10V',
 PART_NUMBER='CH4102K6E00',
 VALUE='0.1UF',
 PRIM_FILE='./archive_libs/logical/q_cap/chips/chips.prt';

PART_NAME
 C516 'Q_CAP_C0201-0.1UF,10V,10%,X7S,CH4102K6E00':;

SECTION_NUMBER 1
 '@T6G_MB_LIB.T6G(SCH_1):PAGE388_I9@PURE_QUANTA.Q_CAP(CHIPS)':
 C_PATH='@t6g_mb_lib.t6g(sch_1):page388_i9@pure_quanta.q_cap(chips)',
 P_PATH='@t6g_mb_lib.t6g(sch_1):page279_i9@pure_quanta.q_cap(chips)',
 PATH='I9',
 DRAWING='@T6G_MB_LIB.T6G(SCH_1):PAGE388',
 TOLERANCE='10%',
 MATERIAL='X7S',
 PHYS_PAGE='279',
 XY='(-6500,3100)',
 ROT='0',
 VER='1',
 PACK_TYPE='C0201',
 LOCATION='C516',
 CDS_LIB='pure_quanta',
 CDS_PART_NAME='Q_CAP_C0201-0.1UF,10V,10%,X7S,CH4102K6E00',
 VOLTAGE='10V',
 PART_NUMBER='CH4102K6E00',
 VALUE='0.1UF',
 PRIM_FILE='./archive_libs/logical/q_cap/chips/chips.prt';

PART_NAME
 C517 'Q_CAP_C0201-0.1UF,10V,10%,X7S,CH4102K6E00':;

SECTION_NUMBER 1
 '@T6G_MB_LIB.T6G(SCH_1):PAGE388_I27@PURE_QUANTA.Q_CAP(CHIPS)':
 C_PATH='@t6g_mb_lib.t6g(sch_1):page388_i27@pure_quanta.q_cap(chips)',
 P_PATH='@t6g_mb_lib.t6g(sch_1):page279_i27@pure_quanta.q_cap(chips)',
 PATH='I27',
 DRAWING='@T6G_MB_LIB.T6G(SCH_1):PAGE388',
 TOLERANCE='10%',
 MATERIAL='X7S',
 PHYS_PAGE='279',
 XY='(-5675,4200)',
 ROT='0',
 VER='1',
 PACK_TYPE='C0201',
 LOCATION='C517',
 CDS_LIB='pure_quanta',
 CDS_PART_NAME='Q_CAP_C0201-0.1UF,10V,10%,X7S,CH4102K6E00',
 VOLTAGE='10V',
 PART_NUMBER='CH4102K6E00',
 VALUE='0.1UF',
 PRIM_FILE='./archive_libs/logical/q_cap/chips/chips.prt';

PART_NAME
 C518 'Q_CAP_C0805-10UF,25V,10%,X6S,CH6104KEA00':
 ROOM='';

SECTION_NUMBER 1
 '@T6G_MB_LIB.T6G(SCH_1):PAGE102_I238@PURE_QUANTA.Q_CAP(CHIPS)':
 C_PATH='@t6g_mb_lib.t6g(sch_1):page102_i238@pure_quanta.q_cap(chips)',
 P_PATH='@t6g_mb_lib.t6g(sch_1):page103_i238@pure_quanta.q_cap(chips)',
 PATH='I238',
 DRAWING='@T6G_MB_LIB.T6G(SCH_1):PAGE102',
 BOM_COST='MEM',
 TOLERANCE='10%',
 MATERIAL='X6S',
 PHYS_PAGE='103',
 XY='(-2900,6000)',
 ROT='2',
 VER='1',
 PACK_TYPE='C0805',
 LOCATION='C518',
 CDS_LIB='pure_quanta',
 CDS_PART_NAME='Q_CAP_C0805-10UF,25V,10%,X6S,CH6104KEA00',
 VOLTAGE='25V',
 ROOM='',
 PART_NUMBER='CH6104KEA00',
 VALUE='10UF',
 PRIM_FILE='./archive_libs/logical/q_cap/chips/chips.prt';

PART_NAME
 C519 'Q_CAP_C0201-0.1UF,10V,10%,X7S,CH4102K6E00':;

SECTION_NUMBER 1
 '@T6G_MB_LIB.T6G(SCH_1):PAGE388_I28@PURE_QUANTA.Q_CAP(CHIPS)':
 C_PATH='@t6g_mb_lib.t6g(sch_1):page388_i28@pure_quanta.q_cap(chips)',
 P_PATH='@t6g_mb_lib.t6g(sch_1):page279_i28@pure_quanta.q_cap(chips)',
 PATH='I28',
 DRAWING='@T6G_MB_LIB.T6G(SCH_1):PAGE388',
 TOLERANCE='10%',
 MATERIAL='X7S',
 PHYS_PAGE='279',
 XY='(-5425,4200)',
 ROT='0',
 VER='1',
 PACK_TYPE='C0201',
 LOCATION='C519',
 CDS_LIB='pure_quanta',
 CDS_PART_NAME='Q_CAP_C0201-0.1UF,10V,10%,X7S,CH4102K6E00',
 VOLTAGE='10V',
 PART_NUMBER='CH4102K6E00',
 VALUE='0.1UF',
 PRIM_FILE='./archive_libs/logical/q_cap/chips/chips.prt';

PART_NAME
 C520 'Q_CAP_C0201-0.1UF,10V,10%,X7S,CH4102K6E00':;

SECTION_NUMBER 1
 '@T6G_MB_LIB.T6G(SCH_1):PAGE388_I29@PURE_QUANTA.Q_CAP(CHIPS)':
 C_PATH='@t6g_mb_lib.t6g(sch_1):page388_i29@pure_quanta.q_cap(chips)',
 P_PATH='@t6g_mb_lib.t6g(sch_1):page279_i29@pure_quanta.q_cap(chips)',
 PATH='I29',
 DRAWING='@T6G_MB_LIB.T6G(SCH_1):PAGE388',
 TOLERANCE='10%',
 MATERIAL='X7S',
 PHYS_PAGE='279',
 XY='(-5150,4200)',
 ROT='0',
 VER='1',
 PACK_TYPE='C0201',
 LOCATION='C520',
 CDS_LIB='pure_quanta',
 CDS_PART_NAME='Q_CAP_C0201-0.1UF,10V,10%,X7S,CH4102K6E00',
 VOLTAGE='10V',
 PART_NUMBER='CH4102K6E00',
 VALUE='0.1UF',
 PRIM_FILE='./archive_libs/logical/q_cap/chips/chips.prt';

PART_NAME
 C521 'Q_CAP_0201-1UF,4V,20%,X6S,CH-10KMEE00':;

SECTION_NUMBER 1
 '@T6G_MB_LIB.T6G(SCH_1):PAGE388_I65@PURE_QUANTA.Q_CAP(CHIPS)':
 C_PATH='@t6g_mb_lib.t6g(sch_1):page388_i65@pure_quanta.q_cap(chips)',
 P_PATH='@t6g_mb_lib.t6g(sch_1):page279_i65@pure_quanta.q_cap(chips)',
 PATH='I65',
 DRAWING='@T6G_MB_LIB.T6G(SCH_1):PAGE388',
 TOLERANCE='20%',
 MATERIAL='X6S',
 PHYS_PAGE='279',
 XY='(-1650,3575)',
 ROT='0',
 VER='1',
 PACK_TYPE='0201',
 LOCATION='C521',
 CDS_LIB='pure_quanta',
 CDS_PART_NAME='Q_CAP_0201-1UF,4V,20%,X6S,CH-10KMEE00',
 VOLTAGE='4V',
 PART_NUMBER='CH-10KMEE00',
 VALUE='1UF',
 PRIM_FILE='./archive_libs/logical/q_cap/chips/chips.prt';

PART_NAME
 C522 'Q_CAP_C0201-0.1UF,10V,10%,X7S,CH4102K6E00':;

SECTION_NUMBER 1
 '@T6G_MB_LIB.T6G(SCH_1):PAGE388_I81@PURE_QUANTA.Q_CAP(CHIPS)':
 C_PATH='@t6g_mb_lib.t6g(sch_1):page388_i81@pure_quanta.q_cap(chips)',
 P_PATH='@t6g_mb_lib.t6g(sch_1):page279_i81@pure_quanta.q_cap(chips)',
 PATH='I81',
 DRAWING='@T6G_MB_LIB.T6G(SCH_1):PAGE388',
 TOLERANCE='10%',
 MATERIAL='X7S',
 PHYS_PAGE='279',
 XY='(-2675,5450)',
 ROT='0',
 VER='1',
 PACK_TYPE='C0201',
 LOCATION='C522',
 CDS_LIB='pure_quanta',
 CDS_PART_NAME='Q_CAP_C0201-0.1UF,10V,10%,X7S,CH4102K6E00',
 VOLTAGE='10V',
 PART_NUMBER='CH4102K6E00',
 VALUE='0.1UF',
 PRIM_FILE='./archive_libs/logical/q_cap/chips/chips.prt';

PART_NAME
 C523 'Q_CAP_C0201-0.1UF,10V,10%,X7S,CH4102K6E00':;

SECTION_NUMBER 1
 '@T6G_MB_LIB.T6G(SCH_1):PAGE388_I50@PURE_QUANTA.Q_CAP(CHIPS)':
 C_PATH='@t6g_mb_lib.t6g(sch_1):page388_i50@pure_quanta.q_cap(chips)',
 P_PATH='@t6g_mb_lib.t6g(sch_1):page279_i50@pure_quanta.q_cap(chips)',
 PATH='I50',
 DRAWING='@T6G_MB_LIB.T6G(SCH_1):PAGE388',
 TOLERANCE='10%',
 MATERIAL='X7S',
 PHYS_PAGE='279',
 XY='(-2175,2250)',
 ROT='0',
 VER='1',
 PACK_TYPE='C0201',
 LOCATION='C523',
 CDS_LIB='pure_quanta',
 CDS_PART_NAME='Q_CAP_C0201-0.1UF,10V,10%,X7S,CH4102K6E00',
 VOLTAGE='10V',
 PART_NUMBER='CH4102K6E00',
 VALUE='0.1UF',
 PRIM_FILE='./archive_libs/logical/q_cap/chips/chips.prt';

PART_NAME
 C524 'Q_CAP_C0201-0.1UF,10V,10%,X7S,CH4102K6E00':;

SECTION_NUMBER 1
 '@T6G_MB_LIB.T6G(SCH_1):PAGE388_I84@PURE_QUANTA.Q_CAP(CHIPS)':
 C_PATH='@t6g_mb_lib.t6g(sch_1):page388_i84@pure_quanta.q_cap(chips)',
 P_PATH='@t6g_mb_lib.t6g(sch_1):page279_i84@pure_quanta.q_cap(chips)',
 PATH='I84',
 DRAWING='@T6G_MB_LIB.T6G(SCH_1):PAGE388',
 TOLERANCE='10%',
 MATERIAL='X7S',
 PHYS_PAGE='279',
 XY='(-2325,5450)',
 ROT='0',
 VER='1',
 PACK_TYPE='C0201',
 LOCATION='C524',
 CDS_LIB='pure_quanta',
 CDS_PART_NAME='Q_CAP_C0201-0.1UF,10V,10%,X7S,CH4102K6E00',
 VOLTAGE='10V',
 PART_NUMBER='CH4102K6E00',
 VALUE='0.1UF',
 PRIM_FILE='./archive_libs/logical/q_cap/chips/chips.prt';

PART_NAME
 C525 'Q_CAP_0201-1UF,4V,20%,X6S,CH-10KMEE00':;

SECTION_NUMBER 1
 '@T6G_MB_LIB.T6G(SCH_1):PAGE388_I58@PURE_QUANTA.Q_CAP(CHIPS)':
 C_PATH='@t6g_mb_lib.t6g(sch_1):page388_i58@pure_quanta.q_cap(chips)',
 P_PATH='@t6g_mb_lib.t6g(sch_1):page279_i58@pure_quanta.q_cap(chips)',
 PATH='I58',
 DRAWING='@T6G_MB_LIB.T6G(SCH_1):PAGE388',
 TOLERANCE='20%',
 MATERIAL='X6S',
 PHYS_PAGE='279',
 XY='(-2100,3575)',
 ROT='0',
 VER='1',
 PACK_TYPE='0201',
 LOCATION='C525',
 CDS_LIB='pure_quanta',
 CDS_PART_NAME='Q_CAP_0201-1UF,4V,20%,X6S,CH-10KMEE00',
 VOLTAGE='4V',
 PART_NUMBER='CH-10KMEE00',
 VALUE='1UF',
 PRIM_FILE='./archive_libs/logical/q_cap/chips/chips.prt';

PART_NAME
 C526 'Q_CAP_0201-1UF,4V,20%,X6S,CH-10KMEE00':;

SECTION_NUMBER 1
 '@T6G_MB_LIB.T6G(SCH_1):PAGE388_I66@PURE_QUANTA.Q_CAP(CHIPS)':
 C_PATH='@t6g_mb_lib.t6g(sch_1):page388_i66@pure_quanta.q_cap(chips)',
 P_PATH='@t6g_mb_lib.t6g(sch_1):page279_i66@pure_quanta.q_cap(chips)',
 PATH='I66',
 DRAWING='@T6G_MB_LIB.T6G(SCH_1):PAGE388',
 TOLERANCE='20%',
 MATERIAL='X6S',
 PHYS_PAGE='279',
 XY='(-1400,3575)',
 ROT='0',
 VER='1',
 PACK_TYPE='0201',
 LOCATION='C526',
 CDS_LIB='pure_quanta',
 CDS_PART_NAME='Q_CAP_0201-1UF,4V,20%,X6S,CH-10KMEE00',
 VOLTAGE='4V',
 PART_NUMBER='CH-10KMEE00',
 VALUE='1UF',
 PRIM_FILE='./archive_libs/logical/q_cap/chips/chips.prt';

PART_NAME
 C527 'Q_CAP_C0805-10UF,25V,10%,X6S,CH6104KEA00':
 ROOM='';

SECTION_NUMBER 1
 '@T6G_MB_LIB.T6G(SCH_1):PAGE102_I239@PURE_QUANTA.Q_CAP(CHIPS)':
 C_PATH='@t6g_mb_lib.t6g(sch_1):page102_i239@pure_quanta.q_cap(chips)',
 P_PATH='@t6g_mb_lib.t6g(sch_1):page103_i239@pure_quanta.q_cap(chips)',
 PATH='I239',
 DRAWING='@T6G_MB_LIB.T6G(SCH_1):PAGE102',
 BOM_COST='MEM',
 TOLERANCE='10%',
 MATERIAL='X6S',
 PHYS_PAGE='103',
 XY='(-2325,6000)',
 ROT='2',
 VER='1',
 PACK_TYPE='C0805',
 LOCATION='C527',
 CDS_LIB='pure_quanta',
 CDS_PART_NAME='Q_CAP_C0805-10UF,25V,10%,X6S,CH6104KEA00',
 VOLTAGE='25V',
 ROOM='',
 PART_NUMBER='CH6104KEA00',
 VALUE='10UF',
 PRIM_FILE='./archive_libs/logical/q_cap/chips/chips.prt';

PART_NAME
 C528 'Q_CAP_0201-1UF,4V,20%,X6S,CH-10KMEE00':;

SECTION_NUMBER 1
 '@T6G_MB_LIB.T6G(SCH_1):PAGE388_I80@PURE_QUANTA.Q_CAP(CHIPS)':
 C_PATH='@t6g_mb_lib.t6g(sch_1):page388_i80@pure_quanta.q_cap(chips)',
 P_PATH='@t6g_mb_lib.t6g(sch_1):page279_i80@pure_quanta.q_cap(chips)',
 PATH='I80',
 DRAWING='@T6G_MB_LIB.T6G(SCH_1):PAGE388',
 TOLERANCE='20%',
 MATERIAL='X6S',
 PHYS_PAGE='279',
 XY='(-2950,5450)',
 ROT='0',
 VER='1',
 PACK_TYPE='0201',
 LOCATION='C528',
 CDS_LIB='pure_quanta',
 CDS_PART_NAME='Q_CAP_0201-1UF,4V,20%,X6S,CH-10KMEE00',
 VOLTAGE='4V',
 PART_NUMBER='CH-10KMEE00',
 VALUE='1UF',
 PRIM_FILE='./archive_libs/logical/q_cap/chips/chips.prt';

PART_NAME
 C529 'Q_CAP_0201-1UF,4V,20%,X6S,CH-10KMEE00':;

SECTION_NUMBER 1
 '@T6G_MB_LIB.T6G(SCH_1):PAGE388_I59@PURE_QUANTA.Q_CAP(CHIPS)':
 C_PATH='@t6g_mb_lib.t6g(sch_1):page388_i59@pure_quanta.q_cap(chips)',
 P_PATH='@t6g_mb_lib.t6g(sch_1):page279_i59@pure_quanta.q_cap(chips)',
 PATH='I59',
 DRAWING='@T6G_MB_LIB.T6G(SCH_1):PAGE388',
 TOLERANCE='20%',
 MATERIAL='X6S',
 PHYS_PAGE='279',
 XY='(-1875,3575)',
 ROT='0',
 VER='1',
 PACK_TYPE='0201',
 LOCATION='C529',
 CDS_LIB='pure_quanta',
 CDS_PART_NAME='Q_CAP_0201-1UF,4V,20%,X6S,CH-10KMEE00',
 VOLTAGE='4V',
 PART_NUMBER='CH-10KMEE00',
 VALUE='1UF',
 PRIM_FILE='./archive_libs/logical/q_cap/chips/chips.prt';

PART_NAME
 C530 'Q_CAP_C0805-10UF,25V,10%,X6S,CH6104KEA00':
 ROOM='';

SECTION_NUMBER 1
 '@T6G_MB_LIB.T6G(SCH_1):PAGE103_I240@PURE_QUANTA.Q_CAP(CHIPS)':
 C_PATH='@t6g_mb_lib.t6g(sch_1):page103_i240@pure_quanta.q_cap(chips)',
 P_PATH='@t6g_mb_lib.t6g(sch_1):page104_i240@pure_quanta.q_cap(chips)',
 PATH='I240',
 DRAWING='@T6G_MB_LIB.T6G(SCH_1):PAGE103',
 BOM_COST='MEM',
 TOLERANCE='10%',
 MATERIAL='X6S',
 PHYS_PAGE='104',
 XY='(-2825,5875)',
 ROT='2',
 VER='1',
 PACK_TYPE='C0805',
 LOCATION='C530',
 CDS_LIB='pure_quanta',
 CDS_PART_NAME='Q_CAP_C0805-10UF,25V,10%,X6S,CH6104KEA00',
 VOLTAGE='25V',
 ROOM='',
 PART_NUMBER='CH6104KEA00',
 VALUE='10UF',
 PRIM_FILE='./archive_libs/logical/q_cap/chips/chips.prt';

PART_NAME
 C531 'Q_CAP_C0805-10UF,25V,10%,X6S,CH6104KEA00':
 ROOM='';

SECTION_NUMBER 1
 '@T6G_MB_LIB.T6G(SCH_1):PAGE103_I241@PURE_QUANTA.Q_CAP(CHIPS)':
 C_PATH='@t6g_mb_lib.t6g(sch_1):page103_i241@pure_quanta.q_cap(chips)',
 P_PATH='@t6g_mb_lib.t6g(sch_1):page104_i241@pure_quanta.q_cap(chips)',
 PATH='I241',
 DRAWING='@T6G_MB_LIB.T6G(SCH_1):PAGE103',
 BOM_COST='MEM',
 TOLERANCE='10%',
 MATERIAL='X6S',
 PHYS_PAGE='104',
 XY='(-2250,5875)',
 ROT='2',
 VER='1',
 PACK_TYPE='C0805',
 LOCATION='C531',
 CDS_LIB='pure_quanta',
 CDS_PART_NAME='Q_CAP_C0805-10UF,25V,10%,X6S,CH6104KEA00',
 VOLTAGE='25V',
 ROOM='',
 PART_NUMBER='CH6104KEA00',
 VALUE='10UF',
 PRIM_FILE='./archive_libs/logical/q_cap/chips/chips.prt';

PART_NAME
 C532 'Q_CAP_C0805-10UF,25V,10%,X6S,CH6104KEA00':
 ROOM='';

SECTION_NUMBER 1
 '@T6G_MB_LIB.T6G(SCH_1):PAGE104_I240@PURE_QUANTA.Q_CAP(CHIPS)':
 C_PATH='@t6g_mb_lib.t6g(sch_1):page104_i240@pure_quanta.q_cap(chips)',
 P_PATH='@t6g_mb_lib.t6g(sch_1):page105_i240@pure_quanta.q_cap(chips)',
 PATH='I240',
 DRAWING='@T6G_MB_LIB.T6G(SCH_1):PAGE104',
 BOM_COST='MEM',
 TOLERANCE='10%',
 MATERIAL='X6S',
 PHYS_PAGE='105',
 XY='(-2825,5875)',
 ROT='2',
 VER='1',
 PACK_TYPE='C0805',
 LOCATION='C532',
 CDS_LIB='pure_quanta',
 CDS_PART_NAME='Q_CAP_C0805-10UF,25V,10%,X6S,CH6104KEA00',
 VOLTAGE='25V',
 ROOM='',
 PART_NUMBER='CH6104KEA00',
 VALUE='10UF',
 PRIM_FILE='./archive_libs/logical/q_cap/chips/chips.prt';

PART_NAME
 C533 'Q_CAP_C0805-10UF,25V,10%,X6S,CH6104KEA00':
 ROOM='';

SECTION_NUMBER 1
 '@T6G_MB_LIB.T6G(SCH_1):PAGE104_I241@PURE_QUANTA.Q_CAP(CHIPS)':
 C_PATH='@t6g_mb_lib.t6g(sch_1):page104_i241@pure_quanta.q_cap(chips)',
 P_PATH='@t6g_mb_lib.t6g(sch_1):page105_i241@pure_quanta.q_cap(chips)',
 PATH='I241',
 DRAWING='@T6G_MB_LIB.T6G(SCH_1):PAGE104',
 BOM_COST='MEM',
 TOLERANCE='10%',
 MATERIAL='X6S',
 PHYS_PAGE='105',
 XY='(-2250,5875)',
 ROT='2',
 VER='1',
 PACK_TYPE='C0805',
 LOCATION='C533',
 CDS_LIB='pure_quanta',
 CDS_PART_NAME='Q_CAP_C0805-10UF,25V,10%,X6S,CH6104KEA00',
 VOLTAGE='25V',
 ROOM='',
 PART_NUMBER='CH6104KEA00',
 VALUE='10UF',
 PRIM_FILE='./archive_libs/logical/q_cap/chips/chips.prt';

PART_NAME
 C534 'Q_CAP_C0805-10UF,25V,10%,X6S,CH6104KEA00':
 ROOM='';

SECTION_NUMBER 1
 '@T6G_MB_LIB.T6G(SCH_1):PAGE105_I238@PURE_QUANTA.Q_CAP(CHIPS)':
 C_PATH='@t6g_mb_lib.t6g(sch_1):page105_i238@pure_quanta.q_cap(chips)',
 P_PATH='@t6g_mb_lib.t6g(sch_1):page106_i238@pure_quanta.q_cap(chips)',
 PATH='I238',
 DRAWING='@T6G_MB_LIB.T6G(SCH_1):PAGE105',
 BOM_COST='MEM',
 TOLERANCE='10%',
 MATERIAL='X6S',
 PHYS_PAGE='106',
 XY='(-2825,5800)',
 ROT='2',
 VER='1',
 PACK_TYPE='C0805',
 LOCATION='C534',
 CDS_LIB='pure_quanta',
 CDS_PART_NAME='Q_CAP_C0805-10UF,25V,10%,X6S,CH6104KEA00',
 VOLTAGE='25V',
 ROOM='',
 PART_NUMBER='CH6104KEA00',
 VALUE='10UF',
 PRIM_FILE='./archive_libs/logical/q_cap/chips/chips.prt';

PART_NAME
 C535 'Q_CAP_C0805-10UF,25V,10%,X6S,CH6104KEA00':
 ROOM='';

SECTION_NUMBER 1
 '@T6G_MB_LIB.T6G(SCH_1):PAGE105_I239@PURE_QUANTA.Q_CAP(CHIPS)':
 C_PATH='@t6g_mb_lib.t6g(sch_1):page105_i239@pure_quanta.q_cap(chips)',
 P_PATH='@t6g_mb_lib.t6g(sch_1):page106_i239@pure_quanta.q_cap(chips)',
 PATH='I239',
 DRAWING='@T6G_MB_LIB.T6G(SCH_1):PAGE105',
 BOM_COST='MEM',
 TOLERANCE='10%',
 MATERIAL='X6S',
 PHYS_PAGE='106',
 XY='(-2250,5800)',
 ROT='2',
 VER='1',
 PACK_TYPE='C0805',
 LOCATION='C535',
 CDS_LIB='pure_quanta',
 CDS_PART_NAME='Q_CAP_C0805-10UF,25V,10%,X6S,CH6104KEA00',
 VOLTAGE='25V',
 ROOM='',
 PART_NUMBER='CH6104KEA00',
 VALUE='10UF',
 PRIM_FILE='./archive_libs/logical/q_cap/chips/chips.prt';

PART_NAME
 C536 'Q_CAP_C0805-10UF,25V,10%,X6S,CH6104KEA00':
 ROOM='';

SECTION_NUMBER 1
 '@T6G_MB_LIB.T6G(SCH_1):PAGE106_I238@PURE_QUANTA.Q_CAP(CHIPS)':
 C_PATH='@t6g_mb_lib.t6g(sch_1):page106_i238@pure_quanta.q_cap(chips)',
 P_PATH='@t6g_mb_lib.t6g(sch_1):page107_i238@pure_quanta.q_cap(chips)',
 PATH='I238',
 DRAWING='@T6G_MB_LIB.T6G(SCH_1):PAGE106',
 BOM_COST='MEM',
 TOLERANCE='10%',
 MATERIAL='X6S',
 PHYS_PAGE='107',
 XY='(-2725,5775)',
 ROT='2',
 VER='1',
 PACK_TYPE='C0805',
 LOCATION='C536',
 CDS_LIB='pure_quanta',
 CDS_PART_NAME='Q_CAP_C0805-10UF,25V,10%,X6S,CH6104KEA00',
 VOLTAGE='25V',
 ROOM='',
 PART_NUMBER='CH6104KEA00',
 VALUE='10UF',
 PRIM_FILE='./archive_libs/logical/q_cap/chips/chips.prt';

PART_NAME
 C537 'Q_CAP_C0805-10UF,25V,10%,X6S,CH6104KEA00':
 ROOM='';

SECTION_NUMBER 1
 '@T6G_MB_LIB.T6G(SCH_1):PAGE106_I239@PURE_QUANTA.Q_CAP(CHIPS)':
 C_PATH='@t6g_mb_lib.t6g(sch_1):page106_i239@pure_quanta.q_cap(chips)',
 P_PATH='@t6g_mb_lib.t6g(sch_1):page107_i239@pure_quanta.q_cap(chips)',
 PATH='I239',
 DRAWING='@T6G_MB_LIB.T6G(SCH_1):PAGE106',
 BOM_COST='MEM',
 TOLERANCE='10%',
 MATERIAL='X6S',
 PHYS_PAGE='107',
 XY='(-2150,5775)',
 ROT='2',
 VER='1',
 PACK_TYPE='C0805',
 LOCATION='C537',
 CDS_LIB='pure_quanta',
 CDS_PART_NAME='Q_CAP_C0805-10UF,25V,10%,X6S,CH6104KEA00',
 VOLTAGE='25V',
 ROOM='',
 PART_NUMBER='CH6104KEA00',
 VALUE='10UF',
 PRIM_FILE='./archive_libs/logical/q_cap/chips/chips.prt';

PART_NAME
 C538 'Q_CAP_C0201-0.1UF,10V,10%,X7S,CH4102K6E00':;

SECTION_NUMBER 1
 '@T6G_MB_LIB.T6G(SCH_1):PAGE388_I32@PURE_QUANTA.Q_CAP(CHIPS)':
 C_PATH='@t6g_mb_lib.t6g(sch_1):page388_i32@pure_quanta.q_cap(chips)',
 P_PATH='@t6g_mb_lib.t6g(sch_1):page279_i32@pure_quanta.q_cap(chips)',
 PATH='I32',
 DRAWING='@T6G_MB_LIB.T6G(SCH_1):PAGE388',
 TOLERANCE='10%',
 MATERIAL='X7S',
 PHYS_PAGE='279',
 XY='(-3025,1150)',
 ROT='0',
 VER='1',
 PACK_TYPE='C0201',
 LOCATION='C538',
 CDS_LIB='pure_quanta',
 CDS_PART_NAME='Q_CAP_C0201-0.1UF,10V,10%,X7S,CH4102K6E00',
 VOLTAGE='10V',
 PART_NUMBER='CH4102K6E00',
 VALUE='0.1UF',
 PRIM_FILE='./archive_libs/logical/q_cap/chips/chips.prt';

PART_NAME
 C539 'Q_CAP_0201-1UF,4V,20%,X6S,CH-10KMEE00':;

SECTION_NUMBER 1
 '@T6G_MB_LIB.T6G(SCH_1):PAGE388_I42@PURE_QUANTA.Q_CAP(CHIPS)':
 C_PATH='@t6g_mb_lib.t6g(sch_1):page388_i42@pure_quanta.q_cap(chips)',
 P_PATH='@t6g_mb_lib.t6g(sch_1):page279_i42@pure_quanta.q_cap(chips)',
 PATH='I42',
 DRAWING='@T6G_MB_LIB.T6G(SCH_1):PAGE388',
 TOLERANCE='20%',
 MATERIAL='X6S',
 PHYS_PAGE='279',
 XY='(-3250,2950)',
 ROT='0',
 VER='1',
 PACK_TYPE='0201',
 LOCATION='C539',
 CDS_LIB='pure_quanta',
 CDS_PART_NAME='Q_CAP_0201-1UF,4V,20%,X6S,CH-10KMEE00',
 VOLTAGE='4V',
 PART_NUMBER='CH-10KMEE00',
 VALUE='1UF',
 PRIM_FILE='./archive_libs/logical/q_cap/chips/chips.prt';

PART_NAME
 C540 'Q_CAP_C0201-0.1UF,10V,10%,X7S,CH4102K6E00':;

SECTION_NUMBER 1
 '@T6G_MB_LIB.T6G(SCH_1):PAGE388_I87@PURE_QUANTA.Q_CAP(CHIPS)':
 C_PATH='@t6g_mb_lib.t6g(sch_1):page388_i87@pure_quanta.q_cap(chips)',
 P_PATH='@t6g_mb_lib.t6g(sch_1):page279_i87@pure_quanta.q_cap(chips)',
 PATH='I87',
 DRAWING='@T6G_MB_LIB.T6G(SCH_1):PAGE388',
 TOLERANCE='10%',
 MATERIAL='X7S',
 PHYS_PAGE='279',
 XY='(-1725,5450)',
 ROT='0',
 VER='1',
 PACK_TYPE='C0201',
 LOCATION='C540',
 CDS_LIB='pure_quanta',
 CDS_PART_NAME='Q_CAP_C0201-0.1UF,10V,10%,X7S,CH4102K6E00',
 VOLTAGE='10V',
 PART_NUMBER='CH4102K6E00',
 VALUE='0.1UF',
 PRIM_FILE='./archive_libs/logical/q_cap/chips/chips.prt';

PART_NAME
 C541 'Q_CAP_C0201-0.1UF,10V,10%,X7S,CH4102K6E00':;

SECTION_NUMBER 1
 '@T6G_MB_LIB.T6G(SCH_1):PAGE388_I48@PURE_QUANTA.Q_CAP(CHIPS)':
 C_PATH='@t6g_mb_lib.t6g(sch_1):page388_i48@pure_quanta.q_cap(chips)',
 P_PATH='@t6g_mb_lib.t6g(sch_1):page279_i48@pure_quanta.q_cap(chips)',
 PATH='I48',
 DRAWING='@T6G_MB_LIB.T6G(SCH_1):PAGE388',
 TOLERANCE='10%',
 MATERIAL='X7S',
 PHYS_PAGE='279',
 XY='(-2675,2250)',
 ROT='0',
 VER='1',
 PACK_TYPE='C0201',
 LOCATION='C541',
 CDS_LIB='pure_quanta',
 CDS_PART_NAME='Q_CAP_C0201-0.1UF,10V,10%,X7S,CH4102K6E00',
 VOLTAGE='10V',
 PART_NUMBER='CH4102K6E00',
 VALUE='0.1UF',
 PRIM_FILE='./archive_libs/logical/q_cap/chips/chips.prt';

PART_NAME
 C542 'Q_CAP_0201-1UF,4V,20%,X6S,CH-10KMEE00':;

SECTION_NUMBER 1
 '@T6G_MB_LIB.T6G(SCH_1):PAGE388_I90@PURE_QUANTA.Q_CAP(CHIPS)':
 C_PATH='@t6g_mb_lib.t6g(sch_1):page388_i90@pure_quanta.q_cap(chips)',
 P_PATH='@t6g_mb_lib.t6g(sch_1):page279_i90@pure_quanta.q_cap(chips)',
 PATH='I90',
 DRAWING='@T6G_MB_LIB.T6G(SCH_1):PAGE388',
 TOLERANCE='20%',
 MATERIAL='X6S',
 PHYS_PAGE='279',
 XY='(-2775,1150)',
 ROT='0',
 VER='1',
 PACK_TYPE='0201',
 LOCATION='C542',
 CDS_LIB='pure_quanta',
 CDS_PART_NAME='Q_CAP_0201-1UF,4V,20%,X6S,CH-10KMEE00',
 VOLTAGE='4V',
 PART_NUMBER='CH-10KMEE00',
 VALUE='1UF',
 PRIM_FILE='./archive_libs/logical/q_cap/chips/chips.prt';

PART_NAME
 C543 'Q_CAP_C0201-0.1UF,10V,10%,X7S,CH4102K6E00':;

SECTION_NUMBER 1
 '@T6G_MB_LIB.T6G(SCH_1):PAGE388_I62@PURE_QUANTA.Q_CAP(CHIPS)':
 C_PATH='@t6g_mb_lib.t6g(sch_1):page388_i62@pure_quanta.q_cap(chips)',
 P_PATH='@t6g_mb_lib.t6g(sch_1):page279_i62@pure_quanta.q_cap(chips)',
 PATH='I62',
 DRAWING='@T6G_MB_LIB.T6G(SCH_1):PAGE388',
 TOLERANCE='10%',
 MATERIAL='X7S',
 PHYS_PAGE='279',
 XY='(-1375,2250)',
 ROT='0',
 VER='1',
 PACK_TYPE='C0201',
 LOCATION='C543',
 CDS_LIB='pure_quanta',
 CDS_PART_NAME='Q_CAP_C0201-0.1UF,10V,10%,X7S,CH4102K6E00',
 VOLTAGE='10V',
 PART_NUMBER='CH4102K6E00',
 VALUE='0.1UF',
 PRIM_FILE='./archive_libs/logical/q_cap/chips/chips.prt';

PART_NAME
 C544 'Q_CAP_C0201-0.1UF,10V,10%,X7S,CH4102K6E00':;

SECTION_NUMBER 1
 '@T6G_MB_LIB.T6G(SCH_1):PAGE388_I36@PURE_QUANTA.Q_CAP(CHIPS)':
 C_PATH='@t6g_mb_lib.t6g(sch_1):page388_i36@pure_quanta.q_cap(chips)',
 P_PATH='@t6g_mb_lib.t6g(sch_1):page279_i36@pure_quanta.q_cap(chips)',
 PATH='I36',
 DRAWING='@T6G_MB_LIB.T6G(SCH_1):PAGE388',
 TOLERANCE='10%',
 MATERIAL='X7S',
 PHYS_PAGE='279',
 XY='(-2475,1150)',
 ROT='0',
 VER='1',
 PACK_TYPE='C0201',
 LOCATION='C544',
 CDS_LIB='pure_quanta',
 CDS_PART_NAME='Q_CAP_C0201-0.1UF,10V,10%,X7S,CH4102K6E00',
 VOLTAGE='10V',
 PART_NUMBER='CH4102K6E00',
 VALUE='0.1UF',
 PRIM_FILE='./archive_libs/logical/q_cap/chips/chips.prt';

PART_NAME
 C545 'Q_CAP_0201-1UF,4V,20%,X6S,CH-10KMEE00':;

SECTION_NUMBER 1
 '@T6G_MB_LIB.T6G(SCH_1):PAGE388_I91@PURE_QUANTA.Q_CAP(CHIPS)':
 C_PATH='@t6g_mb_lib.t6g(sch_1):page388_i91@pure_quanta.q_cap(chips)',
 P_PATH='@t6g_mb_lib.t6g(sch_1):page279_i91@pure_quanta.q_cap(chips)',
 PATH='I91',
 DRAWING='@T6G_MB_LIB.T6G(SCH_1):PAGE388',
 TOLERANCE='20%',
 MATERIAL='X6S',
 PHYS_PAGE='279',
 XY='(-2225,1150)',
 ROT='0',
 VER='1',
 PACK_TYPE='0201',
 LOCATION='C545',
 CDS_LIB='pure_quanta',
 CDS_PART_NAME='Q_CAP_0201-1UF,4V,20%,X6S,CH-10KMEE00',
 VOLTAGE='4V',
 PART_NUMBER='CH-10KMEE00',
 VALUE='1UF',
 PRIM_FILE='./archive_libs/logical/q_cap/chips/chips.prt';

PART_NAME
 C546 'Q_CAP_C0805-10UF,25V,10%,X6S,CH6104KEA00':
 ROOM='';

SECTION_NUMBER 1
 '@T6G_MB_LIB.T6G(SCH_1):PAGE107_I237@PURE_QUANTA.Q_CAP(CHIPS)':
 C_PATH='@t6g_mb_lib.t6g(sch_1):page107_i237@pure_quanta.q_cap(chips)',
 P_PATH='@t6g_mb_lib.t6g(sch_1):page108_i237@pure_quanta.q_cap(chips)',
 PATH='I237',
 DRAWING='@T6G_MB_LIB.T6G(SCH_1):PAGE107',
 BOM_COST='MEM',
 TOLERANCE='10%',
 MATERIAL='X6S',
 PHYS_PAGE='108',
 XY='(-2850,5825)',
 ROT='2',
 VER='1',
 PACK_TYPE='C0805',
 LOCATION='C546',
 CDS_LIB='pure_quanta',
 CDS_PART_NAME='Q_CAP_C0805-10UF,25V,10%,X6S,CH6104KEA00',
 VOLTAGE='25V',
 ROOM='',
 PART_NUMBER='CH6104KEA00',
 VALUE='10UF',
 PRIM_FILE='./archive_libs/logical/q_cap/chips/chips.prt';

PART_NAME
 C547 'Q_CAP_C0805-10UF,25V,10%,X6S,CH6104KEA00':
 ROOM='';

SECTION_NUMBER 1
 '@T6G_MB_LIB.T6G(SCH_1):PAGE107_I238@PURE_QUANTA.Q_CAP(CHIPS)':
 C_PATH='@t6g_mb_lib.t6g(sch_1):page107_i238@pure_quanta.q_cap(chips)',
 P_PATH='@t6g_mb_lib.t6g(sch_1):page108_i238@pure_quanta.q_cap(chips)',
 PATH='I238',
 DRAWING='@T6G_MB_LIB.T6G(SCH_1):PAGE107',
 BOM_COST='MEM',
 TOLERANCE='10%',
 MATERIAL='X6S',
 PHYS_PAGE='108',
 XY='(-2275,5825)',
 ROT='2',
 VER='1',
 PACK_TYPE='C0805',
 LOCATION='C547',
 CDS_LIB='pure_quanta',
 CDS_PART_NAME='Q_CAP_C0805-10UF,25V,10%,X6S,CH6104KEA00',
 VOLTAGE='25V',
 ROOM='',
 PART_NUMBER='CH6104KEA00',
 VALUE='10UF',
 PRIM_FILE='./archive_libs/logical/q_cap/chips/chips.prt';

PART_NAME
 C548 'Q_CAP_C0805-10UF,25V,10%,X6S,CH6104KEA00':
 ROOM='';

SECTION_NUMBER 1
 '@T6G_MB_LIB.T6G(SCH_1):PAGE108_I237@PURE_QUANTA.Q_CAP(CHIPS)':
 C_PATH='@t6g_mb_lib.t6g(sch_1):page108_i237@pure_quanta.q_cap(chips)',
 P_PATH='@t6g_mb_lib.t6g(sch_1):page109_i237@pure_quanta.q_cap(chips)',
 PATH='I237',
 DRAWING='@T6G_MB_LIB.T6G(SCH_1):PAGE108',
 BOM_COST='MEM',
 TOLERANCE='10%',
 MATERIAL='X6S',
 PHYS_PAGE='109',
 XY='(-2800,5850)',
 ROT='2',
 VER='1',
 PACK_TYPE='C0805',
 LOCATION='C548',
 CDS_LIB='pure_quanta',
 CDS_PART_NAME='Q_CAP_C0805-10UF,25V,10%,X6S,CH6104KEA00',
 VOLTAGE='25V',
 ROOM='',
 PART_NUMBER='CH6104KEA00',
 VALUE='10UF',
 PRIM_FILE='./archive_libs/logical/q_cap/chips/chips.prt';

PART_NAME
 C549 'Q_CAP_C0805-10UF,25V,10%,X6S,CH6104KEA00':
 ROOM='';

SECTION_NUMBER 1
 '@T6G_MB_LIB.T6G(SCH_1):PAGE108_I238@PURE_QUANTA.Q_CAP(CHIPS)':
 C_PATH='@t6g_mb_lib.t6g(sch_1):page108_i238@pure_quanta.q_cap(chips)',
 P_PATH='@t6g_mb_lib.t6g(sch_1):page109_i238@pure_quanta.q_cap(chips)',
 PATH='I238',
 DRAWING='@T6G_MB_LIB.T6G(SCH_1):PAGE108',
 BOM_COST='MEM',
 TOLERANCE='10%',
 MATERIAL='X6S',
 PHYS_PAGE='109',
 XY='(-2225,5850)',
 ROT='2',
 VER='1',
 PACK_TYPE='C0805',
 LOCATION='C549',
 CDS_LIB='pure_quanta',
 CDS_PART_NAME='Q_CAP_C0805-10UF,25V,10%,X6S,CH6104KEA00',
 VOLTAGE='25V',
 ROOM='',
 PART_NUMBER='CH6104KEA00',
 VALUE='10UF',
 PRIM_FILE='./archive_libs/logical/q_cap/chips/chips.prt';

PART_NAME
 C550 'Q_CAP_C0805-100UF,4V,20%,X6S,CH710KMEA01':;

SECTION_NUMBER 1
 '@T6G_MB_LIB.T6G(SCH_1):PAGE388_I67@PURE_QUANTA.Q_CAP(CHIPS)':
 C_PATH='@t6g_mb_lib.t6g(sch_1):page388_i67@pure_quanta.q_cap(chips)',
 P_PATH='@t6g_mb_lib.t6g(sch_1):page279_i67@pure_quanta.q_cap(chips)',
 PATH='I67',
 DRAWING='@T6G_MB_LIB.T6G(SCH_1):PAGE388',
 TOLERANCE='20%',
 MATERIAL='X6S',
 PHYS_PAGE='279',
 XY='(-3475,4200)',
 ROT='0',
 VER='1',
 PACK_TYPE='C0805',
 LOCATION='C550',
 CDS_LIB='pure_quanta',
 CDS_PART_NAME='Q_CAP_C0805-100UF,4V,20%,X6S,CH710KMEA01',
 VOLTAGE='4V',
 PART_NUMBER='CH710KMEA01',
 VALUE='100UF',
 PRIM_FILE='./archive_libs/logical/q_cap/chips/chips.prt';

PART_NAME
 C551 'Q_CAP_C0402-0.01UF,50V,10%,X7R,CH31006KB18':
 SIGNAL_MODEL='DEFAULT_CAPACITOR_10000PF_2_1';

SECTION_NUMBER 1
 '@T6G_MB_LIB.T6G(SCH_1):PAGE149_I123@PURE_QUANTA.Q_CAP(CHIPS)':
 C_PATH='@t6g_mb_lib.t6g(sch_1):page149_i123@pure_quanta.q_cap(chips)',
 P_PATH='@t6g_mb_lib.t6g(sch_1):page172_i123@pure_quanta.q_cap(chips)',
 PATH='I123',
 DRAWING='@T6G_MB_LIB.T6G(SCH_1):PAGE149',
 TOLERANCE='10%',
 MATERIAL='X7R',
 PHYS_PAGE='172',
 XY='(-2125,5325)',
 ROT='0',
 VER='1',
 PACK_TYPE='C0402',
 LOCATION='C551',
 CDS_LIB='pure_quanta',
 CDS_PART_NAME='Q_CAP_C0402-0.01UF,50V,10%,X7R,CH31006KB18',
 SIGNAL_MODEL='DEFAULT_CAPACITOR_10000PF_2_1',
 VOLTAGE='50V',
 PART_NUMBER='CH31006KB18',
 VALUE='0.01UF',
 PRIM_FILE='./archive_libs/logical/q_cap/chips/chips.prt';

PART_NAME
 C552 'Q_CAP_0402-0.1UF,25V,10%,X7R,CH4104K1B00':;

SECTION_NUMBER 1
 '@T6G_MB_LIB.T6G(SCH_1):PAGE83_I24@PURE_QUANTA.Q_CAP(CHIPS)':
 C_PATH='@t6g_mb_lib.t6g(sch_1):page83_i24@pure_quanta.q_cap(chips)',
 P_PATH='@t6g_mb_lib.t6g(sch_1):page84_i24@pure_quanta.q_cap(chips)',
 PATH='I24',
 DRAWING='@T6G_MB_LIB.T6G(SCH_1):PAGE83',
 BOM_COST='OCP3.0 ',
 TOLERANCE='10%',
 MATERIAL='X7R',
 PHYS_PAGE='84',
 XY='(-2850,5850)',
 ROT='0',
 VER='1',
 PACK_TYPE='0402',
 LOCATION='C552',
 CDS_LIB='pure_quanta',
 CDS_PART_NAME='Q_CAP_0402-0.1UF,25V,10%,X7R,CH4104K1B00',
 VOLTAGE='25V',
 PART_NUMBER='CH4104K1B00',
 VALUE='0.1UF',
 PRIM_FILE='./archive_libs/logical/q_cap/chips/chips.prt';

PART_NAME
 C553 'Q_CAP_0402-0.1UF,25V,10%,X7R,CH4104K1B00':;

SECTION_NUMBER 1
 '@T6G_MB_LIB.T6G(SCH_1):PAGE148_I342@PURE_QUANTA.Q_CAP(CHIPS)':
 C_PATH='@t6g_mb_lib.t6g(sch_1):page148_i342@pure_quanta.q_cap(chips)',
 P_PATH='@t6g_mb_lib.t6g(sch_1):page171_i342@pure_quanta.q_cap(chips)',
 PATH='I342',
 DRAWING='@T6G_MB_LIB.T6G(SCH_1):PAGE148',
 BOM_COST='OCP3.0 ',
 TOLERANCE='10%',
 MATERIAL='X7R',
 PHYS_PAGE='171',
 XY='(-8000,5550)',
 ROT='0',
 VER='1',
 PACK_TYPE='0402',
 LOCATION='C553',
 CDS_LIB='pure_quanta',
 CDS_PART_NAME='Q_CAP_0402-0.1UF,25V,10%,X7R,CH4104K1B00',
 VOLTAGE='25V',
 PART_NUMBER='CH4104K1B00',
 VALUE='0.1UF',
 PRIM_FILE='./archive_libs/logical/q_cap/chips/chips.prt';

PART_NAME
 C554 'Q_CAP_0402-4.7UF,6.3V,20%,X6S,CH5471MEB01':;

SECTION_NUMBER 1
 '@T6G_MB_LIB.T6G(SCH_1):PAGE388_I45@PURE_QUANTA.Q_CAP(CHIPS)':
 C_PATH='@t6g_mb_lib.t6g(sch_1):page388_i45@pure_quanta.q_cap(chips)',
 P_PATH='@t6g_mb_lib.t6g(sch_1):page279_i45@pure_quanta.q_cap(chips)',
 PATH='I45',
 DRAWING='@T6G_MB_LIB.T6G(SCH_1):PAGE388',
 TOLERANCE='20%',
 MATERIAL='X6S',
 PHYS_PAGE='279',
 XY='(-3025,3575)',
 ROT='0',
 VER='1',
 PACK_TYPE='0402',
 LOCATION='C554',
 CDS_LIB='pure_quanta',
 CDS_PART_NAME='Q_CAP_0402-4.7UF,6.3V,20%,X6S,CH5471MEB01',
 VOLTAGE='6.3V',
 PART_NUMBER='CH5471MEB01',
 VALUE='4.7UF',
 PRIM_FILE='./archive_libs/logical/q_cap/chips/chips.prt';

PART_NAME
 C555 'Q_CAP_0201-1UF,4V,20%,X6S,CH-10KMEE00':;

SECTION_NUMBER 1
 '@T6G_MB_LIB.T6G(SCH_1):PAGE388_I40@PURE_QUANTA.Q_CAP(CHIPS)':
 C_PATH='@t6g_mb_lib.t6g(sch_1):page388_i40@pure_quanta.q_cap(chips)',
 P_PATH='@t6g_mb_lib.t6g(sch_1):page279_i40@pure_quanta.q_cap(chips)',
 PATH='I40',
 DRAWING='@T6G_MB_LIB.T6G(SCH_1):PAGE388',
 TOLERANCE='20%',
 MATERIAL='X6S',
 PHYS_PAGE='279',
 XY='(-3475,2950)',
 ROT='0',
 VER='1',
 PACK_TYPE='0201',
 LOCATION='C555',
 CDS_LIB='pure_quanta',
 CDS_PART_NAME='Q_CAP_0201-1UF,4V,20%,X6S,CH-10KMEE00',
 VOLTAGE='4V',
 PART_NUMBER='CH-10KMEE00',
 VALUE='1UF',
 PRIM_FILE='./archive_libs/logical/q_cap/chips/chips.prt';

PART_NAME
 C556 'Q_CAP_C0805-100UF,4V,20%,X6S,CH710KMEA01':;

SECTION_NUMBER 1
 '@T6G_MB_LIB.T6G(SCH_1):PAGE388_I69@PURE_QUANTA.Q_CAP(CHIPS)':
 C_PATH='@t6g_mb_lib.t6g(sch_1):page388_i69@pure_quanta.q_cap(chips)',
 P_PATH='@t6g_mb_lib.t6g(sch_1):page279_i69@pure_quanta.q_cap(chips)',
 PATH='I69',
 DRAWING='@T6G_MB_LIB.T6G(SCH_1):PAGE388',
 TOLERANCE='20%',
 MATERIAL='X6S',
 PHYS_PAGE='279',
 XY='(-3250,4200)',
 ROT='0',
 VER='1',
 PACK_TYPE='C0805',
 LOCATION='C556',
 CDS_LIB='pure_quanta',
 CDS_PART_NAME='Q_CAP_C0805-100UF,4V,20%,X6S,CH710KMEA01',
 VOLTAGE='4V',
 PART_NUMBER='CH710KMEA01',
 VALUE='100UF',
 PRIM_FILE='./archive_libs/logical/q_cap/chips/chips.prt';

PART_NAME
 C557 'Q_CAP_0402-4.7UF,6.3V,20%,X6S,CH5471MEB01':;

SECTION_NUMBER 1
 '@T6G_MB_LIB.T6G(SCH_1):PAGE388_I54@PURE_QUANTA.Q_CAP(CHIPS)':
 C_PATH='@t6g_mb_lib.t6g(sch_1):page388_i54@pure_quanta.q_cap(chips)',
 P_PATH='@t6g_mb_lib.t6g(sch_1):page279_i54@pure_quanta.q_cap(chips)',
 PATH='I54',
 DRAWING='@T6G_MB_LIB.T6G(SCH_1):PAGE388',
 TOLERANCE='20%',
 MATERIAL='X6S',
 PHYS_PAGE='279',
 XY='(-2550,3575)',
 ROT='0',
 VER='1',
 PACK_TYPE='0402',
 LOCATION='C557',
 CDS_LIB='pure_quanta',
 CDS_PART_NAME='Q_CAP_0402-4.7UF,6.3V,20%,X6S,CH5471MEB01',
 VOLTAGE='6.3V',
 PART_NUMBER='CH5471MEB01',
 VALUE='4.7UF',
 PRIM_FILE='./archive_libs/logical/q_cap/chips/chips.prt';

PART_NAME
 C558 'Q_CAP_C0201-0.1UF,10V,10%,X7S,CH4102K6E00':;

SECTION_NUMBER 1
 '@T6G_MB_LIB.T6G(SCH_1):PAGE388_I60@PURE_QUANTA.Q_CAP(CHIPS)':
 C_PATH='@t6g_mb_lib.t6g(sch_1):page388_i60@pure_quanta.q_cap(chips)',
 P_PATH='@t6g_mb_lib.t6g(sch_1):page279_i60@pure_quanta.q_cap(chips)',
 PATH='I60',
 DRAWING='@T6G_MB_LIB.T6G(SCH_1):PAGE388',
 TOLERANCE='10%',
 MATERIAL='X7S',
 PHYS_PAGE='279',
 XY='(-1625,2250)',
 ROT='0',
 VER='1',
 PACK_TYPE='C0201',
 LOCATION='C558',
 CDS_LIB='pure_quanta',
 CDS_PART_NAME='Q_CAP_C0201-0.1UF,10V,10%,X7S,CH4102K6E00',
 VOLTAGE='10V',
 PART_NUMBER='CH4102K6E00',
 VALUE='0.1UF',
 PRIM_FILE='./archive_libs/logical/q_cap/chips/chips.prt';

PART_NAME
 C559 'Q_CAP_C0805-100UF,4V,20%,X6S,CH710KMEA01':;

SECTION_NUMBER 1
 '@T6G_MB_LIB.T6G(SCH_1):PAGE388_I72@PURE_QUANTA.Q_CAP(CHIPS)':
 C_PATH='@t6g_mb_lib.t6g(sch_1):page388_i72@pure_quanta.q_cap(chips)',
 P_PATH='@t6g_mb_lib.t6g(sch_1):page279_i72@pure_quanta.q_cap(chips)',
 PATH='I72',
 DRAWING='@T6G_MB_LIB.T6G(SCH_1):PAGE388',
 TOLERANCE='20%',
 MATERIAL='X6S',
 PHYS_PAGE='279',
 XY='(-4100,5475)',
 ROT='0',
 VER='1',
 PACK_TYPE='C0805',
 LOCATION='C559',
 CDS_LIB='pure_quanta',
 CDS_PART_NAME='Q_CAP_C0805-100UF,4V,20%,X6S,CH710KMEA01',
 VOLTAGE='4V',
 PART_NUMBER='CH710KMEA01',
 VALUE='100UF',
 PRIM_FILE='./archive_libs/logical/q_cap/chips/chips.prt';

PART_NAME
 C560 'Q_CAP_C0805-100UF,4V,20%,X6S,CH710KMEA01':;

SECTION_NUMBER 1
 '@T6G_MB_LIB.T6G(SCH_1):PAGE388_I70@PURE_QUANTA.Q_CAP(CHIPS)':
 C_PATH='@t6g_mb_lib.t6g(sch_1):page388_i70@pure_quanta.q_cap(chips)',
 P_PATH='@t6g_mb_lib.t6g(sch_1):page279_i70@pure_quanta.q_cap(chips)',
 PATH='I70',
 DRAWING='@T6G_MB_LIB.T6G(SCH_1):PAGE388',
 TOLERANCE='20%',
 MATERIAL='X6S',
 PHYS_PAGE='279',
 XY='(-3025,4200)',
 ROT='0',
 VER='1',
 PACK_TYPE='C0805',
 LOCATION='C560',
 CDS_LIB='pure_quanta',
 CDS_PART_NAME='Q_CAP_C0805-100UF,4V,20%,X6S,CH710KMEA01',
 VOLTAGE='4V',
 PART_NUMBER='CH710KMEA01',
 VALUE='100UF',
 PRIM_FILE='./archive_libs/logical/q_cap/chips/chips.prt';

PART_NAME
 C561 'Q_CAP_C0402-10UF,6.3V,20%,X6S,CH6101MEB01':;

SECTION_NUMBER 1
 '@T6G_MB_LIB.T6G(SCH_1):PAGE388_I41@PURE_QUANTA.Q_CAP(CHIPS)':
 C_PATH='@t6g_mb_lib.t6g(sch_1):page388_i41@pure_quanta.q_cap(chips)',
 P_PATH='@t6g_mb_lib.t6g(sch_1):page279_i41@pure_quanta.q_cap(chips)',
 PATH='I41',
 DRAWING='@T6G_MB_LIB.T6G(SCH_1):PAGE388',
 TOLERANCE='20%',
 MATERIAL='X6S',
 PHYS_PAGE='279',
 XY='(-3475,3575)',
 ROT='0',
 VER='1',
 PACK_TYPE='C0402',
 LOCATION='C561',
 CDS_LIB='pure_quanta',
 CDS_PART_NAME='Q_CAP_C0402-10UF,6.3V,20%,X6S,CH6101MEB01',
 VOLTAGE='6.3V',
 PART_NUMBER='CH6101MEB01',
 VALUE='10UF',
 PRIM_FILE='./archive_libs/logical/q_cap/chips/chips.prt';

PART_NAME
 C562 'Q_CAP_0201-1UF,4V,20%,X6S,CH-10KMEE00':;

SECTION_NUMBER 1
 '@T6G_MB_LIB.T6G(SCH_1):PAGE388_I43@PURE_QUANTA.Q_CAP(CHIPS)':
 C_PATH='@t6g_mb_lib.t6g(sch_1):page388_i43@pure_quanta.q_cap(chips)',
 P_PATH='@t6g_mb_lib.t6g(sch_1):page279_i43@pure_quanta.q_cap(chips)',
 PATH='I43',
 DRAWING='@T6G_MB_LIB.T6G(SCH_1):PAGE388',
 TOLERANCE='20%',
 MATERIAL='X6S',
 PHYS_PAGE='279',
 XY='(-3000,2950)',
 ROT='0',
 VER='1',
 PACK_TYPE='0201',
 LOCATION='C562',
 CDS_LIB='pure_quanta',
 CDS_PART_NAME='Q_CAP_0201-1UF,4V,20%,X6S,CH-10KMEE00',
 VOLTAGE='4V',
 PART_NUMBER='CH-10KMEE00',
 VALUE='1UF',
 PRIM_FILE='./archive_libs/logical/q_cap/chips/chips.prt';

PART_NAME
 C563 'Q_CAP_C0402-22UF,4V,20%,X6S,CH622KMEB02':;

SECTION_NUMBER 1
 '@T6G_MB_LIB.T6G(SCH_1):PAGE388_I74@PURE_QUANTA.Q_CAP(CHIPS)':
 C_PATH='@t6g_mb_lib.t6g(sch_1):page388_i74@pure_quanta.q_cap(chips)',
 P_PATH='@t6g_mb_lib.t6g(sch_1):page279_i74@pure_quanta.q_cap(chips)',
 PATH='I74',
 DRAWING='@T6G_MB_LIB.T6G(SCH_1):PAGE388',
 TOLERANCE='20%',
 MATERIAL='X6S',
 PHYS_PAGE='279',
 XY='(-3825,5475)',
 ROT='0',
 VER='1',
 PACK_TYPE='C0402',
 LOCATION='C563',
 CDS_LIB='pure_quanta',
 CDS_PART_NAME='Q_CAP_C0402-22UF,4V,20%,X6S,CH622KMEB02',
 VOLTAGE='4V',
 PART_NUMBER='CH622KMEB02',
 VALUE='22UF',
 PRIM_FILE='./archive_libs/logical/q_cap/chips/chips.prt';

PART_NAME
 C564 'Q_CAP_C0805-100UF,4V,20%,X6S,CH710KMEA01':;

SECTION_NUMBER 1
 '@T6G_MB_LIB.T6G(SCH_1):PAGE388_I71@PURE_QUANTA.Q_CAP(CHIPS)':
 C_PATH='@t6g_mb_lib.t6g(sch_1):page388_i71@pure_quanta.q_cap(chips)',
 P_PATH='@t6g_mb_lib.t6g(sch_1):page279_i71@pure_quanta.q_cap(chips)',
 PATH='I71',
 DRAWING='@T6G_MB_LIB.T6G(SCH_1):PAGE388',
 TOLERANCE='20%',
 MATERIAL='X6S',
 PHYS_PAGE='279',
 XY='(-2800,4200)',
 ROT='0',
 VER='1',
 PACK_TYPE='C0805',
 LOCATION='C564',
 CDS_LIB='pure_quanta',
 CDS_PART_NAME='Q_CAP_C0805-100UF,4V,20%,X6S,CH710KMEA01',
 VOLTAGE='4V',
 PART_NUMBER='CH710KMEA01',
 VALUE='100UF',
 PRIM_FILE='./archive_libs/logical/q_cap/chips/chips.prt';

PART_NAME
 C565 'Q_CAP_C0402-22UF,4V,20%,X6S,CH622KMEB02':;

SECTION_NUMBER 1
 '@T6G_MB_LIB.T6G(SCH_1):PAGE388_I76@PURE_QUANTA.Q_CAP(CHIPS)':
 C_PATH='@t6g_mb_lib.t6g(sch_1):page388_i76@pure_quanta.q_cap(chips)',
 P_PATH='@t6g_mb_lib.t6g(sch_1):page279_i76@pure_quanta.q_cap(chips)',
 PATH='I76',
 DRAWING='@T6G_MB_LIB.T6G(SCH_1):PAGE388',
 TOLERANCE='20%',
 MATERIAL='X6S',
 PHYS_PAGE='279',
 XY='(-2325,4200)',
 ROT='0',
 VER='1',
 PACK_TYPE='C0402',
 LOCATION='C565',
 CDS_LIB='pure_quanta',
 CDS_PART_NAME='Q_CAP_C0402-22UF,4V,20%,X6S,CH622KMEB02',
 VOLTAGE='4V',
 PART_NUMBER='CH622KMEB02',
 VALUE='22UF',
 PRIM_FILE='./archive_libs/logical/q_cap/chips/chips.prt';

PART_NAME
 C566 'Q_CAP_C0201-0.1UF,10V,10%,X7S,CH4102K6E00':;

SECTION_NUMBER 1
 '@T6G_MB_LIB.T6G(SCH_1):PAGE388_I94@PURE_QUANTA.Q_CAP(CHIPS)':
 C_PATH='@t6g_mb_lib.t6g(sch_1):page388_i94@pure_quanta.q_cap(chips)',
 P_PATH='@t6g_mb_lib.t6g(sch_1):page279_i94@pure_quanta.q_cap(chips)',
 PATH='I94',
 DRAWING='@T6G_MB_LIB.T6G(SCH_1):PAGE388',
 TOLERANCE='10%',
 MATERIAL='X7S',
 PHYS_PAGE='279',
 XY='(-1375,2925)',
 ROT='0',
 VER='1',
 PACK_TYPE='C0201',
 LOCATION='C566',
 CDS_LIB='pure_quanta',
 CDS_PART_NAME='Q_CAP_C0201-0.1UF,10V,10%,X7S,CH4102K6E00',
 VOLTAGE='10V',
 PART_NUMBER='CH4102K6E00',
 VALUE='0.1UF',
 PRIM_FILE='./archive_libs/logical/q_cap/chips/chips.prt';

PART_NAME
 C567 'Q_CAP_C0402-10UF,6.3V,20%,X6S,CH6101MEB01':;

SECTION_NUMBER 1
 '@T6G_MB_LIB.T6G(SCH_1):PAGE388_I83@PURE_QUANTA.Q_CAP(CHIPS)':
 C_PATH='@t6g_mb_lib.t6g(sch_1):page388_i83@pure_quanta.q_cap(chips)',
 P_PATH='@t6g_mb_lib.t6g(sch_1):page279_i83@pure_quanta.q_cap(chips)',
 PATH='I83',
 DRAWING='@T6G_MB_LIB.T6G(SCH_1):PAGE388',
 TOLERANCE='20%',
 MATERIAL='X6S',
 PHYS_PAGE='279',
 XY='(-1275,4200)',
 ROT='0',
 VER='1',
 PACK_TYPE='C0402',
 LOCATION='C567',
 CDS_LIB='pure_quanta',
 CDS_PART_NAME='Q_CAP_C0402-10UF,6.3V,20%,X6S,CH6101MEB01',
 VOLTAGE='6.3V',
 PART_NUMBER='CH6101MEB01',
 VALUE='10UF',
 PRIM_FILE='./archive_libs/logical/q_cap/chips/chips.prt';

PART_NAME
 C568 'Q_CAP_C0402-22UF,4V,20%,X6S,CH622KMEB02':;

SECTION_NUMBER 1
 '@T6G_MB_LIB.T6G(SCH_1):PAGE388_I78@PURE_QUANTA.Q_CAP(CHIPS)':
 C_PATH='@t6g_mb_lib.t6g(sch_1):page388_i78@pure_quanta.q_cap(chips)',
 P_PATH='@t6g_mb_lib.t6g(sch_1):page279_i78@pure_quanta.q_cap(chips)',
 PATH='I78',
 DRAWING='@T6G_MB_LIB.T6G(SCH_1):PAGE388',
 TOLERANCE='20%',
 MATERIAL='X6S',
 PHYS_PAGE='279',
 XY='(-1875,4200)',
 ROT='0',
 VER='1',
 PACK_TYPE='C0402',
 LOCATION='C568',
 CDS_LIB='pure_quanta',
 CDS_PART_NAME='Q_CAP_C0402-22UF,4V,20%,X6S,CH622KMEB02',
 VOLTAGE='4V',
 PART_NUMBER='CH622KMEB02',
 VALUE='22UF',
 PRIM_FILE='./archive_libs/logical/q_cap/chips/chips.prt';

PART_NAME
 C569 'Q_CAP_0402-4.7UF,6.3V,20%,X6S,CH5471MEB01':;

SECTION_NUMBER 1
 '@T6G_MB_LIB.T6G(SCH_1):PAGE388_I79@PURE_QUANTA.Q_CAP(CHIPS)':
 C_PATH='@t6g_mb_lib.t6g(sch_1):page388_i79@pure_quanta.q_cap(chips)',
 P_PATH='@t6g_mb_lib.t6g(sch_1):page279_i79@pure_quanta.q_cap(chips)',
 PATH='I79',
 DRAWING='@T6G_MB_LIB.T6G(SCH_1):PAGE388',
 TOLERANCE='20%',
 MATERIAL='X6S',
 PHYS_PAGE='279',
 XY='(-3250,5450)',
 ROT='0',
 VER='1',
 PACK_TYPE='0402',
 LOCATION='C569',
 CDS_LIB='pure_quanta',
 CDS_PART_NAME='Q_CAP_0402-4.7UF,6.3V,20%,X6S,CH5471MEB01',
 VOLTAGE='6.3V',
 PART_NUMBER='CH5471MEB01',
 VALUE='4.7UF',
 PRIM_FILE='./archive_libs/logical/q_cap/chips/chips.prt';

PART_NAME
 C570 'Q_CAP_0201-1UF,4V,20%,X6S,CH-10KMEE00':;

SECTION_NUMBER 1
 '@T6G_MB_LIB.T6G(SCH_1):PAGE388_I52@PURE_QUANTA.Q_CAP(CHIPS)':
 C_PATH='@t6g_mb_lib.t6g(sch_1):page388_i52@pure_quanta.q_cap(chips)',
 P_PATH='@t6g_mb_lib.t6g(sch_1):page279_i52@pure_quanta.q_cap(chips)',
 PATH='I52',
 DRAWING='@T6G_MB_LIB.T6G(SCH_1):PAGE388',
 TOLERANCE='20%',
 MATERIAL='X6S',
 PHYS_PAGE='279',
 XY='(-2725,2950)',
 ROT='0',
 VER='1',
 PACK_TYPE='0201',
 LOCATION='C570',
 CDS_LIB='pure_quanta',
 CDS_PART_NAME='Q_CAP_0201-1UF,4V,20%,X6S,CH-10KMEE00',
 VOLTAGE='4V',
 PART_NUMBER='CH-10KMEE00',
 VALUE='1UF',
 PRIM_FILE='./archive_libs/logical/q_cap/chips/chips.prt';

PART_NAME
 C571 'Q_CAP_0402-4.7UF,6.3V,20%,X6S,CH5471MEB01':;

SECTION_NUMBER 1
 '@T6G_MB_LIB.T6G(SCH_1):PAGE388_I46@PURE_QUANTA.Q_CAP(CHIPS)':
 C_PATH='@t6g_mb_lib.t6g(sch_1):page388_i46@pure_quanta.q_cap(chips)',
 P_PATH='@t6g_mb_lib.t6g(sch_1):page279_i46@pure_quanta.q_cap(chips)',
 PATH='I46',
 DRAWING='@T6G_MB_LIB.T6G(SCH_1):PAGE388',
 TOLERANCE='20%',
 MATERIAL='X6S',
 PHYS_PAGE='279',
 XY='(-2800,3575)',
 ROT='0',
 VER='1',
 PACK_TYPE='0402',
 LOCATION='C571',
 CDS_LIB='pure_quanta',
 CDS_PART_NAME='Q_CAP_0402-4.7UF,6.3V,20%,X6S,CH5471MEB01',
 VOLTAGE='6.3V',
 PART_NUMBER='CH5471MEB01',
 VALUE='4.7UF',
 PRIM_FILE='./archive_libs/logical/q_cap/chips/chips.prt';

PART_NAME
 C572 'Q_CAP_0402-4.7UF,6.3V,20%,X6S,CH5471MEB01':;

SECTION_NUMBER 1
 '@T6G_MB_LIB.T6G(SCH_1):PAGE388_I55@PURE_QUANTA.Q_CAP(CHIPS)':
 C_PATH='@t6g_mb_lib.t6g(sch_1):page388_i55@pure_quanta.q_cap(chips)',
 P_PATH='@t6g_mb_lib.t6g(sch_1):page279_i55@pure_quanta.q_cap(chips)',
 PATH='I55',
 DRAWING='@T6G_MB_LIB.T6G(SCH_1):PAGE388',
 TOLERANCE='20%',
 MATERIAL='X6S',
 PHYS_PAGE='279',
 XY='(-2325,3575)',
 ROT='0',
 VER='1',
 PACK_TYPE='0402',
 LOCATION='C572',
 CDS_LIB='pure_quanta',
 CDS_PART_NAME='Q_CAP_0402-4.7UF,6.3V,20%,X6S,CH5471MEB01',
 VOLTAGE='6.3V',
 PART_NUMBER='CH5471MEB01',
 VALUE='4.7UF',
 PRIM_FILE='./archive_libs/logical/q_cap/chips/chips.prt';

PART_NAME
 C573 'Q_CAP_0201-1UF,4V,20%,X6S,CH-10KMEE00':;

SECTION_NUMBER 1
 '@T6G_MB_LIB.T6G(SCH_1):PAGE388_I53@PURE_QUANTA.Q_CAP(CHIPS)':
 C_PATH='@t6g_mb_lib.t6g(sch_1):page388_i53@pure_quanta.q_cap(chips)',
 P_PATH='@t6g_mb_lib.t6g(sch_1):page279_i53@pure_quanta.q_cap(chips)',
 PATH='I53',
 DRAWING='@T6G_MB_LIB.T6G(SCH_1):PAGE388',
 TOLERANCE='20%',
 MATERIAL='X6S',
 PHYS_PAGE='279',
 XY='(-2450,2950)',
 ROT='0',
 VER='1',
 PACK_TYPE='0201',
 LOCATION='C573',
 CDS_LIB='pure_quanta',
 CDS_PART_NAME='Q_CAP_0201-1UF,4V,20%,X6S,CH-10KMEE00',
 VOLTAGE='4V',
 PART_NUMBER='CH-10KMEE00',
 VALUE='1UF',
 PRIM_FILE='./archive_libs/logical/q_cap/chips/chips.prt';

PART_NAME
 C574 'Q_CAP_C0402-10UF,6.3V,20%,X6S,CH6101MEB01':;

SECTION_NUMBER 1
 '@T6G_MB_LIB.T6G(SCH_1):PAGE388_I73@PURE_QUANTA.Q_CAP(CHIPS)':
 C_PATH='@t6g_mb_lib.t6g(sch_1):page388_i73@pure_quanta.q_cap(chips)',
 P_PATH='@t6g_mb_lib.t6g(sch_1):page279_i73@pure_quanta.q_cap(chips)',
 PATH='I73',
 DRAWING='@T6G_MB_LIB.T6G(SCH_1):PAGE388',
 TOLERANCE='20%',
 MATERIAL='X6S',
 PHYS_PAGE='279',
 XY='(-3525,5450)',
 ROT='0',
 VER='1',
 PACK_TYPE='C0402',
 LOCATION='C574',
 CDS_LIB='pure_quanta',
 CDS_PART_NAME='Q_CAP_C0402-10UF,6.3V,20%,X6S,CH6101MEB01',
 VOLTAGE='6.3V',
 PART_NUMBER='CH6101MEB01',
 VALUE='10UF',
 PRIM_FILE='./archive_libs/logical/q_cap/chips/chips.prt';

PART_NAME
 C575 'Q_CAP_C0402-22UF,4V,20%,X6S,CH622KMEB02':;

SECTION_NUMBER 1
 '@T6G_MB_LIB.T6G(SCH_1):PAGE388_I77@PURE_QUANTA.Q_CAP(CHIPS)':
 C_PATH='@t6g_mb_lib.t6g(sch_1):page388_i77@pure_quanta.q_cap(chips)',
 P_PATH='@t6g_mb_lib.t6g(sch_1):page279_i77@pure_quanta.q_cap(chips)',
 PATH='I77',
 DRAWING='@T6G_MB_LIB.T6G(SCH_1):PAGE388',
 TOLERANCE='20%',
 MATERIAL='X6S',
 PHYS_PAGE='279',
 XY='(-2100,4200)',
 ROT='0',
 VER='1',
 PACK_TYPE='C0402',
 LOCATION='C575',
 CDS_LIB='pure_quanta',
 CDS_PART_NAME='Q_CAP_C0402-22UF,4V,20%,X6S,CH622KMEB02',
 VOLTAGE='4V',
 PART_NUMBER='CH622KMEB02',
 VALUE='22UF',
 PRIM_FILE='./archive_libs/logical/q_cap/chips/chips.prt';

PART_NAME
 C576 'Q_CAP_C0201-0.1UF,10V,10%,X7S,CH4102K6E00':;

SECTION_NUMBER 1
 '@T6G_MB_LIB.T6G(SCH_1):PAGE388_I38@PURE_QUANTA.Q_CAP(CHIPS)':
 C_PATH='@t6g_mb_lib.t6g(sch_1):page388_i38@pure_quanta.q_cap(chips)',
 P_PATH='@t6g_mb_lib.t6g(sch_1):page279_i38@pure_quanta.q_cap(chips)',
 PATH='I38',
 DRAWING='@T6G_MB_LIB.T6G(SCH_1):PAGE388',
 TOLERANCE='10%',
 MATERIAL='X7S',
 PHYS_PAGE='279',
 XY='(-3200,2250)',
 ROT='0',
 VER='1',
 PACK_TYPE='C0201',
 LOCATION='C576',
 CDS_LIB='pure_quanta',
 CDS_PART_NAME='Q_CAP_C0201-0.1UF,10V,10%,X7S,CH4102K6E00',
 VOLTAGE='10V',
 PART_NUMBER='CH4102K6E00',
 VALUE='0.1UF',
 PRIM_FILE='./archive_libs/logical/q_cap/chips/chips.prt';

PART_NAME
 C577 'Q_CAP_0201-1UF,4V,20%,X6S,CH-10KMEE00':;

SECTION_NUMBER 1
 '@T6G_MB_LIB.T6G(SCH_1):PAGE388_I56@PURE_QUANTA.Q_CAP(CHIPS)':
 C_PATH='@t6g_mb_lib.t6g(sch_1):page388_i56@pure_quanta.q_cap(chips)',
 P_PATH='@t6g_mb_lib.t6g(sch_1):page279_i56@pure_quanta.q_cap(chips)',
 PATH='I56',
 DRAWING='@T6G_MB_LIB.T6G(SCH_1):PAGE388',
 TOLERANCE='20%',
 MATERIAL='X6S',
 PHYS_PAGE='279',
 XY='(-2200,2925)',
 ROT='0',
 VER='1',
 PACK_TYPE='0201',
 LOCATION='C577',
 CDS_LIB='pure_quanta',
 CDS_PART_NAME='Q_CAP_0201-1UF,4V,20%,X6S,CH-10KMEE00',
 VOLTAGE='4V',
 PART_NUMBER='CH-10KMEE00',
 VALUE='1UF',
 PRIM_FILE='./archive_libs/logical/q_cap/chips/chips.prt';

PART_NAME
 C578 'Q_CAP_C0201-0.1UF,10V,10%,X7S,CH4102K6E00':;

SECTION_NUMBER 1
 '@T6G_MB_LIB.T6G(SCH_1):PAGE388_I85@PURE_QUANTA.Q_CAP(CHIPS)':
 C_PATH='@t6g_mb_lib.t6g(sch_1):page388_i85@pure_quanta.q_cap(chips)',
 P_PATH='@t6g_mb_lib.t6g(sch_1):page279_i85@pure_quanta.q_cap(chips)',
 PATH='I85',
 DRAWING='@T6G_MB_LIB.T6G(SCH_1):PAGE388',
 TOLERANCE='10%',
 MATERIAL='X7S',
 PHYS_PAGE='279',
 XY='(-2050,5450)',
 ROT='0',
 VER='1',
 PACK_TYPE='C0201',
 LOCATION='C578',
 CDS_LIB='pure_quanta',
 CDS_PART_NAME='Q_CAP_C0201-0.1UF,10V,10%,X7S,CH4102K6E00',
 VOLTAGE='10V',
 PART_NUMBER='CH4102K6E00',
 VALUE='0.1UF',
 PRIM_FILE='./archive_libs/logical/q_cap/chips/chips.prt';

PART_NAME
 C579 'Q_CAP_C0402-10UF,6.3V,20%,X6S,CH6101MEB01':;

SECTION_NUMBER 1
 '@T6G_MB_LIB.T6G(SCH_1):PAGE388_I44@PURE_QUANTA.Q_CAP(CHIPS)':
 C_PATH='@t6g_mb_lib.t6g(sch_1):page388_i44@pure_quanta.q_cap(chips)',
 P_PATH='@t6g_mb_lib.t6g(sch_1):page279_i44@pure_quanta.q_cap(chips)',
 PATH='I44',
 DRAWING='@T6G_MB_LIB.T6G(SCH_1):PAGE388',
 TOLERANCE='20%',
 MATERIAL='X6S',
 PHYS_PAGE='279',
 XY='(-3250,3575)',
 ROT='0',
 VER='1',
 PACK_TYPE='C0402',
 LOCATION='C579',
 CDS_LIB='pure_quanta',
 CDS_PART_NAME='Q_CAP_C0402-10UF,6.3V,20%,X6S,CH6101MEB01',
 VOLTAGE='6.3V',
 PART_NUMBER='CH6101MEB01',
 VALUE='10UF',
 PRIM_FILE='./archive_libs/logical/q_cap/chips/chips.prt';

PART_NAME
 C580 'Q_CAP_C0201-0.1UF,10V,10%,X7S,CH4102K6E00':;

SECTION_NUMBER 1
 '@T6G_MB_LIB.T6G(SCH_1):PAGE388_I39@PURE_QUANTA.Q_CAP(CHIPS)':
 C_PATH='@t6g_mb_lib.t6g(sch_1):page388_i39@pure_quanta.q_cap(chips)',
 P_PATH='@t6g_mb_lib.t6g(sch_1):page279_i39@pure_quanta.q_cap(chips)',
 PATH='I39',
 DRAWING='@T6G_MB_LIB.T6G(SCH_1):PAGE388',
 TOLERANCE='10%',
 MATERIAL='X7S',
 PHYS_PAGE='279',
 XY='(-2900,2250)',
 ROT='0',
 VER='1',
 PACK_TYPE='C0201',
 LOCATION='C580',
 CDS_LIB='pure_quanta',
 CDS_PART_NAME='Q_CAP_C0201-0.1UF,10V,10%,X7S,CH4102K6E00',
 VOLTAGE='10V',
 PART_NUMBER='CH4102K6E00',
 VALUE='0.1UF',
 PRIM_FILE='./archive_libs/logical/q_cap/chips/chips.prt';

PART_NAME
 C581 'Q_CAP_0201-1UF,4V,20%,X6S,CH-10KMEE00':;

SECTION_NUMBER 1
 '@T6G_MB_LIB.T6G(SCH_1):PAGE388_I57@PURE_QUANTA.Q_CAP(CHIPS)':
 C_PATH='@t6g_mb_lib.t6g(sch_1):page388_i57@pure_quanta.q_cap(chips)',
 P_PATH='@t6g_mb_lib.t6g(sch_1):page279_i57@pure_quanta.q_cap(chips)',
 PATH='I57',
 DRAWING='@T6G_MB_LIB.T6G(SCH_1):PAGE388',
 TOLERANCE='20%',
 MATERIAL='X6S',
 PHYS_PAGE='279',
 XY='(-1925,2925)',
 ROT='0',
 VER='1',
 PACK_TYPE='0201',
 LOCATION='C581',
 CDS_LIB='pure_quanta',
 CDS_PART_NAME='Q_CAP_0201-1UF,4V,20%,X6S,CH-10KMEE00',
 VOLTAGE='4V',
 PART_NUMBER='CH-10KMEE00',
 VALUE='1UF',
 PRIM_FILE='./archive_libs/logical/q_cap/chips/chips.prt';

PART_NAME
 C582 'Q_CAP_C0201-0.1UF,10V,10%,X7S,CH4102K6E00':;

SECTION_NUMBER 1
 '@T6G_MB_LIB.T6G(SCH_1):PAGE388_I49@PURE_QUANTA.Q_CAP(CHIPS)':
 C_PATH='@t6g_mb_lib.t6g(sch_1):page388_i49@pure_quanta.q_cap(chips)',
 P_PATH='@t6g_mb_lib.t6g(sch_1):page279_i49@pure_quanta.q_cap(chips)',
 PATH='I49',
 DRAWING='@T6G_MB_LIB.T6G(SCH_1):PAGE388',
 TOLERANCE='10%',
 MATERIAL='X7S',
 PHYS_PAGE='279',
 XY='(-2425,2250)',
 ROT='0',
 VER='1',
 PACK_TYPE='C0201',
 LOCATION='C582',
 CDS_LIB='pure_quanta',
 CDS_PART_NAME='Q_CAP_C0201-0.1UF,10V,10%,X7S,CH4102K6E00',
 VOLTAGE='10V',
 PART_NUMBER='CH4102K6E00',
 VALUE='0.1UF',
 PRIM_FILE='./archive_libs/logical/q_cap/chips/chips.prt';

PART_NAME
 C583 'Q_CAP_C0201-0.1UF,10V,10%,X7S,CH4102K6E00':;

SECTION_NUMBER 1
 '@T6G_MB_LIB.T6G(SCH_1):PAGE388_I93@PURE_QUANTA.Q_CAP(CHIPS)':
 C_PATH='@t6g_mb_lib.t6g(sch_1):page388_i93@pure_quanta.q_cap(chips)',
 P_PATH='@t6g_mb_lib.t6g(sch_1):page279_i93@pure_quanta.q_cap(chips)',
 PATH='I93',
 DRAWING='@T6G_MB_LIB.T6G(SCH_1):PAGE388',
 TOLERANCE='10%',
 MATERIAL='X7S',
 PHYS_PAGE='279',
 XY='(-1675,2925)',
 ROT='0',
 VER='1',
 PACK_TYPE='C0201',
 LOCATION='C583',
 CDS_LIB='pure_quanta',
 CDS_PART_NAME='Q_CAP_C0201-0.1UF,10V,10%,X7S,CH4102K6E00',
 VOLTAGE='10V',
 PART_NUMBER='CH4102K6E00',
 VALUE='0.1UF',
 PRIM_FILE='./archive_libs/logical/q_cap/chips/chips.prt';

PART_NAME
 C584 'Q_CAP_C0402-10UF,6.3V,20%,X6S,CH6101MEB01':;

SECTION_NUMBER 1
 '@T6G_MB_LIB.T6G(SCH_1):PAGE388_I82@PURE_QUANTA.Q_CAP(CHIPS)':
 C_PATH='@t6g_mb_lib.t6g(sch_1):page388_i82@pure_quanta.q_cap(chips)',
 P_PATH='@t6g_mb_lib.t6g(sch_1):page279_i82@pure_quanta.q_cap(chips)',
 PATH='I82',
 DRAWING='@T6G_MB_LIB.T6G(SCH_1):PAGE388',
 TOLERANCE='20%',
 MATERIAL='X6S',
 PHYS_PAGE='279',
 XY='(-1575,4200)',
 ROT='0',
 VER='1',
 PACK_TYPE='C0402',
 LOCATION='C584',
 CDS_LIB='pure_quanta',
 CDS_PART_NAME='Q_CAP_C0402-10UF,6.3V,20%,X6S,CH6101MEB01',
 VOLTAGE='6.3V',
 PART_NUMBER='CH6101MEB01',
 VALUE='10UF',
 PRIM_FILE='./archive_libs/logical/q_cap/chips/chips.prt';

PART_NAME
 C585 'Q_CAP_C0201-0.1UF,10V,10%,X7S,CH4102K6E00':;

SECTION_NUMBER 1
 '@T6G_MB_LIB.T6G(SCH_1):PAGE388_I51@PURE_QUANTA.Q_CAP(CHIPS)':
 C_PATH='@t6g_mb_lib.t6g(sch_1):page388_i51@pure_quanta.q_cap(chips)',
 P_PATH='@t6g_mb_lib.t6g(sch_1):page279_i51@pure_quanta.q_cap(chips)',
 PATH='I51',
 DRAWING='@T6G_MB_LIB.T6G(SCH_1):PAGE388',
 TOLERANCE='10%',
 MATERIAL='X7S',
 PHYS_PAGE='279',
 XY='(-1900,2250)',
 ROT='0',
 VER='1',
 PACK_TYPE='C0201',
 LOCATION='C585',
 CDS_LIB='pure_quanta',
 CDS_PART_NAME='Q_CAP_C0201-0.1UF,10V,10%,X7S,CH4102K6E00',
 VOLTAGE='10V',
 PART_NUMBER='CH4102K6E00',
 VALUE='0.1UF',
 PRIM_FILE='./archive_libs/logical/q_cap/chips/chips.prt';

PART_NAME
 C586 'Q_CAP_C0402-22UF,4V,20%,X6S,CH622KMEB02':;

SECTION_NUMBER 1
 '@T6G_MB_LIB.T6G(SCH_1):PAGE388_I75@PURE_QUANTA.Q_CAP(CHIPS)':
 C_PATH='@t6g_mb_lib.t6g(sch_1):page388_i75@pure_quanta.q_cap(chips)',
 P_PATH='@t6g_mb_lib.t6g(sch_1):page279_i75@pure_quanta.q_cap(chips)',
 PATH='I75',
 DRAWING='@T6G_MB_LIB.T6G(SCH_1):PAGE388',
 TOLERANCE='20%',
 MATERIAL='X6S',
 PHYS_PAGE='279',
 XY='(-2550,4200)',
 ROT='0',
 VER='1',
 PACK_TYPE='C0402',
 LOCATION='C586',
 CDS_LIB='pure_quanta',
 CDS_PART_NAME='Q_CAP_C0402-22UF,4V,20%,X6S,CH622KMEB02',
 VOLTAGE='4V',
 PART_NUMBER='CH622KMEB02',
 VALUE='22UF',
 PRIM_FILE='./archive_libs/logical/q_cap/chips/chips.prt';

PART_NAME
 C587 'Q_CAP_C0805-100UF,4V,20%,X6S,CH710KMEA01':;

SECTION_NUMBER 1
 '@T6G_MB_LIB.T6G(SCH_1):PAGE411_I17@PURE_QUANTA.Q_CAP(CHIPS)':
 C_PATH='@t6g_mb_lib.t6g(sch_1):page411_i17@pure_quanta.q_cap(chips)',
 P_PATH='@t6g_mb_lib.t6g(sch_1):page290_i17@pure_quanta.q_cap(chips)',
 PATH='I17',
 DRAWING='@T6G_MB_LIB.T6G(SCH_1):PAGE411',
 TOLERANCE='20%',
 MATERIAL='X6S',
 PHYS_PAGE='290',
 XY='(-7225,4725)',
 ROT='0',
 VER='1',
 PACK_TYPE='C0805',
 LOCATION='C587',
 CDS_LIB='pure_quanta',
 CDS_PART_NAME='Q_CAP_C0805-100UF,4V,20%,X6S,CH710KMEA01',
 VOLTAGE='4V',
 PART_NUMBER='CH710KMEA01',
 VALUE='100UF',
 PRIM_FILE='./archive_libs/logical/q_cap/chips/chips.prt';

PART_NAME
 C588 'Q_CAP_C0805-100UF,4V,20%,X6S,CH710KMEA01':;

SECTION_NUMBER 1
 '@T6G_MB_LIB.T6G(SCH_1):PAGE411_I12@PURE_QUANTA.Q_CAP(CHIPS)':
 C_PATH='@t6g_mb_lib.t6g(sch_1):page411_i12@pure_quanta.q_cap(chips)',
 P_PATH='@t6g_mb_lib.t6g(sch_1):page290_i12@pure_quanta.q_cap(chips)',
 PATH='I12',
 DRAWING='@T6G_MB_LIB.T6G(SCH_1):PAGE411',
 TOLERANCE='20%',
 MATERIAL='X6S',
 PHYS_PAGE='290',
 XY='(-7375,3900)',
 ROT='0',
 VER='1',
 PACK_TYPE='C0805',
 LOCATION='C588',
 CDS_LIB='pure_quanta',
 CDS_PART_NAME='Q_CAP_C0805-100UF,4V,20%,X6S,CH710KMEA01',
 VOLTAGE='4V',
 PART_NUMBER='CH710KMEA01',
 VALUE='100UF',
 PRIM_FILE='./archive_libs/logical/q_cap/chips/chips.prt';

PART_NAME
 C589 'Q_CAP_C0402-22UF,4V,20%,X6S,CH622KMEB02':;

SECTION_NUMBER 1
 '@T6G_MB_LIB.T6G(SCH_1):PAGE411_I18@PURE_QUANTA.Q_CAP(CHIPS)':
 C_PATH='@t6g_mb_lib.t6g(sch_1):page411_i18@pure_quanta.q_cap(chips)',
 P_PATH='@t6g_mb_lib.t6g(sch_1):page290_i18@pure_quanta.q_cap(chips)',
 PATH='I18',
 DRAWING='@T6G_MB_LIB.T6G(SCH_1):PAGE411',
 TOLERANCE='20%',
 MATERIAL='X6S',
 PHYS_PAGE='290',
 XY='(-6975,4725)',
 ROT='0',
 VER='1',
 PACK_TYPE='C0402',
 LOCATION='C589',
 CDS_LIB='pure_quanta',
 CDS_PART_NAME='Q_CAP_C0402-22UF,4V,20%,X6S,CH622KMEB02',
 VOLTAGE='4V',
 PART_NUMBER='CH622KMEB02',
 VALUE='22UF',
 PRIM_FILE='./archive_libs/logical/q_cap/chips/chips.prt';

PART_NAME
 C590 'Q_CAP_C0402-22UF,4V,20%,X6S,CH622KMEB02':;

SECTION_NUMBER 1
 '@T6G_MB_LIB.T6G(SCH_1):PAGE411_I15@PURE_QUANTA.Q_CAP(CHIPS)':
 C_PATH='@t6g_mb_lib.t6g(sch_1):page411_i15@pure_quanta.q_cap(chips)',
 P_PATH='@t6g_mb_lib.t6g(sch_1):page290_i15@pure_quanta.q_cap(chips)',
 PATH='I15',
 DRAWING='@T6G_MB_LIB.T6G(SCH_1):PAGE411',
 TOLERANCE='20%',
 MATERIAL='X6S',
 PHYS_PAGE='290',
 XY='(-7150,3900)',
 ROT='0',
 VER='1',
 PACK_TYPE='C0402',
 LOCATION='C590',
 CDS_LIB='pure_quanta',
 CDS_PART_NAME='Q_CAP_C0402-22UF,4V,20%,X6S,CH622KMEB02',
 VOLTAGE='4V',
 PART_NUMBER='CH622KMEB02',
 VALUE='22UF',
 PRIM_FILE='./archive_libs/logical/q_cap/chips/chips.prt';

PART_NAME
 C591 'Q_CAP_C0402-10UF,6.3V,20%,X6S,CH6101MEB01':;

SECTION_NUMBER 1
 '@T6G_MB_LIB.T6G(SCH_1):PAGE411_I22@PURE_QUANTA.Q_CAP(CHIPS)':
 C_PATH='@t6g_mb_lib.t6g(sch_1):page411_i22@pure_quanta.q_cap(chips)',
 P_PATH='@t6g_mb_lib.t6g(sch_1):page290_i22@pure_quanta.q_cap(chips)',
 PATH='I22',
 DRAWING='@T6G_MB_LIB.T6G(SCH_1):PAGE411',
 TOLERANCE='20%',
 MATERIAL='X6S',
 PHYS_PAGE='290',
 XY='(-6725,4700)',
 ROT='0',
 VER='1',
 PACK_TYPE='C0402',
 LOCATION='C591',
 CDS_LIB='pure_quanta',
 CDS_PART_NAME='Q_CAP_C0402-10UF,6.3V,20%,X6S,CH6101MEB01',
 VOLTAGE='6.3V',
 PART_NUMBER='CH6101MEB01',
 VALUE='10UF',
 PRIM_FILE='./archive_libs/logical/q_cap/chips/chips.prt';

PART_NAME
 C592 'Q_CAP_0402-0.1UF,25V,10%,X7R,CH4104K1B00':;

SECTION_NUMBER 1
 '@T6G_MB_LIB.T6G(SCH_1):PAGE338_I33@PURE_QUANTA.Q_CAP(CHIPS)':
 C_PATH='@t6g_mb_lib.t6g(sch_1):page338_i33@pure_quanta.q_cap(chips)',
 P_PATH='@t6g_mb_lib.t6g(sch_1):page134_i33@pure_quanta.q_cap(chips)',
 PATH='I33',
 DRAWING='@T6G_MB_LIB.T6G(SCH_1):PAGE338',
 TOLERANCE='10%',
 MATERIAL='X7R',
 PHYS_PAGE='134',
 XY='(5950,9275)',
 ROT='0',
 VER='1',
 PACK_TYPE='0402',
 LOCATION='C592',
 CDS_LIB='pure_quanta',
 CDS_PART_NAME='Q_CAP_0402-0.1UF,25V,10%,X7R,CH4104K1B00',
 VOLTAGE='25V',
 PART_NUMBER='CH4104K1B00',
 VALUE='0.1UF',
 PRIM_FILE='./archive_libs/logical/q_cap/chips/chips.prt';

PART_NAME
 C593 'Q_CAP_0402-0.1UF,25V,10%,X7R,CH4104K1B00':;

SECTION_NUMBER 1
 '@T6G_MB_LIB.T6G(SCH_1):PAGE338_I30@PURE_QUANTA.Q_CAP(CHIPS)':
 C_PATH='@t6g_mb_lib.t6g(sch_1):page338_i30@pure_quanta.q_cap(chips)',
 P_PATH='@t6g_mb_lib.t6g(sch_1):page134_i30@pure_quanta.q_cap(chips)',
 PATH='I30',
 DRAWING='@T6G_MB_LIB.T6G(SCH_1):PAGE338',
 TOLERANCE='10%',
 MATERIAL='X7R',
 PHYS_PAGE='134',
 XY='(5950,8375)',
 ROT='0',
 VER='1',
 PACK_TYPE='0402',
 LOCATION='C593',
 CDS_LIB='pure_quanta',
 CDS_PART_NAME='Q_CAP_0402-0.1UF,25V,10%,X7R,CH4104K1B00',
 VOLTAGE='25V',
 PART_NUMBER='CH4104K1B00',
 VALUE='0.1UF',
 PRIM_FILE='./archive_libs/logical/q_cap/chips/chips.prt';

PART_NAME
 C594 'Q_CAP_0402-4.7UF,6.3V,20%,X6S,CH5471MEB01':;

SECTION_NUMBER 1
 '@T6G_MB_LIB.T6G(SCH_1):PAGE411_I19@PURE_QUANTA.Q_CAP(CHIPS)':
 C_PATH='@t6g_mb_lib.t6g(sch_1):page411_i19@pure_quanta.q_cap(chips)',
 P_PATH='@t6g_mb_lib.t6g(sch_1):page290_i19@pure_quanta.q_cap(chips)',
 PATH='I19',
 DRAWING='@T6G_MB_LIB.T6G(SCH_1):PAGE411',
 TOLERANCE='20%',
 MATERIAL='X6S',
 PHYS_PAGE='290',
 XY='(-6750,3900)',
 ROT='0',
 VER='1',
 PACK_TYPE='0402',
 LOCATION='C594',
 CDS_LIB='pure_quanta',
 CDS_PART_NAME='Q_CAP_0402-4.7UF,6.3V,20%,X6S,CH5471MEB01',
 VOLTAGE='6.3V',
 PART_NUMBER='CH5471MEB01',
 VALUE='4.7UF',
 PRIM_FILE='./archive_libs/logical/q_cap/chips/chips.prt';

PART_NAME
 C595 'Q_CAP_C0402-10UF,6.3V,20%,X6S,CH6101MEB01':;

SECTION_NUMBER 1
 '@T6G_MB_LIB.T6G(SCH_1):PAGE411_I16@PURE_QUANTA.Q_CAP(CHIPS)':
 C_PATH='@t6g_mb_lib.t6g(sch_1):page411_i16@pure_quanta.q_cap(chips)',
 P_PATH='@t6g_mb_lib.t6g(sch_1):page290_i16@pure_quanta.q_cap(chips)',
 PATH='I16',
 DRAWING='@T6G_MB_LIB.T6G(SCH_1):PAGE411',
 TOLERANCE='20%',
 MATERIAL='X6S',
 PHYS_PAGE='290',
 XY='(-6950,3900)',
 ROT='0',
 VER='1',
 PACK_TYPE='C0402',
 LOCATION='C595',
 CDS_LIB='pure_quanta',
 CDS_PART_NAME='Q_CAP_C0402-10UF,6.3V,20%,X6S,CH6101MEB01',
 VOLTAGE='6.3V',
 PART_NUMBER='CH6101MEB01',
 VALUE='10UF',
 PRIM_FILE='./archive_libs/logical/q_cap/chips/chips.prt';

PART_NAME
 C596 'Q_CAP_0402-4.7UF,6.3V,20%,X6S,CH5471MEB01':;

SECTION_NUMBER 1
 '@T6G_MB_LIB.T6G(SCH_1):PAGE411_I24@PURE_QUANTA.Q_CAP(CHIPS)':
 C_PATH='@t6g_mb_lib.t6g(sch_1):page411_i24@pure_quanta.q_cap(chips)',
 P_PATH='@t6g_mb_lib.t6g(sch_1):page290_i24@pure_quanta.q_cap(chips)',
 PATH='I24',
 DRAWING='@T6G_MB_LIB.T6G(SCH_1):PAGE411',
 TOLERANCE='20%',
 MATERIAL='X6S',
 PHYS_PAGE='290',
 XY='(-6475,4700)',
 ROT='0',
 VER='1',
 PACK_TYPE='0402',
 LOCATION='C596',
 CDS_LIB='pure_quanta',
 CDS_PART_NAME='Q_CAP_0402-4.7UF,6.3V,20%,X6S,CH5471MEB01',
 VOLTAGE='6.3V',
 PART_NUMBER='CH5471MEB01',
 VALUE='4.7UF',
 PRIM_FILE='./archive_libs/logical/q_cap/chips/chips.prt';

PART_NAME
 C597 'Q_CAP_0201-1UF,4V,20%,X6S,CH-10KMEE00':;

SECTION_NUMBER 1
 '@T6G_MB_LIB.T6G(SCH_1):PAGE411_I20@PURE_QUANTA.Q_CAP(CHIPS)':
 C_PATH='@t6g_mb_lib.t6g(sch_1):page411_i20@pure_quanta.q_cap(chips)',
 P_PATH='@t6g_mb_lib.t6g(sch_1):page290_i20@pure_quanta.q_cap(chips)',
 PATH='I20',
 DRAWING='@T6G_MB_LIB.T6G(SCH_1):PAGE411',
 TOLERANCE='20%',
 MATERIAL='X6S',
 PHYS_PAGE='290',
 XY='(-6525,3900)',
 ROT='0',
 VER='1',
 PACK_TYPE='0201',
 LOCATION='C597',
 CDS_LIB='pure_quanta',
 CDS_PART_NAME='Q_CAP_0201-1UF,4V,20%,X6S,CH-10KMEE00',
 VOLTAGE='4V',
 PART_NUMBER='CH-10KMEE00',
 VALUE='1UF',
 PRIM_FILE='./archive_libs/logical/q_cap/chips/chips.prt';

PART_NAME
 C598 'Q_CAP_0201-1UF,4V,20%,X6S,CH-10KMEE00':;

SECTION_NUMBER 1
 '@T6G_MB_LIB.T6G(SCH_1):PAGE411_I5@PURE_QUANTA.Q_CAP(CHIPS)':
 C_PATH='@t6g_mb_lib.t6g(sch_1):page411_i5@pure_quanta.q_cap(chips)',
 P_PATH='@t6g_mb_lib.t6g(sch_1):page290_i5@pure_quanta.q_cap(chips)',
 PATH='I5',
 DRAWING='@T6G_MB_LIB.T6G(SCH_1):PAGE411',
 TOLERANCE='20%',
 MATERIAL='X6S',
 PHYS_PAGE='290',
 XY='(-6950,2825)',
 ROT='0',
 VER='1',
 PACK_TYPE='0201',
 LOCATION='C598',
 CDS_LIB='pure_quanta',
 CDS_PART_NAME='Q_CAP_0201-1UF,4V,20%,X6S,CH-10KMEE00',
 VOLTAGE='4V',
 PART_NUMBER='CH-10KMEE00',
 VALUE='1UF',
 PRIM_FILE='./archive_libs/logical/q_cap/chips/chips.prt';

PART_NAME
 C599 'Q_CAP_0201-1UF,4V,20%,X6S,CH-10KMEE00':;

SECTION_NUMBER 1
 '@T6G_MB_LIB.T6G(SCH_1):PAGE411_I21@PURE_QUANTA.Q_CAP(CHIPS)':
 C_PATH='@t6g_mb_lib.t6g(sch_1):page411_i21@pure_quanta.q_cap(chips)',
 P_PATH='@t6g_mb_lib.t6g(sch_1):page290_i21@pure_quanta.q_cap(chips)',
 PATH='I21',
 DRAWING='@T6G_MB_LIB.T6G(SCH_1):PAGE411',
 TOLERANCE='20%',
 MATERIAL='X6S',
 PHYS_PAGE='290',
 XY='(-6325,3900)',
 ROT='0',
 VER='1',
 PACK_TYPE='0201',
 LOCATION='C599',
 CDS_LIB='pure_quanta',
 CDS_PART_NAME='Q_CAP_0201-1UF,4V,20%,X6S,CH-10KMEE00',
 VOLTAGE='4V',
 PART_NUMBER='CH-10KMEE00',
 VALUE='1UF',
 PRIM_FILE='./archive_libs/logical/q_cap/chips/chips.prt';

PART_NAME
 C600 'Q_CAP_C0201-0.1UF,10V,10%,X7S,CH4102K6E00':;

SECTION_NUMBER 1
 '@T6G_MB_LIB.T6G(SCH_1):PAGE411_I25@PURE_QUANTA.Q_CAP(CHIPS)':
 C_PATH='@t6g_mb_lib.t6g(sch_1):page411_i25@pure_quanta.q_cap(chips)',
 P_PATH='@t6g_mb_lib.t6g(sch_1):page290_i25@pure_quanta.q_cap(chips)',
 PATH='I25',
 DRAWING='@T6G_MB_LIB.T6G(SCH_1):PAGE411',
 TOLERANCE='10%',
 MATERIAL='X7S',
 PHYS_PAGE='290',
 XY='(-6100,3900)',
 ROT='0',
 VER='1',
 PACK_TYPE='C0201',
 LOCATION='C600',
 CDS_LIB='pure_quanta',
 CDS_PART_NAME='Q_CAP_C0201-0.1UF,10V,10%,X7S,CH4102K6E00',
 VOLTAGE='10V',
 PART_NUMBER='CH4102K6E00',
 VALUE='0.1UF',
 PRIM_FILE='./archive_libs/logical/q_cap/chips/chips.prt';

PART_NAME
 C601 'Q_CAP_C0201-0.1UF,10V,10%,X7S,CH4102K6E00':;

SECTION_NUMBER 1
 '@T6G_MB_LIB.T6G(SCH_1):PAGE411_I7@PURE_QUANTA.Q_CAP(CHIPS)':
 C_PATH='@t6g_mb_lib.t6g(sch_1):page411_i7@pure_quanta.q_cap(chips)',
 P_PATH='@t6g_mb_lib.t6g(sch_1):page290_i7@pure_quanta.q_cap(chips)',
 PATH='I7',
 DRAWING='@T6G_MB_LIB.T6G(SCH_1):PAGE411',
 TOLERANCE='10%',
 MATERIAL='X7S',
 PHYS_PAGE='290',
 XY='(-6675,2800)',
 ROT='0',
 VER='1',
 PACK_TYPE='C0201',
 LOCATION='C601',
 CDS_LIB='pure_quanta',
 CDS_PART_NAME='Q_CAP_C0201-0.1UF,10V,10%,X7S,CH4102K6E00',
 VOLTAGE='10V',
 PART_NUMBER='CH4102K6E00',
 VALUE='0.1UF',
 PRIM_FILE='./archive_libs/logical/q_cap/chips/chips.prt';

PART_NAME
 C602 'Q_CAP_C0201-0.1UF,10V,10%,X7S,CH4102K6E00':;

SECTION_NUMBER 1
 '@T6G_MB_LIB.T6G(SCH_1):PAGE411_I26@PURE_QUANTA.Q_CAP(CHIPS)':
 C_PATH='@t6g_mb_lib.t6g(sch_1):page411_i26@pure_quanta.q_cap(chips)',
 P_PATH='@t6g_mb_lib.t6g(sch_1):page290_i26@pure_quanta.q_cap(chips)',
 PATH='I26',
 DRAWING='@T6G_MB_LIB.T6G(SCH_1):PAGE411',
 TOLERANCE='10%',
 MATERIAL='X7S',
 PHYS_PAGE='290',
 XY='(-5850,3900)',
 ROT='0',
 VER='1',
 PACK_TYPE='C0201',
 LOCATION='C602',
 CDS_LIB='pure_quanta',
 CDS_PART_NAME='Q_CAP_C0201-0.1UF,10V,10%,X7S,CH4102K6E00',
 VOLTAGE='10V',
 PART_NUMBER='CH4102K6E00',
 VALUE='0.1UF',
 PRIM_FILE='./archive_libs/logical/q_cap/chips/chips.prt';

PART_NAME
 C603 'Q_CAP_C0201-0.1UF,10V,10%,X7S,CH4102K6E00':;

SECTION_NUMBER 1
 '@T6G_MB_LIB.T6G(SCH_1):PAGE411_I27@PURE_QUANTA.Q_CAP(CHIPS)':
 C_PATH='@t6g_mb_lib.t6g(sch_1):page411_i27@pure_quanta.q_cap(chips)',
 P_PATH='@t6g_mb_lib.t6g(sch_1):page290_i27@pure_quanta.q_cap(chips)',
 PATH='I27',
 DRAWING='@T6G_MB_LIB.T6G(SCH_1):PAGE411',
 TOLERANCE='10%',
 MATERIAL='X7S',
 PHYS_PAGE='290',
 XY='(-5600,3900)',
 ROT='0',
 VER='1',
 PACK_TYPE='C0201',
 LOCATION='C603',
 CDS_LIB='pure_quanta',
 CDS_PART_NAME='Q_CAP_C0201-0.1UF,10V,10%,X7S,CH4102K6E00',
 VOLTAGE='10V',
 PART_NUMBER='CH4102K6E00',
 VALUE='0.1UF',
 PRIM_FILE='./archive_libs/logical/q_cap/chips/chips.prt';

PART_NAME
 C604 'Q_CAP_C0402-0.001UF,50V,10%,X7R,CH30106KB19':;

SECTION_NUMBER 1
 '@T6G_MB_LIB.T6G(SCH_1):PAGE149_I140@PURE_QUANTA.Q_CAP(CHIPS)':
 C_PATH='@t6g_mb_lib.t6g(sch_1):page149_i140@pure_quanta.q_cap(chips)',
 P_PATH='@t6g_mb_lib.t6g(sch_1):page172_i140@pure_quanta.q_cap(chips)',
 PATH='I140',
 DRAWING='@T6G_MB_LIB.T6G(SCH_1):PAGE149',
 TOLERANCE='10%',
 MATERIAL='X7R',
 PHYS_PAGE='172',
 XY='(-2800,5325)',
 ROT='0',
 VER='1',
 PACK_TYPE='C0402',
 LOCATION='C604',
 CDS_LIB='pure_quanta',
 CDS_PART_NAME='Q_CAP_C0402-0.001UF,50V,10%,X7R,CH30106KB19',
 VOLTAGE='50V',
 PART_NUMBER='CH30106KB19',
 VALUE='0.001UF',
 PRIM_FILE='./archive_libs/logical/q_cap/chips/chips.prt';

PART_NAME
 C605 'Q_CAP_C0402-0.001UF,50V,10%,X7R,CH30106KB19':;

SECTION_NUMBER 1
 '@T6G_MB_LIB.T6G(SCH_1):PAGE149_I137@PURE_QUANTA.Q_CAP(CHIPS)':
 C_PATH='@t6g_mb_lib.t6g(sch_1):page149_i137@pure_quanta.q_cap(chips)',
 P_PATH='@t6g_mb_lib.t6g(sch_1):page172_i137@pure_quanta.q_cap(chips)',
 PATH='I137',
 DRAWING='@T6G_MB_LIB.T6G(SCH_1):PAGE149',
 TOLERANCE='10%',
 MATERIAL='X7R',
 PHYS_PAGE='172',
 XY='(-2575,5325)',
 ROT='0',
 VER='1',
 PACK_TYPE='C0402',
 LOCATION='C605',
 CDS_LIB='pure_quanta',
 CDS_PART_NAME='Q_CAP_C0402-0.001UF,50V,10%,X7R,CH30106KB19',
 VOLTAGE='50V',
 PART_NUMBER='CH30106KB19',
 VALUE='0.001UF',
 PRIM_FILE='./archive_libs/logical/q_cap/chips/chips.prt';

PART_NAME
 C606 'Q_CAP_C0201-0.1UF,10V,10%,X7S,CH4102K6E00':;

SECTION_NUMBER 1
 '@T6G_MB_LIB.T6G(SCH_1):PAGE411_I28@PURE_QUANTA.Q_CAP(CHIPS)':
 C_PATH='@t6g_mb_lib.t6g(sch_1):page411_i28@pure_quanta.q_cap(chips)',
 P_PATH='@t6g_mb_lib.t6g(sch_1):page290_i28@pure_quanta.q_cap(chips)',
 PATH='I28',
 DRAWING='@T6G_MB_LIB.T6G(SCH_1):PAGE411',
 TOLERANCE='10%',
 MATERIAL='X7S',
 PHYS_PAGE='290',
 XY='(-5325,3900)',
 ROT='0',
 VER='1',
 PACK_TYPE='C0201',
 LOCATION='C606',
 CDS_LIB='pure_quanta',
 CDS_PART_NAME='Q_CAP_C0201-0.1UF,10V,10%,X7S,CH4102K6E00',
 VOLTAGE='10V',
 PART_NUMBER='CH4102K6E00',
 VALUE='0.1UF',
 PRIM_FILE='./archive_libs/logical/q_cap/chips/chips.prt';

PART_NAME
 C607 'Q_CAP_0201-1UF,4V,20%,X6S,CH-10KMEE00':;

SECTION_NUMBER 1
 '@T6G_MB_LIB.T6G(SCH_1):PAGE411_I44@PURE_QUANTA.Q_CAP(CHIPS)':
 C_PATH='@t6g_mb_lib.t6g(sch_1):page411_i44@pure_quanta.q_cap(chips)',
 P_PATH='@t6g_mb_lib.t6g(sch_1):page290_i44@pure_quanta.q_cap(chips)',
 PATH='I44',
 DRAWING='@T6G_MB_LIB.T6G(SCH_1):PAGE411',
 TOLERANCE='20%',
 MATERIAL='X6S',
 PHYS_PAGE='290',
 XY='(-3175,2650)',
 ROT='0',
 VER='1',
 PACK_TYPE='0201',
 LOCATION='C607',
 CDS_LIB='pure_quanta',
 CDS_PART_NAME='Q_CAP_0201-1UF,4V,20%,X6S,CH-10KMEE00',
 VOLTAGE='4V',
 PART_NUMBER='CH-10KMEE00',
 VALUE='1UF',
 PRIM_FILE='./archive_libs/logical/q_cap/chips/chips.prt';

PART_NAME
 C608 'Q_CAP_C0201-0.1UF,10V,10%,X7S,CH4102K6E00':;

SECTION_NUMBER 1
 '@T6G_MB_LIB.T6G(SCH_1):PAGE411_I81@PURE_QUANTA.Q_CAP(CHIPS)':
 C_PATH='@t6g_mb_lib.t6g(sch_1):page411_i81@pure_quanta.q_cap(chips)',
 P_PATH='@t6g_mb_lib.t6g(sch_1):page290_i81@pure_quanta.q_cap(chips)',
 PATH='I81',
 DRAWING='@T6G_MB_LIB.T6G(SCH_1):PAGE411',
 TOLERANCE='10%',
 MATERIAL='X7S',
 PHYS_PAGE='290',
 XY='(-2100,5125)',
 ROT='0',
 VER='1',
 PACK_TYPE='C0201',
 LOCATION='C608',
 CDS_LIB='pure_quanta',
 CDS_PART_NAME='Q_CAP_C0201-0.1UF,10V,10%,X7S,CH4102K6E00',
 VOLTAGE='10V',
 PART_NUMBER='CH4102K6E00',
 VALUE='0.1UF',
 PRIM_FILE='./archive_libs/logical/q_cap/chips/chips.prt';

PART_NAME
 C609 'Q_CAP_0201-1UF,4V,20%,X6S,CH-10KMEE00':;

SECTION_NUMBER 1
 '@T6G_MB_LIB.T6G(SCH_1):PAGE411_I38@PURE_QUANTA.Q_CAP(CHIPS)':
 C_PATH='@t6g_mb_lib.t6g(sch_1):page411_i38@pure_quanta.q_cap(chips)',
 P_PATH='@t6g_mb_lib.t6g(sch_1):page290_i38@pure_quanta.q_cap(chips)',
 PATH='I38',
 DRAWING='@T6G_MB_LIB.T6G(SCH_1):PAGE411',
 TOLERANCE='20%',
 MATERIAL='X6S',
 PHYS_PAGE='290',
 XY='(-3650,2650)',
 ROT='0',
 VER='1',
 PACK_TYPE='0201',
 LOCATION='C609',
 CDS_LIB='pure_quanta',
 CDS_PART_NAME='Q_CAP_0201-1UF,4V,20%,X6S,CH-10KMEE00',
 VOLTAGE='4V',
 PART_NUMBER='CH-10KMEE00',
 VALUE='1UF',
 PRIM_FILE='./archive_libs/logical/q_cap/chips/chips.prt';

PART_NAME
 C610 'Q_CAP_C0201-0.1UF,10V,10%,X7S,CH4102K6E00':;

SECTION_NUMBER 1
 '@T6G_MB_LIB.T6G(SCH_1):PAGE411_I82@PURE_QUANTA.Q_CAP(CHIPS)':
 C_PATH='@t6g_mb_lib.t6g(sch_1):page411_i82@pure_quanta.q_cap(chips)',
 P_PATH='@t6g_mb_lib.t6g(sch_1):page290_i82@pure_quanta.q_cap(chips)',
 PATH='I82',
 DRAWING='@T6G_MB_LIB.T6G(SCH_1):PAGE411',
 TOLERANCE='10%',
 MATERIAL='X7S',
 PHYS_PAGE='290',
 XY='(-1825,5125)',
 ROT='0',
 VER='1',
 PACK_TYPE='C0201',
 LOCATION='C610',
 CDS_LIB='pure_quanta',
 CDS_PART_NAME='Q_CAP_C0201-0.1UF,10V,10%,X7S,CH4102K6E00',
 VOLTAGE='10V',
 PART_NUMBER='CH4102K6E00',
 VALUE='0.1UF',
 PRIM_FILE='./archive_libs/logical/q_cap/chips/chips.prt';

PART_NAME
 C611 'Q_CAP_0402-0.1UF,25V,10%,X7R,CH4104K1B00':;

SECTION_NUMBER 1
 '@T6G_MB_LIB.T6G(SCH_1):PAGE137_I6@PURE_QUANTA.Q_CAP(CHIPS)':
 C_PATH='@t6g_mb_lib.t6g(sch_1):page137_i6@pure_quanta.q_cap(chips)',
 P_PATH='@t6g_mb_lib.t6g(sch_1):page160_i6@pure_quanta.q_cap(chips)',
 PATH='I6',
 DRAWING='@T6G_MB_LIB.T6G(SCH_1):PAGE137',
 TOLERANCE='10%',
 MATERIAL='X7R',
 PHYS_PAGE='160',
 XY='(-6450,-1175)',
 ROT='0',
 VER='1',
 PACK_TYPE='0402',
 LOCATION='C611',
 CDS_LIB='pure_quanta',
 CDS_PART_NAME='Q_CAP_0402-0.1UF,25V,10%,X7R,CH4104K1B00',
 VOLTAGE='25V',
 PART_NUMBER='CH4104K1B00',
 VALUE='0.1UF',
 PRIM_FILE='./archive_libs/logical/q_cap/chips/chips.prt';

PART_NAME
 C612 'Q_CAP_0402-0.1UF,25V,10%,X7R,CH4104K1B00':;

SECTION_NUMBER 1
 '@T6G_MB_LIB.T6G(SCH_1):PAGE137_I8@PURE_QUANTA.Q_CAP(CHIPS)':
 C_PATH='@t6g_mb_lib.t6g(sch_1):page137_i8@pure_quanta.q_cap(chips)',
 P_PATH='@t6g_mb_lib.t6g(sch_1):page160_i8@pure_quanta.q_cap(chips)',
 PATH='I8',
 DRAWING='@T6G_MB_LIB.T6G(SCH_1):PAGE137',
 TOLERANCE='10%',
 MATERIAL='X7R',
 PHYS_PAGE='160',
 XY='(-5125,-1175)',
 ROT='0',
 VER='1',
 PACK_TYPE='0402',
 LOCATION='C612',
 CDS_LIB='pure_quanta',
 CDS_PART_NAME='Q_CAP_0402-0.1UF,25V,10%,X7R,CH4104K1B00',
 VOLTAGE='25V',
 PART_NUMBER='CH4104K1B00',
 VALUE='0.1UF',
 PRIM_FILE='./archive_libs/logical/q_cap/chips/chips.prt';

PART_NAME
 C613 'Q_CAP_0201-1UF,4V,20%,X6S,CH-10KMEE00':;

SECTION_NUMBER 1
 '@T6G_MB_LIB.T6G(SCH_1):PAGE411_I61@PURE_QUANTA.Q_CAP(CHIPS)':
 C_PATH='@t6g_mb_lib.t6g(sch_1):page411_i61@pure_quanta.q_cap(chips)',
 P_PATH='@t6g_mb_lib.t6g(sch_1):page290_i61@pure_quanta.q_cap(chips)',
 PATH='I61',
 DRAWING='@T6G_MB_LIB.T6G(SCH_1):PAGE411',
 TOLERANCE='20%',
 MATERIAL='X6S',
 PHYS_PAGE='290',
 XY='(-1575,3275)',
 ROT='0',
 VER='1',
 PACK_TYPE='0201',
 LOCATION='C613',
 CDS_LIB='pure_quanta',
 CDS_PART_NAME='Q_CAP_0201-1UF,4V,20%,X6S,CH-10KMEE00',
 VOLTAGE='4V',
 PART_NUMBER='CH-10KMEE00',
 VALUE='1UF',
 PRIM_FILE='./archive_libs/logical/q_cap/chips/chips.prt';

PART_NAME
 C614 'Q_CAP_C0201-0.1UF,10V,10%,X7S,CH4102K6E00':;

SECTION_NUMBER 1
 '@T6G_MB_LIB.T6G(SCH_1):PAGE411_I85@PURE_QUANTA.Q_CAP(CHIPS)':
 C_PATH='@t6g_mb_lib.t6g(sch_1):page411_i85@pure_quanta.q_cap(chips)',
 P_PATH='@t6g_mb_lib.t6g(sch_1):page290_i85@pure_quanta.q_cap(chips)',
 PATH='I85',
 DRAWING='@T6G_MB_LIB.T6G(SCH_1):PAGE411',
 TOLERANCE='10%',
 MATERIAL='X7S',
 PHYS_PAGE='290',
 XY='(-2075,1950)',
 ROT='0',
 VER='1',
 PACK_TYPE='C0201',
 LOCATION='C614',
 CDS_LIB='pure_quanta',
 CDS_PART_NAME='Q_CAP_C0201-0.1UF,10V,10%,X7S,CH4102K6E00',
 VOLTAGE='10V',
 PART_NUMBER='CH4102K6E00',
 VALUE='0.1UF',
 PRIM_FILE='./archive_libs/logical/q_cap/chips/chips.prt';

PART_NAME
 C615 'Q_CAP_C0201-0.1UF,10V,10%,X7S,CH4102K6E00':;

SECTION_NUMBER 1
 '@T6G_MB_LIB.T6G(SCH_1):PAGE411_I83@PURE_QUANTA.Q_CAP(CHIPS)':
 C_PATH='@t6g_mb_lib.t6g(sch_1):page411_i83@pure_quanta.q_cap(chips)',
 P_PATH='@t6g_mb_lib.t6g(sch_1):page290_i83@pure_quanta.q_cap(chips)',
 PATH='I83',
 DRAWING='@T6G_MB_LIB.T6G(SCH_1):PAGE411',
 TOLERANCE='10%',
 MATERIAL='X7S',
 PHYS_PAGE='290',
 XY='(-1575,5125)',
 ROT='0',
 VER='1',
 PACK_TYPE='C0201',
 LOCATION='C615',
 CDS_LIB='pure_quanta',
 CDS_PART_NAME='Q_CAP_C0201-0.1UF,10V,10%,X7S,CH4102K6E00',
 VOLTAGE='10V',
 PART_NUMBER='CH4102K6E00',
 VALUE='0.1UF',
 PRIM_FILE='./archive_libs/logical/q_cap/chips/chips.prt';

PART_NAME
 C616 'Q_CAP_C0201-0.1UF,10V,10%,X7S,CH4102K6E00':;

SECTION_NUMBER 1
 '@T6G_MB_LIB.T6G(SCH_1):PAGE411_I42@PURE_QUANTA.Q_CAP(CHIPS)':
 C_PATH='@t6g_mb_lib.t6g(sch_1):page411_i42@pure_quanta.q_cap(chips)',
 P_PATH='@t6g_mb_lib.t6g(sch_1):page290_i42@pure_quanta.q_cap(chips)',
 PATH='I42',
 DRAWING='@T6G_MB_LIB.T6G(SCH_1):PAGE411',
 TOLERANCE='10%',
 MATERIAL='X7S',
 PHYS_PAGE='290',
 XY='(-3075,1950)',
 ROT='0',
 VER='1',
 PACK_TYPE='C0201',
 LOCATION='C616',
 CDS_LIB='pure_quanta',
 CDS_PART_NAME='Q_CAP_C0201-0.1UF,10V,10%,X7S,CH4102K6E00',
 VOLTAGE='10V',
 PART_NUMBER='CH4102K6E00',
 VALUE='0.1UF',
 PRIM_FILE='./archive_libs/logical/q_cap/chips/chips.prt';

PART_NAME
 C617 'Q_CAP_C0201-0.1UF,10V,10%,X7S,CH4102K6E00':;

SECTION_NUMBER 1
 '@T6G_MB_LIB.T6G(SCH_1):PAGE411_I32@PURE_QUANTA.Q_CAP(CHIPS)':
 C_PATH='@t6g_mb_lib.t6g(sch_1):page411_i32@pure_quanta.q_cap(chips)',
 P_PATH='@t6g_mb_lib.t6g(sch_1):page290_i32@pure_quanta.q_cap(chips)',
 PATH='I32',
 DRAWING='@T6G_MB_LIB.T6G(SCH_1):PAGE411',
 TOLERANCE='10%',
 MATERIAL='X7S',
 PHYS_PAGE='290',
 XY='(-3200,850)',
 ROT='0',
 VER='1',
 PACK_TYPE='C0201',
 LOCATION='C617',
 CDS_LIB='pure_quanta',
 CDS_PART_NAME='Q_CAP_C0201-0.1UF,10V,10%,X7S,CH4102K6E00',
 VOLTAGE='10V',
 PART_NUMBER='CH4102K6E00',
 VALUE='0.1UF',
 PRIM_FILE='./archive_libs/logical/q_cap/chips/chips.prt';

PART_NAME
 C618 'Q_CAP_0201-1UF,4V,20%,X6S,CH-10KMEE00':;

SECTION_NUMBER 1
 '@T6G_MB_LIB.T6G(SCH_1):PAGE411_I39@PURE_QUANTA.Q_CAP(CHIPS)':
 C_PATH='@t6g_mb_lib.t6g(sch_1):page411_i39@pure_quanta.q_cap(chips)',
 P_PATH='@t6g_mb_lib.t6g(sch_1):page290_i39@pure_quanta.q_cap(chips)',
 PATH='I39',
 DRAWING='@T6G_MB_LIB.T6G(SCH_1):PAGE411',
 TOLERANCE='20%',
 MATERIAL='X6S',
 PHYS_PAGE='290',
 XY='(-3425,2650)',
 ROT='0',
 VER='1',
 PACK_TYPE='0201',
 LOCATION='C618',
 CDS_LIB='pure_quanta',
 CDS_PART_NAME='Q_CAP_0201-1UF,4V,20%,X6S,CH-10KMEE00',
 VOLTAGE='4V',
 PART_NUMBER='CH-10KMEE00',
 VALUE='1UF',
 PRIM_FILE='./archive_libs/logical/q_cap/chips/chips.prt';

PART_NAME
 C619 'Q_CAP_C0201-0.1UF,10V,10%,X7S,CH4102K6E00':;

SECTION_NUMBER 1
 '@T6G_MB_LIB.T6G(SCH_1):PAGE411_I84@PURE_QUANTA.Q_CAP(CHIPS)':
 C_PATH='@t6g_mb_lib.t6g(sch_1):page411_i84@pure_quanta.q_cap(chips)',
 P_PATH='@t6g_mb_lib.t6g(sch_1):page290_i84@pure_quanta.q_cap(chips)',
 PATH='I84',
 DRAWING='@T6G_MB_LIB.T6G(SCH_1):PAGE411',
 TOLERANCE='10%',
 MATERIAL='X7S',
 PHYS_PAGE='290',
 XY='(-1300,5125)',
 ROT='0',
 VER='1',
 PACK_TYPE='C0201',
 LOCATION='C619',
 CDS_LIB='pure_quanta',
 CDS_PART_NAME='Q_CAP_C0201-0.1UF,10V,10%,X7S,CH4102K6E00',
 VOLTAGE='10V',
 PART_NUMBER='CH4102K6E00',
 VALUE='0.1UF',
 PRIM_FILE='./archive_libs/logical/q_cap/chips/chips.prt';

PART_NAME
 C620 'Q_CAP_0201-1UF,4V,20%,X6S,CH-10KMEE00':;

SECTION_NUMBER 1
 '@T6G_MB_LIB.T6G(SCH_1):PAGE411_I59@PURE_QUANTA.Q_CAP(CHIPS)':
 C_PATH='@t6g_mb_lib.t6g(sch_1):page411_i59@pure_quanta.q_cap(chips)',
 P_PATH='@t6g_mb_lib.t6g(sch_1):page290_i59@pure_quanta.q_cap(chips)',
 PATH='I59',
 DRAWING='@T6G_MB_LIB.T6G(SCH_1):PAGE411',
 TOLERANCE='20%',
 MATERIAL='X6S',
 PHYS_PAGE='290',
 XY='(-2050,3275)',
 ROT='0',
 VER='1',
 PACK_TYPE='0201',
 LOCATION='C620',
 CDS_LIB='pure_quanta',
 CDS_PART_NAME='Q_CAP_0201-1UF,4V,20%,X6S,CH-10KMEE00',
 VOLTAGE='4V',
 PART_NUMBER='CH-10KMEE00',
 VALUE='1UF',
 PRIM_FILE='./archive_libs/logical/q_cap/chips/chips.prt';

PART_NAME
 C621 'Q_CAP_0201-1UF,4V,20%,X6S,CH-10KMEE00':;

SECTION_NUMBER 1
 '@T6G_MB_LIB.T6G(SCH_1):PAGE411_I90@PURE_QUANTA.Q_CAP(CHIPS)':
 C_PATH='@t6g_mb_lib.t6g(sch_1):page411_i90@pure_quanta.q_cap(chips)',
 P_PATH='@t6g_mb_lib.t6g(sch_1):page290_i90@pure_quanta.q_cap(chips)',
 PATH='I90',
 DRAWING='@T6G_MB_LIB.T6G(SCH_1):PAGE411',
 TOLERANCE='20%',
 MATERIAL='X6S',
 PHYS_PAGE='290',
 XY='(-2950,850)',
 ROT='0',
 VER='1',
 PACK_TYPE='0201',
 LOCATION='C621',
 CDS_LIB='pure_quanta',
 CDS_PART_NAME='Q_CAP_0201-1UF,4V,20%,X6S,CH-10KMEE00',
 VOLTAGE='4V',
 PART_NUMBER='CH-10KMEE00',
 VALUE='1UF',
 PRIM_FILE='./archive_libs/logical/q_cap/chips/chips.prt';

PART_NAME
 C622 'Q_CAP_0201-1UF,4V,20%,X6S,CH-10KMEE00':;

SECTION_NUMBER 1
 '@T6G_MB_LIB.T6G(SCH_1):PAGE411_I86@PURE_QUANTA.Q_CAP(CHIPS)':
 C_PATH='@t6g_mb_lib.t6g(sch_1):page411_i86@pure_quanta.q_cap(chips)',
 P_PATH='@t6g_mb_lib.t6g(sch_1):page290_i86@pure_quanta.q_cap(chips)',
 PATH='I86',
 DRAWING='@T6G_MB_LIB.T6G(SCH_1):PAGE411',
 TOLERANCE='20%',
 MATERIAL='X6S',
 PHYS_PAGE='290',
 XY='(-2475,2625)',
 ROT='0',
 VER='1',
 PACK_TYPE='0201',
 LOCATION='C622',
 CDS_LIB='pure_quanta',
 CDS_PART_NAME='Q_CAP_0201-1UF,4V,20%,X6S,CH-10KMEE00',
 VOLTAGE='4V',
 PART_NUMBER='CH-10KMEE00',
 VALUE='1UF',
 PRIM_FILE='./archive_libs/logical/q_cap/chips/chips.prt';

PART_NAME
 C623 'Q_CAP_C0201-0.1UF,10V,10%,X7S,CH4102K6E00':;

SECTION_NUMBER 1
 '@T6G_MB_LIB.T6G(SCH_1):PAGE411_I34@PURE_QUANTA.Q_CAP(CHIPS)':
 C_PATH='@t6g_mb_lib.t6g(sch_1):page411_i34@pure_quanta.q_cap(chips)',
 P_PATH='@t6g_mb_lib.t6g(sch_1):page290_i34@pure_quanta.q_cap(chips)',
 PATH='I34',
 DRAWING='@T6G_MB_LIB.T6G(SCH_1):PAGE411',
 TOLERANCE='10%',
 MATERIAL='X7S',
 PHYS_PAGE='290',
 XY='(-2650,850)',
 ROT='0',
 VER='1',
 PACK_TYPE='C0201',
 LOCATION='C623',
 CDS_LIB='pure_quanta',
 CDS_PART_NAME='Q_CAP_C0201-0.1UF,10V,10%,X7S,CH4102K6E00',
 VOLTAGE='10V',
 PART_NUMBER='CH4102K6E00',
 VALUE='0.1UF',
 PRIM_FILE='./archive_libs/logical/q_cap/chips/chips.prt';

PART_NAME
 C624 'Q_CAP_0201-1UF,4V,20%,X6S,CH-10KMEE00':;

SECTION_NUMBER 1
 '@T6G_MB_LIB.T6G(SCH_1):PAGE411_I91@PURE_QUANTA.Q_CAP(CHIPS)':
 C_PATH='@t6g_mb_lib.t6g(sch_1):page411_i91@pure_quanta.q_cap(chips)',
 P_PATH='@t6g_mb_lib.t6g(sch_1):page290_i91@pure_quanta.q_cap(chips)',
 PATH='I91',
 DRAWING='@T6G_MB_LIB.T6G(SCH_1):PAGE411',
 TOLERANCE='20%',
 MATERIAL='X6S',
 PHYS_PAGE='290',
 XY='(-2400,850)',
 ROT='0',
 VER='1',
 PACK_TYPE='0201',
 LOCATION='C624',
 CDS_LIB='pure_quanta',
 CDS_PART_NAME='Q_CAP_0201-1UF,4V,20%,X6S,CH-10KMEE00',
 VOLTAGE='4V',
 PART_NUMBER='CH-10KMEE00',
 VALUE='1UF',
 PRIM_FILE='./archive_libs/logical/q_cap/chips/chips.prt';

PART_NAME
 C625 'Q_CAP_C0805-100UF,4V,20%,X6S,CH710KMEA01':;

SECTION_NUMBER 1
 '@T6G_MB_LIB.T6G(SCH_1):PAGE411_I64@PURE_QUANTA.Q_CAP(CHIPS)':
 C_PATH='@t6g_mb_lib.t6g(sch_1):page411_i64@pure_quanta.q_cap(chips)',
 P_PATH='@t6g_mb_lib.t6g(sch_1):page290_i64@pure_quanta.q_cap(chips)',
 PATH='I64',
 DRAWING='@T6G_MB_LIB.T6G(SCH_1):PAGE411',
 TOLERANCE='20%',
 MATERIAL='X6S',
 PHYS_PAGE='290',
 XY='(-3650,3900)',
 ROT='0',
 VER='1',
 PACK_TYPE='C0805',
 LOCATION='C625',
 CDS_LIB='pure_quanta',
 CDS_PART_NAME='Q_CAP_C0805-100UF,4V,20%,X6S,CH710KMEA01',
 VOLTAGE='4V',
 PART_NUMBER='CH710KMEA01',
 VALUE='100UF',
 PRIM_FILE='./archive_libs/logical/q_cap/chips/chips.prt';

PART_NAME
 C626 'Q_CAP_C0402-10UF,6.3V,20%,X6S,CH6101MEB01':;

SECTION_NUMBER 1
 '@T6G_MB_LIB.T6G(SCH_1):PAGE411_I40@PURE_QUANTA.Q_CAP(CHIPS)':
 C_PATH='@t6g_mb_lib.t6g(sch_1):page411_i40@pure_quanta.q_cap(chips)',
 P_PATH='@t6g_mb_lib.t6g(sch_1):page290_i40@pure_quanta.q_cap(chips)',
 PATH='I40',
 DRAWING='@T6G_MB_LIB.T6G(SCH_1):PAGE411',
 TOLERANCE='20%',
 MATERIAL='X6S',
 PHYS_PAGE='290',
 XY='(-3650,3275)',
 ROT='0',
 VER='1',
 PACK_TYPE='C0402',
 LOCATION='C626',
 CDS_LIB='pure_quanta',
 CDS_PART_NAME='Q_CAP_C0402-10UF,6.3V,20%,X6S,CH6101MEB01',
 VOLTAGE='6.3V',
 PART_NUMBER='CH6101MEB01',
 VALUE='10UF',
 PRIM_FILE='./archive_libs/logical/q_cap/chips/chips.prt';

PART_NAME
 C627 'Q_CAP_C0201-0.1UF,10V,10%,X7S,CH4102K6E00':;

SECTION_NUMBER 1
 '@T6G_MB_LIB.T6G(SCH_1):PAGE411_I47@PURE_QUANTA.Q_CAP(CHIPS)':
 C_PATH='@t6g_mb_lib.t6g(sch_1):page411_i47@pure_quanta.q_cap(chips)',
 P_PATH='@t6g_mb_lib.t6g(sch_1):page290_i47@pure_quanta.q_cap(chips)',
 PATH='I47',
 DRAWING='@T6G_MB_LIB.T6G(SCH_1):PAGE411',
 TOLERANCE='10%',
 MATERIAL='X7S',
 PHYS_PAGE='290',
 XY='(-2350,1950)',
 ROT='0',
 VER='1',
 PACK_TYPE='C0201',
 LOCATION='C627',
 CDS_LIB='pure_quanta',
 CDS_PART_NAME='Q_CAP_C0201-0.1UF,10V,10%,X7S,CH4102K6E00',
 VOLTAGE='10V',
 PART_NUMBER='CH4102K6E00',
 VALUE='0.1UF',
 PRIM_FILE='./archive_libs/logical/q_cap/chips/chips.prt';

PART_NAME
 C628 'Q_CAP_C0805-100UF,4V,20%,X6S,CH710KMEA01':;

SECTION_NUMBER 1
 '@T6G_MB_LIB.T6G(SCH_1):PAGE411_I65@PURE_QUANTA.Q_CAP(CHIPS)':
 C_PATH='@t6g_mb_lib.t6g(sch_1):page411_i65@pure_quanta.q_cap(chips)',
 P_PATH='@t6g_mb_lib.t6g(sch_1):page290_i65@pure_quanta.q_cap(chips)',
 PATH='I65',
 DRAWING='@T6G_MB_LIB.T6G(SCH_1):PAGE411',
 TOLERANCE='20%',
 MATERIAL='X6S',
 PHYS_PAGE='290',
 XY='(-3425,3900)',
 ROT='0',
 VER='1',
 PACK_TYPE='C0805',
 LOCATION='C628',
 CDS_LIB='pure_quanta',
 CDS_PART_NAME='Q_CAP_C0805-100UF,4V,20%,X6S,CH710KMEA01',
 VOLTAGE='4V',
 PART_NUMBER='CH710KMEA01',
 VALUE='100UF',
 PRIM_FILE='./archive_libs/logical/q_cap/chips/chips.prt';

PART_NAME
 C629 'Q_CAP_0402-0.1UF,25V,10%,X7R,CH4104K1B00':;

SECTION_NUMBER 1
 '@T6G_MB_LIB.T6G(SCH_1):PAGE361_I55@PURE_QUANTA.Q_CAP(CHIPS)':
 C_PATH='@t6g_mb_lib.t6g(sch_1):page361_i55@pure_quanta.q_cap(chips)',
 P_PATH='@t6g_mb_lib.t6g(sch_1):page238_i55@pure_quanta.q_cap(chips)',
 PATH='I55',
 DRAWING='@T6G_MB_LIB.T6G(SCH_1):PAGE361',
 TOLERANCE='10%',
 MATERIAL='X7R',
 PHYS_PAGE='238',
 XY='(-775,3700)',
 ROT='2',
 VER='1',
 PACK_TYPE='0402',
 LOCATION='C629',
 CDS_LIB='pure_quanta',
 CDS_PART_NAME='Q_CAP_0402-0.1UF,25V,10%,X7R,CH4104K1B00',
 VOLTAGE='25V',
 PART_NUMBER='CH4104K1B00',
 VALUE='0.1UF',
 PRIM_FILE='./archive_libs/logical/q_cap/chips/chips.prt';

PART_NAME
 C630 'Q_CAP_C0402-22UF,4V,20%,X6S,CH622KMEB02':;

SECTION_NUMBER 1
 '@T6G_MB_LIB.T6G(SCH_1):PAGE411_I73@PURE_QUANTA.Q_CAP(CHIPS)':
 C_PATH='@t6g_mb_lib.t6g(sch_1):page411_i73@pure_quanta.q_cap(chips)',
 P_PATH='@t6g_mb_lib.t6g(sch_1):page290_i73@pure_quanta.q_cap(chips)',
 PATH='I73',
 DRAWING='@T6G_MB_LIB.T6G(SCH_1):PAGE411',
 TOLERANCE='20%',
 MATERIAL='X6S',
 PHYS_PAGE='290',
 XY='(-2275,3900)',
 ROT='0',
 VER='1',
 PACK_TYPE='C0402',
 LOCATION='C630',
 CDS_LIB='pure_quanta',
 CDS_PART_NAME='Q_CAP_C0402-22UF,4V,20%,X6S,CH622KMEB02',
 VOLTAGE='4V',
 PART_NUMBER='CH622KMEB02',
 VALUE='22UF',
 PRIM_FILE='./archive_libs/logical/q_cap/chips/chips.prt';

PART_NAME
 C631 'Q_CAP_C0201-0.1UF,10V,10%,X7S,CH4102K6E00':;

SECTION_NUMBER 1
 '@T6G_MB_LIB.T6G(SCH_1):PAGE411_I55@PURE_QUANTA.Q_CAP(CHIPS)':
 C_PATH='@t6g_mb_lib.t6g(sch_1):page411_i55@pure_quanta.q_cap(chips)',
 P_PATH='@t6g_mb_lib.t6g(sch_1):page290_i55@pure_quanta.q_cap(chips)',
 PATH='I55',
 DRAWING='@T6G_MB_LIB.T6G(SCH_1):PAGE411',
 TOLERANCE='10%',
 MATERIAL='X7S',
 PHYS_PAGE='290',
 XY='(-1800,1950)',
 ROT='0',
 VER='1',
 PACK_TYPE='C0201',
 LOCATION='C631',
 CDS_LIB='pure_quanta',
 CDS_PART_NAME='Q_CAP_C0201-0.1UF,10V,10%,X7S,CH4102K6E00',
 VOLTAGE='10V',
 PART_NUMBER='CH4102K6E00',
 VALUE='0.1UF',
 PRIM_FILE='./archive_libs/logical/q_cap/chips/chips.prt';

PART_NAME
 C632 'Q_CAP_C0805-100UF,4V,20%,X6S,CH710KMEA01':;

SECTION_NUMBER 1
 '@T6G_MB_LIB.T6G(SCH_1):PAGE411_I67@PURE_QUANTA.Q_CAP(CHIPS)':
 C_PATH='@t6g_mb_lib.t6g(sch_1):page411_i67@pure_quanta.q_cap(chips)',
 P_PATH='@t6g_mb_lib.t6g(sch_1):page290_i67@pure_quanta.q_cap(chips)',
 PATH='I67',
 DRAWING='@T6G_MB_LIB.T6G(SCH_1):PAGE411',
 TOLERANCE='20%',
 MATERIAL='X6S',
 PHYS_PAGE='290',
 XY='(-3600,5175)',
 ROT='0',
 VER='1',
 PACK_TYPE='C0805',
 LOCATION='C632',
 CDS_LIB='pure_quanta',
 CDS_PART_NAME='Q_CAP_C0805-100UF,4V,20%,X6S,CH710KMEA01',
 VOLTAGE='4V',
 PART_NUMBER='CH710KMEA01',
 VALUE='100UF',
 PRIM_FILE='./archive_libs/logical/q_cap/chips/chips.prt';

PART_NAME
 C633 'Q_CAP_C0805-100UF,4V,20%,X6S,CH710KMEA01':;

SECTION_NUMBER 1
 '@T6G_MB_LIB.T6G(SCH_1):PAGE411_I69@PURE_QUANTA.Q_CAP(CHIPS)':
 C_PATH='@t6g_mb_lib.t6g(sch_1):page411_i69@pure_quanta.q_cap(chips)',
 P_PATH='@t6g_mb_lib.t6g(sch_1):page290_i69@pure_quanta.q_cap(chips)',
 PATH='I69',
 DRAWING='@T6G_MB_LIB.T6G(SCH_1):PAGE411',
 TOLERANCE='20%',
 MATERIAL='X6S',
 PHYS_PAGE='290',
 XY='(-3200,3900)',
 ROT='0',
 VER='1',
 PACK_TYPE='C0805',
 LOCATION='C633',
 CDS_LIB='pure_quanta',
 CDS_PART_NAME='Q_CAP_C0805-100UF,4V,20%,X6S,CH710KMEA01',
 VOLTAGE='4V',
 PART_NUMBER='CH710KMEA01',
 VALUE='100UF',
 PRIM_FILE='./archive_libs/logical/q_cap/chips/chips.prt';

PART_NAME
 C634 'Q_CAP_C0402-22UF,4V,20%,X6S,CH622KMEB02':;

SECTION_NUMBER 1
 '@T6G_MB_LIB.T6G(SCH_1):PAGE411_I71@PURE_QUANTA.Q_CAP(CHIPS)':
 C_PATH='@t6g_mb_lib.t6g(sch_1):page411_i71@pure_quanta.q_cap(chips)',
 P_PATH='@t6g_mb_lib.t6g(sch_1):page290_i71@pure_quanta.q_cap(chips)',
 PATH='I71',
 DRAWING='@T6G_MB_LIB.T6G(SCH_1):PAGE411',
 TOLERANCE='20%',
 MATERIAL='X6S',
 PHYS_PAGE='290',
 XY='(-2725,3900)',
 ROT='0',
 VER='1',
 PACK_TYPE='C0402',
 LOCATION='C634',
 CDS_LIB='pure_quanta',
 CDS_PART_NAME='Q_CAP_C0402-22UF,4V,20%,X6S,CH622KMEB02',
 VOLTAGE='4V',
 PART_NUMBER='CH622KMEB02',
 VALUE='22UF',
 PRIM_FILE='./archive_libs/logical/q_cap/chips/chips.prt';

PART_NAME
 C635 'Q_CAP_C0201-0.1UF,10V,10%,X7S,CH4102K6E00':;

SECTION_NUMBER 1
 '@T6G_MB_LIB.T6G(SCH_1):PAGE411_I46@PURE_QUANTA.Q_CAP(CHIPS)':
 C_PATH='@t6g_mb_lib.t6g(sch_1):page411_i46@pure_quanta.q_cap(chips)',
 P_PATH='@t6g_mb_lib.t6g(sch_1):page290_i46@pure_quanta.q_cap(chips)',
 PATH='I46',
 DRAWING='@T6G_MB_LIB.T6G(SCH_1):PAGE411',
 TOLERANCE='10%',
 MATERIAL='X7S',
 PHYS_PAGE='290',
 XY='(-2600,1950)',
 ROT='0',
 VER='1',
 PACK_TYPE='C0201',
 LOCATION='C635',
 CDS_LIB='pure_quanta',
 CDS_PART_NAME='Q_CAP_C0201-0.1UF,10V,10%,X7S,CH4102K6E00',
 VOLTAGE='10V',
 PART_NUMBER='CH4102K6E00',
 VALUE='0.1UF',
 PRIM_FILE='./archive_libs/logical/q_cap/chips/chips.prt';

PART_NAME
 C636 'Q_CAP_C0402-22UF,4V,20%,X6S,CH622KMEB02':;

SECTION_NUMBER 1
 '@T6G_MB_LIB.T6G(SCH_1):PAGE411_I68@PURE_QUANTA.Q_CAP(CHIPS)':
 C_PATH='@t6g_mb_lib.t6g(sch_1):page411_i68@pure_quanta.q_cap(chips)',
 P_PATH='@t6g_mb_lib.t6g(sch_1):page290_i68@pure_quanta.q_cap(chips)',
 PATH='I68',
 DRAWING='@T6G_MB_LIB.T6G(SCH_1):PAGE411',
 TOLERANCE='20%',
 MATERIAL='X6S',
 PHYS_PAGE='290',
 XY='(-3325,5175)',
 ROT='0',
 VER='1',
 PACK_TYPE='C0402',
 LOCATION='C636',
 CDS_LIB='pure_quanta',
 CDS_PART_NAME='Q_CAP_C0402-22UF,4V,20%,X6S,CH622KMEB02',
 VOLTAGE='4V',
 PART_NUMBER='CH622KMEB02',
 VALUE='22UF',
 PRIM_FILE='./archive_libs/logical/q_cap/chips/chips.prt';

PART_NAME
 C637 'Q_CAP_C0805-100UF,4V,20%,X6S,CH710KMEA01':;

SECTION_NUMBER 1
 '@T6G_MB_LIB.T6G(SCH_1):PAGE411_I70@PURE_QUANTA.Q_CAP(CHIPS)':
 C_PATH='@t6g_mb_lib.t6g(sch_1):page411_i70@pure_quanta.q_cap(chips)',
 P_PATH='@t6g_mb_lib.t6g(sch_1):page290_i70@pure_quanta.q_cap(chips)',
 PATH='I70',
 DRAWING='@T6G_MB_LIB.T6G(SCH_1):PAGE411',
 TOLERANCE='20%',
 MATERIAL='X6S',
 PHYS_PAGE='290',
 XY='(-2975,3900)',
 ROT='0',
 VER='1',
 PACK_TYPE='C0805',
 LOCATION='C637',
 CDS_LIB='pure_quanta',
 CDS_PART_NAME='Q_CAP_C0805-100UF,4V,20%,X6S,CH710KMEA01',
 VOLTAGE='4V',
 PART_NUMBER='CH710KMEA01',
 VALUE='100UF',
 PRIM_FILE='./archive_libs/logical/q_cap/chips/chips.prt';

PART_NAME
 C638 'Q_CAP_0402-4.7UF,6.3V,20%,X6S,CH5471MEB01':;

SECTION_NUMBER 1
 '@T6G_MB_LIB.T6G(SCH_1):PAGE411_I51@PURE_QUANTA.Q_CAP(CHIPS)':
 C_PATH='@t6g_mb_lib.t6g(sch_1):page411_i51@pure_quanta.q_cap(chips)',
 P_PATH='@t6g_mb_lib.t6g(sch_1):page290_i51@pure_quanta.q_cap(chips)',
 PATH='I51',
 DRAWING='@T6G_MB_LIB.T6G(SCH_1):PAGE411',
 TOLERANCE='20%',
 MATERIAL='X6S',
 PHYS_PAGE='290',
 XY='(-2975,3275)',
 ROT='0',
 VER='1',
 PACK_TYPE='0402',
 LOCATION='C638',
 CDS_LIB='pure_quanta',
 CDS_PART_NAME='Q_CAP_0402-4.7UF,6.3V,20%,X6S,CH5471MEB01',
 VOLTAGE='6.3V',
 PART_NUMBER='CH5471MEB01',
 VALUE='4.7UF',
 PRIM_FILE='./archive_libs/logical/q_cap/chips/chips.prt';

PART_NAME
 C639 'Q_CAP_0402-0.1UF,25V,10%,X7R,CH4104K1B00':;

SECTION_NUMBER 1
 '@T6G_MB_LIB.T6G(SCH_1):PAGE336_I59@PURE_QUANTA.Q_CAP(CHIPS)':
 C_PATH='@t6g_mb_lib.t6g(sch_1):page336_i59@pure_quanta.q_cap(chips)',
 P_PATH='@t6g_mb_lib.t6g(sch_1):page132_i59@pure_quanta.q_cap(chips)',
 PATH='I59',
 DRAWING='@T6G_MB_LIB.T6G(SCH_1):PAGE336',
 TOLERANCE='10%',
 MATERIAL='X7R',
 PHYS_PAGE='132',
 XY='(-2075,4425)',
 ROT='2',
 VER='1',
 PACK_TYPE='0402',
 LOCATION='C639',
 CDS_LIB='pure_quanta',
 CDS_PART_NAME='Q_CAP_0402-0.1UF,25V,10%,X7R,CH4104K1B00',
 VOLTAGE='25V',
 PART_NUMBER='CH4104K1B00',
 VALUE='0.1UF',
 PRIM_FILE='./archive_libs/logical/q_cap/chips/chips.prt';

PART_NAME
 C640 'Q_CAP_0402-0.1UF,25V,10%,X7R,CH4104K1B00':;

SECTION_NUMBER 1
 '@T6G_MB_LIB.T6G(SCH_1):PAGE336_I47@PURE_QUANTA.Q_CAP(CHIPS)':
 C_PATH='@t6g_mb_lib.t6g(sch_1):page336_i47@pure_quanta.q_cap(chips)',
 P_PATH='@t6g_mb_lib.t6g(sch_1):page132_i47@pure_quanta.q_cap(chips)',
 PATH='I47',
 DRAWING='@T6G_MB_LIB.T6G(SCH_1):PAGE336',
 TOLERANCE='10%',
 MATERIAL='X7R',
 PHYS_PAGE='132',
 XY='(-975,7225)',
 ROT='2',
 VER='1',
 PACK_TYPE='0402',
 LOCATION='C640',
 CDS_LIB='pure_quanta',
 CDS_PART_NAME='Q_CAP_0402-0.1UF,25V,10%,X7R,CH4104K1B00',
 VOLTAGE='25V',
 PART_NUMBER='CH4104K1B00',
 VALUE='0.1UF',
 PRIM_FILE='./archive_libs/logical/q_cap/chips/chips.prt';

PART_NAME
 C641 'Q_CAP_0402-0.1UF,25V,10%,X7R,CH4104K1B00':;

SECTION_NUMBER 1
 '@T6G_MB_LIB.T6G(SCH_1):PAGE336_I16@PURE_QUANTA.Q_CAP(CHIPS)':
 C_PATH='@t6g_mb_lib.t6g(sch_1):page336_i16@pure_quanta.q_cap(chips)',
 P_PATH='@t6g_mb_lib.t6g(sch_1):page132_i16@pure_quanta.q_cap(chips)',
 PATH='I16',
 DRAWING='@T6G_MB_LIB.T6G(SCH_1):PAGE336',
 TOLERANCE='10%',
 MATERIAL='X7R',
 PHYS_PAGE='132',
 XY='(-975,5800)',
 ROT='2',
 VER='1',
 PACK_TYPE='0402',
 LOCATION='C641',
 CDS_LIB='pure_quanta',
 CDS_PART_NAME='Q_CAP_0402-0.1UF,25V,10%,X7R,CH4104K1B00',
 VOLTAGE='25V',
 PART_NUMBER='CH4104K1B00',
 VALUE='0.1UF',
 PRIM_FILE='./archive_libs/logical/q_cap/chips/chips.prt';

PART_NAME
 C642 'Q_CAP_0402-1000PF,50V,5%,X7R,TMP_QCH21006JB10':;

SECTION_NUMBER 1
 '@T6G_MB_LIB.T6G(SCH_1):PAGE199_I44@PURE_QUANTA.Q_CAP(CHIPS)':
 C_PATH='@t6g_mb_lib.t6g(sch_1):page199_i44@pure_quanta.q_cap(chips)',
 P_PATH='@t6g_mb_lib.t6g(sch_1):page224_i44@pure_quanta.q_cap(chips)',
 PATH='I44',
 DRAWING='@T6G_MB_LIB.T6G(SCH_1):PAGE199',
 TOLERANCE='5%',
 MATERIAL='X7R',
 PHYS_PAGE='224',
 XY='(-5300,5850)',
 ROT='0',
 VER='2',
 PACK_TYPE='0402',
 LOCATION='C642',
 CDS_LIB='pure_quanta',
 CDS_PART_NAME='Q_CAP_0402-1000PF,50V,5%,X7R,TMP_QCH21006JB10',
 VOLTAGE='50V',
 PART_NUMBER='TMP_QCH21006JB10',
 VALUE='1000PF',
 PRIM_FILE='./archive_libs/logical/q_cap/chips/chips.prt';

PART_NAME
 C643 'Q_CAP_0201-1UF,4V,20%,X6S,CH-10KMEE00':;

SECTION_NUMBER 1
 '@T6G_MB_LIB.T6G(SCH_1):PAGE411_I45@PURE_QUANTA.Q_CAP(CHIPS)':
 C_PATH='@t6g_mb_lib.t6g(sch_1):page411_i45@pure_quanta.q_cap(chips)',
 P_PATH='@t6g_mb_lib.t6g(sch_1):page290_i45@pure_quanta.q_cap(chips)',
 PATH='I45',
 DRAWING='@T6G_MB_LIB.T6G(SCH_1):PAGE411',
 TOLERANCE='20%',
 MATERIAL='X6S',
 PHYS_PAGE='290',
 XY='(-2950,2650)',
 ROT='0',
 VER='1',
 PACK_TYPE='0201',
 LOCATION='C643',
 CDS_LIB='pure_quanta',
 CDS_PART_NAME='Q_CAP_0201-1UF,4V,20%,X6S,CH-10KMEE00',
 VOLTAGE='4V',
 PART_NUMBER='CH-10KMEE00',
 VALUE='1UF',
 PRIM_FILE='./archive_libs/logical/q_cap/chips/chips.prt';

PART_NAME
 C644 'Q_CAP_0402-4.7UF,6.3V,20%,X6S,CH5471MEB01':;

SECTION_NUMBER 1
 '@T6G_MB_LIB.T6G(SCH_1):PAGE411_I50@PURE_QUANTA.Q_CAP(CHIPS)':
 C_PATH='@t6g_mb_lib.t6g(sch_1):page411_i50@pure_quanta.q_cap(chips)',
 P_PATH='@t6g_mb_lib.t6g(sch_1):page290_i50@pure_quanta.q_cap(chips)',
 PATH='I50',
 DRAWING='@T6G_MB_LIB.T6G(SCH_1):PAGE411',
 TOLERANCE='20%',
 MATERIAL='X6S',
 PHYS_PAGE='290',
 XY='(-3200,3275)',
 ROT='0',
 VER='1',
 PACK_TYPE='0402',
 LOCATION='C644',
 CDS_LIB='pure_quanta',
 CDS_PART_NAME='Q_CAP_0402-4.7UF,6.3V,20%,X6S,CH5471MEB01',
 VOLTAGE='6.3V',
 PART_NUMBER='CH5471MEB01',
 VALUE='4.7UF',
 PRIM_FILE='./archive_libs/logical/q_cap/chips/chips.prt';

PART_NAME
 C645 'Q_CAP_C0402-10UF,6.3V,20%,X6S,CH6101MEB01':;

SECTION_NUMBER 1
 '@T6G_MB_LIB.T6G(SCH_1):PAGE411_I41@PURE_QUANTA.Q_CAP(CHIPS)':
 C_PATH='@t6g_mb_lib.t6g(sch_1):page411_i41@pure_quanta.q_cap(chips)',
 P_PATH='@t6g_mb_lib.t6g(sch_1):page290_i41@pure_quanta.q_cap(chips)',
 PATH='I41',
 DRAWING='@T6G_MB_LIB.T6G(SCH_1):PAGE411',
 TOLERANCE='20%',
 MATERIAL='X6S',
 PHYS_PAGE='290',
 XY='(-3425,3275)',
 ROT='0',
 VER='1',
 PACK_TYPE='C0402',
 LOCATION='C645',
 CDS_LIB='pure_quanta',
 CDS_PART_NAME='Q_CAP_C0402-10UF,6.3V,20%,X6S,CH6101MEB01',
 VOLTAGE='6.3V',
 PART_NUMBER='CH6101MEB01',
 VALUE='10UF',
 PRIM_FILE='./archive_libs/logical/q_cap/chips/chips.prt';

PART_NAME
 C646 'Q_CAP_C0402-10UF,6.3V,20%,X6S,CH6101MEB01':;

SECTION_NUMBER 1
 '@T6G_MB_LIB.T6G(SCH_1):PAGE411_I74@PURE_QUANTA.Q_CAP(CHIPS)':
 C_PATH='@t6g_mb_lib.t6g(sch_1):page411_i74@pure_quanta.q_cap(chips)',
 P_PATH='@t6g_mb_lib.t6g(sch_1):page290_i74@pure_quanta.q_cap(chips)',
 PATH='I74',
 DRAWING='@T6G_MB_LIB.T6G(SCH_1):PAGE411',
 TOLERANCE='20%',
 MATERIAL='X6S',
 PHYS_PAGE='290',
 XY='(-3000,5150)',
 ROT='0',
 VER='1',
 PACK_TYPE='C0402',
 LOCATION='C646',
 CDS_LIB='pure_quanta',
 CDS_PART_NAME='Q_CAP_C0402-10UF,6.3V,20%,X6S,CH6101MEB01',
 VOLTAGE='6.3V',
 PART_NUMBER='CH6101MEB01',
 VALUE='10UF',
 PRIM_FILE='./archive_libs/logical/q_cap/chips/chips.prt';

PART_NAME
 C647 'Q_CAP_0201-1UF,4V,20%,X6S,CH-10KMEE00':;

SECTION_NUMBER 1
 '@T6G_MB_LIB.T6G(SCH_1):PAGE411_I48@PURE_QUANTA.Q_CAP(CHIPS)':
 C_PATH='@t6g_mb_lib.t6g(sch_1):page411_i48@pure_quanta.q_cap(chips)',
 P_PATH='@t6g_mb_lib.t6g(sch_1):page290_i48@pure_quanta.q_cap(chips)',
 PATH='I48',
 DRAWING='@T6G_MB_LIB.T6G(SCH_1):PAGE411',
 TOLERANCE='20%',
 MATERIAL='X6S',
 PHYS_PAGE='290',
 XY='(-2700,2650)',
 ROT='0',
 VER='1',
 PACK_TYPE='0201',
 LOCATION='C647',
 CDS_LIB='pure_quanta',
 CDS_PART_NAME='Q_CAP_0201-1UF,4V,20%,X6S,CH-10KMEE00',
 VOLTAGE='4V',
 PART_NUMBER='CH-10KMEE00',
 VALUE='1UF',
 PRIM_FILE='./archive_libs/logical/q_cap/chips/chips.prt';

PART_NAME
 C648 'Q_CAP_C0402-10UF,6.3V,20%,X6S,CH6101MEB01':;

SECTION_NUMBER 1
 '@T6G_MB_LIB.T6G(SCH_1):PAGE411_I79@PURE_QUANTA.Q_CAP(CHIPS)':
 C_PATH='@t6g_mb_lib.t6g(sch_1):page411_i79@pure_quanta.q_cap(chips)',
 P_PATH='@t6g_mb_lib.t6g(sch_1):page290_i79@pure_quanta.q_cap(chips)',
 PATH='I79',
 DRAWING='@T6G_MB_LIB.T6G(SCH_1):PAGE411',
 TOLERANCE='20%',
 MATERIAL='X6S',
 PHYS_PAGE='290',
 XY='(-1450,3900)',
 ROT='0',
 VER='1',
 PACK_TYPE='C0402',
 LOCATION='C648',
 CDS_LIB='pure_quanta',
 CDS_PART_NAME='Q_CAP_C0402-10UF,6.3V,20%,X6S,CH6101MEB01',
 VOLTAGE='6.3V',
 PART_NUMBER='CH6101MEB01',
 VALUE='10UF',
 PRIM_FILE='./archive_libs/logical/q_cap/chips/chips.prt';

PART_NAME
 C649 'Q_CAP_0402-4.7UF,6.3V,20%,X6S,CH5471MEB01':;

SECTION_NUMBER 1
 '@T6G_MB_LIB.T6G(SCH_1):PAGE411_I52@PURE_QUANTA.Q_CAP(CHIPS)':
 C_PATH='@t6g_mb_lib.t6g(sch_1):page411_i52@pure_quanta.q_cap(chips)',
 P_PATH='@t6g_mb_lib.t6g(sch_1):page290_i52@pure_quanta.q_cap(chips)',
 PATH='I52',
 DRAWING='@T6G_MB_LIB.T6G(SCH_1):PAGE411',
 TOLERANCE='20%',
 MATERIAL='X6S',
 PHYS_PAGE='290',
 XY='(-2500,3275)',
 ROT='0',
 VER='1',
 PACK_TYPE='0402',
 LOCATION='C649',
 CDS_LIB='pure_quanta',
 CDS_PART_NAME='Q_CAP_0402-4.7UF,6.3V,20%,X6S,CH5471MEB01',
 VOLTAGE='6.3V',
 PART_NUMBER='CH5471MEB01',
 VALUE='4.7UF',
 PRIM_FILE='./archive_libs/logical/q_cap/chips/chips.prt';

PART_NAME
 C650 'Q_CAP_C0201-0.1UF,10V,10%,X7S,CH4102K6E00':;

SECTION_NUMBER 1
 '@T6G_MB_LIB.T6G(SCH_1):PAGE411_I58@PURE_QUANTA.Q_CAP(CHIPS)':
 C_PATH='@t6g_mb_lib.t6g(sch_1):page411_i58@pure_quanta.q_cap(chips)',
 P_PATH='@t6g_mb_lib.t6g(sch_1):page290_i58@pure_quanta.q_cap(chips)',
 PATH='I58',
 DRAWING='@T6G_MB_LIB.T6G(SCH_1):PAGE411',
 TOLERANCE='10%',
 MATERIAL='X7S',
 PHYS_PAGE='290',
 XY='(-1550,1950)',
 ROT='0',
 VER='1',
 PACK_TYPE='C0201',
 LOCATION='C650',
 CDS_LIB='pure_quanta',
 CDS_PART_NAME='Q_CAP_C0201-0.1UF,10V,10%,X7S,CH4102K6E00',
 VOLTAGE='10V',
 PART_NUMBER='CH4102K6E00',
 VALUE='0.1UF',
 PRIM_FILE='./archive_libs/logical/q_cap/chips/chips.prt';

PART_NAME
 C651 'Q_CAP_0402-4.7UF,6.3V,20%,X6S,CH5471MEB01':;

SECTION_NUMBER 1
 '@T6G_MB_LIB.T6G(SCH_1):PAGE411_I75@PURE_QUANTA.Q_CAP(CHIPS)':
 C_PATH='@t6g_mb_lib.t6g(sch_1):page411_i75@pure_quanta.q_cap(chips)',
 P_PATH='@t6g_mb_lib.t6g(sch_1):page290_i75@pure_quanta.q_cap(chips)',
 PATH='I75',
 DRAWING='@T6G_MB_LIB.T6G(SCH_1):PAGE411',
 TOLERANCE='20%',
 MATERIAL='X6S',
 PHYS_PAGE='290',
 XY='(-2700,5150)',
 ROT='0',
 VER='1',
 PACK_TYPE='0402',
 LOCATION='C651',
 CDS_LIB='pure_quanta',
 CDS_PART_NAME='Q_CAP_0402-4.7UF,6.3V,20%,X6S,CH5471MEB01',
 VOLTAGE='6.3V',
 PART_NUMBER='CH5471MEB01',
 VALUE='4.7UF',
 PRIM_FILE='./archive_libs/logical/q_cap/chips/chips.prt';

PART_NAME
 C652 'Q_CAP_0402-4.7UF,6.3V,20%,X6S,CH5471MEB01':;

SECTION_NUMBER 1
 '@T6G_MB_LIB.T6G(SCH_1):PAGE411_I87@PURE_QUANTA.Q_CAP(CHIPS)':
 C_PATH='@t6g_mb_lib.t6g(sch_1):page411_i87@pure_quanta.q_cap(chips)',
 P_PATH='@t6g_mb_lib.t6g(sch_1):page290_i87@pure_quanta.q_cap(chips)',
 PATH='I87',
 DRAWING='@T6G_MB_LIB.T6G(SCH_1):PAGE411',
 TOLERANCE='20%',
 MATERIAL='X6S',
 PHYS_PAGE='290',
 XY='(-2725,3275)',
 ROT='0',
 VER='1',
 PACK_TYPE='0402',
 LOCATION='C652',
 CDS_LIB='pure_quanta',
 CDS_PART_NAME='Q_CAP_0402-4.7UF,6.3V,20%,X6S,CH5471MEB01',
 VOLTAGE='6.3V',
 PART_NUMBER='CH5471MEB01',
 VALUE='4.7UF',
 PRIM_FILE='./archive_libs/logical/q_cap/chips/chips.prt';

PART_NAME
 C653 'Q_CAP_0201-1UF,4V,20%,X6S,CH-10KMEE00':;

SECTION_NUMBER 1
 '@T6G_MB_LIB.T6G(SCH_1):PAGE411_I53@PURE_QUANTA.Q_CAP(CHIPS)':
 C_PATH='@t6g_mb_lib.t6g(sch_1):page411_i53@pure_quanta.q_cap(chips)',
 P_PATH='@t6g_mb_lib.t6g(sch_1):page290_i53@pure_quanta.q_cap(chips)',
 PATH='I53',
 DRAWING='@T6G_MB_LIB.T6G(SCH_1):PAGE411',
 TOLERANCE='20%',
 MATERIAL='X6S',
 PHYS_PAGE='290',
 XY='(-2275,3275)',
 ROT='0',
 VER='1',
 PACK_TYPE='0201',
 LOCATION='C653',
 CDS_LIB='pure_quanta',
 CDS_PART_NAME='Q_CAP_0201-1UF,4V,20%,X6S,CH-10KMEE00',
 VOLTAGE='4V',
 PART_NUMBER='CH-10KMEE00',
 VALUE='1UF',
 PRIM_FILE='./archive_libs/logical/q_cap/chips/chips.prt';

PART_NAME
 C654 'Q_CAP_0201-1UF,4V,20%,X6S,CH-10KMEE00':;

SECTION_NUMBER 1
 '@T6G_MB_LIB.T6G(SCH_1):PAGE411_I49@PURE_QUANTA.Q_CAP(CHIPS)':
 C_PATH='@t6g_mb_lib.t6g(sch_1):page411_i49@pure_quanta.q_cap(chips)',
 P_PATH='@t6g_mb_lib.t6g(sch_1):page290_i49@pure_quanta.q_cap(chips)',
 PATH='I49',
 DRAWING='@T6G_MB_LIB.T6G(SCH_1):PAGE411',
 TOLERANCE='20%',
 MATERIAL='X6S',
 PHYS_PAGE='290',
 XY='(-2250,2625)',
 ROT='0',
 VER='1',
 PACK_TYPE='0201',
 LOCATION='C654',
 CDS_LIB='pure_quanta',
 CDS_PART_NAME='Q_CAP_0201-1UF,4V,20%,X6S,CH-10KMEE00',
 VOLTAGE='4V',
 PART_NUMBER='CH-10KMEE00',
 VALUE='1UF',
 PRIM_FILE='./archive_libs/logical/q_cap/chips/chips.prt';

PART_NAME
 C655 'Q_CAP_0201-1UF,4V,20%,X6S,CH-10KMEE00':;

SECTION_NUMBER 1
 '@T6G_MB_LIB.T6G(SCH_1):PAGE411_I76@PURE_QUANTA.Q_CAP(CHIPS)':
 C_PATH='@t6g_mb_lib.t6g(sch_1):page411_i76@pure_quanta.q_cap(chips)',
 P_PATH='@t6g_mb_lib.t6g(sch_1):page290_i76@pure_quanta.q_cap(chips)',
 PATH='I76',
 DRAWING='@T6G_MB_LIB.T6G(SCH_1):PAGE411',
 TOLERANCE='20%',
 MATERIAL='X6S',
 PHYS_PAGE='290',
 XY='(-2400,5150)',
 ROT='0',
 VER='1',
 PACK_TYPE='0201',
 LOCATION='C655',
 CDS_LIB='pure_quanta',
 CDS_PART_NAME='Q_CAP_0201-1UF,4V,20%,X6S,CH-10KMEE00',
 VOLTAGE='4V',
 PART_NUMBER='CH-10KMEE00',
 VALUE='1UF',
 PRIM_FILE='./archive_libs/logical/q_cap/chips/chips.prt';

PART_NAME
 C656 'Q_CAP_C0402-22UF,4V,20%,X6S,CH622KMEB02':;

SECTION_NUMBER 1
 '@T6G_MB_LIB.T6G(SCH_1):PAGE411_I77@PURE_QUANTA.Q_CAP(CHIPS)':
 C_PATH='@t6g_mb_lib.t6g(sch_1):page411_i77@pure_quanta.q_cap(chips)',
 P_PATH='@t6g_mb_lib.t6g(sch_1):page290_i77@pure_quanta.q_cap(chips)',
 PATH='I77',
 DRAWING='@T6G_MB_LIB.T6G(SCH_1):PAGE411',
 TOLERANCE='20%',
 MATERIAL='X6S',
 PHYS_PAGE='290',
 XY='(-2050,3900)',
 ROT='0',
 VER='1',
 PACK_TYPE='C0402',
 LOCATION='C656',
 CDS_LIB='pure_quanta',
 CDS_PART_NAME='Q_CAP_C0402-22UF,4V,20%,X6S,CH622KMEB02',
 VOLTAGE='4V',
 PART_NUMBER='CH622KMEB02',
 VALUE='22UF',
 PRIM_FILE='./archive_libs/logical/q_cap/chips/chips.prt';

PART_NAME
 C657 'Q_CAP_C0201-0.1UF,10V,10%,X7S,CH4102K6E00':;

SECTION_NUMBER 1
 '@T6G_MB_LIB.T6G(SCH_1):PAGE411_I43@PURE_QUANTA.Q_CAP(CHIPS)':
 C_PATH='@t6g_mb_lib.t6g(sch_1):page411_i43@pure_quanta.q_cap(chips)',
 P_PATH='@t6g_mb_lib.t6g(sch_1):page290_i43@pure_quanta.q_cap(chips)',
 PATH='I43',
 DRAWING='@T6G_MB_LIB.T6G(SCH_1):PAGE411',
 TOLERANCE='10%',
 MATERIAL='X7S',
 PHYS_PAGE='290',
 XY='(-2850,1950)',
 ROT='0',
 VER='1',
 PACK_TYPE='C0201',
 LOCATION='C657',
 CDS_LIB='pure_quanta',
 CDS_PART_NAME='Q_CAP_C0201-0.1UF,10V,10%,X7S,CH4102K6E00',
 VOLTAGE='10V',
 PART_NUMBER='CH4102K6E00',
 VALUE='0.1UF',
 PRIM_FILE='./archive_libs/logical/q_cap/chips/chips.prt';

PART_NAME
 C658 'Q_CAP_C0201-0.1UF,10V,10%,X7S,CH4102K6E00':;

SECTION_NUMBER 1
 '@T6G_MB_LIB.T6G(SCH_1):PAGE411_I92@PURE_QUANTA.Q_CAP(CHIPS)':
 C_PATH='@t6g_mb_lib.t6g(sch_1):page411_i92@pure_quanta.q_cap(chips)',
 P_PATH='@t6g_mb_lib.t6g(sch_1):page290_i92@pure_quanta.q_cap(chips)',
 PATH='I92',
 DRAWING='@T6G_MB_LIB.T6G(SCH_1):PAGE411',
 TOLERANCE='10%',
 MATERIAL='X7S',
 PHYS_PAGE='290',
 XY='(-1975,2625)',
 ROT='0',
 VER='1',
 PACK_TYPE='C0201',
 LOCATION='C658',
 CDS_LIB='pure_quanta',
 CDS_PART_NAME='Q_CAP_C0201-0.1UF,10V,10%,X7S,CH4102K6E00',
 VOLTAGE='10V',
 PART_NUMBER='CH4102K6E00',
 VALUE='0.1UF',
 PRIM_FILE='./archive_libs/logical/q_cap/chips/chips.prt';

PART_NAME
 C659 'Q_CAP_C0201-0.1UF,10V,10%,X7S,CH4102K6E00':;

SECTION_NUMBER 1
 '@T6G_MB_LIB.T6G(SCH_1):PAGE411_I93@PURE_QUANTA.Q_CAP(CHIPS)':
 C_PATH='@t6g_mb_lib.t6g(sch_1):page411_i93@pure_quanta.q_cap(chips)',
 P_PATH='@t6g_mb_lib.t6g(sch_1):page290_i93@pure_quanta.q_cap(chips)',
 PATH='I93',
 DRAWING='@T6G_MB_LIB.T6G(SCH_1):PAGE411',
 TOLERANCE='10%',
 MATERIAL='X7S',
 PHYS_PAGE='290',
 XY='(-1700,2625)',
 ROT='0',
 VER='1',
 PACK_TYPE='C0201',
 LOCATION='C659',
 CDS_LIB='pure_quanta',
 CDS_PART_NAME='Q_CAP_C0201-0.1UF,10V,10%,X7S,CH4102K6E00',
 VOLTAGE='10V',
 PART_NUMBER='CH4102K6E00',
 VALUE='0.1UF',
 PRIM_FILE='./archive_libs/logical/q_cap/chips/chips.prt';

PART_NAME
 C660 'Q_CAP_0201-1UF,4V,20%,X6S,CH-10KMEE00':;

SECTION_NUMBER 1
 '@T6G_MB_LIB.T6G(SCH_1):PAGE411_I94@PURE_QUANTA.Q_CAP(CHIPS)':
 C_PATH='@t6g_mb_lib.t6g(sch_1):page411_i94@pure_quanta.q_cap(chips)',
 P_PATH='@t6g_mb_lib.t6g(sch_1):page290_i94@pure_quanta.q_cap(chips)',
 PATH='I94',
 DRAWING='@T6G_MB_LIB.T6G(SCH_1):PAGE411',
 TOLERANCE='20%',
 MATERIAL='X6S',
 PHYS_PAGE='290',
 XY='(-1825,3275)',
 ROT='0',
 VER='1',
 PACK_TYPE='0201',
 LOCATION='C660',
 CDS_LIB='pure_quanta',
 CDS_PART_NAME='Q_CAP_0201-1UF,4V,20%,X6S,CH-10KMEE00',
 VOLTAGE='4V',
 PART_NUMBER='CH-10KMEE00',
 VALUE='1UF',
 PRIM_FILE='./archive_libs/logical/q_cap/chips/chips.prt';

PART_NAME
 C661 'Q_CAP_C0402-10UF,6.3V,20%,X6S,CH6101MEB01':;

SECTION_NUMBER 1
 '@T6G_MB_LIB.T6G(SCH_1):PAGE411_I78@PURE_QUANTA.Q_CAP(CHIPS)':
 C_PATH='@t6g_mb_lib.t6g(sch_1):page411_i78@pure_quanta.q_cap(chips)',
 P_PATH='@t6g_mb_lib.t6g(sch_1):page290_i78@pure_quanta.q_cap(chips)',
 PATH='I78',
 DRAWING='@T6G_MB_LIB.T6G(SCH_1):PAGE411',
 TOLERANCE='20%',
 MATERIAL='X6S',
 PHYS_PAGE='290',
 XY='(-1750,3900)',
 ROT='0',
 VER='1',
 PACK_TYPE='C0402',
 LOCATION='C661',
 CDS_LIB='pure_quanta',
 CDS_PART_NAME='Q_CAP_C0402-10UF,6.3V,20%,X6S,CH6101MEB01',
 VOLTAGE='6.3V',
 PART_NUMBER='CH6101MEB01',
 VALUE='10UF',
 PRIM_FILE='./archive_libs/logical/q_cap/chips/chips.prt';

PART_NAME
 C662 'Q_CAP_C0201-0.1UF,10V,10%,X7S,CH4102K6E00':;

SECTION_NUMBER 1
 '@T6G_MB_LIB.T6G(SCH_1):PAGE411_I37@PURE_QUANTA.Q_CAP(CHIPS)':
 C_PATH='@t6g_mb_lib.t6g(sch_1):page411_i37@pure_quanta.q_cap(chips)',
 P_PATH='@t6g_mb_lib.t6g(sch_1):page290_i37@pure_quanta.q_cap(chips)',
 PATH='I37',
 DRAWING='@T6G_MB_LIB.T6G(SCH_1):PAGE411',
 TOLERANCE='10%',
 MATERIAL='X7S',
 PHYS_PAGE='290',
 XY='(-3375,1950)',
 ROT='0',
 VER='1',
 PACK_TYPE='C0201',
 LOCATION='C662',
 CDS_LIB='pure_quanta',
 CDS_PART_NAME='Q_CAP_C0201-0.1UF,10V,10%,X7S,CH4102K6E00',
 VOLTAGE='10V',
 PART_NUMBER='CH4102K6E00',
 VALUE='0.1UF',
 PRIM_FILE='./archive_libs/logical/q_cap/chips/chips.prt';

PART_NAME
 C663 'Q_CAP_C0402-22UF,4V,20%,X6S,CH622KMEB02':;

SECTION_NUMBER 1
 '@T6G_MB_LIB.T6G(SCH_1):PAGE411_I72@PURE_QUANTA.Q_CAP(CHIPS)':
 C_PATH='@t6g_mb_lib.t6g(sch_1):page411_i72@pure_quanta.q_cap(chips)',
 P_PATH='@t6g_mb_lib.t6g(sch_1):page290_i72@pure_quanta.q_cap(chips)',
 PATH='I72',
 DRAWING='@T6G_MB_LIB.T6G(SCH_1):PAGE411',
 TOLERANCE='20%',
 MATERIAL='X6S',
 PHYS_PAGE='290',
 XY='(-2500,3900)',
 ROT='0',
 VER='1',
 PACK_TYPE='C0402',
 LOCATION='C663',
 CDS_LIB='pure_quanta',
 CDS_PART_NAME='Q_CAP_C0402-22UF,4V,20%,X6S,CH622KMEB02',
 VOLTAGE='4V',
 PART_NUMBER='CH622KMEB02',
 VALUE='22UF',
 PRIM_FILE='./archive_libs/logical/q_cap/chips/chips.prt';

PART_NAME
 C664 'Q_CAP_C0201-0.1UF,10V,10%,X7S,CH4102K6E00':;

SECTION_NUMBER 1
 '@T6G_MB_LIB.T6G(SCH_1):PAGE410_I24@PURE_QUANTA.Q_CAP(CHIPS)':
 C_PATH='@t6g_mb_lib.t6g(sch_1):page410_i24@pure_quanta.q_cap(chips)',
 P_PATH='@t6g_mb_lib.t6g(sch_1):page289_i24@pure_quanta.q_cap(chips)',
 PATH='I24',
 DRAWING='@T6G_MB_LIB.T6G(SCH_1):PAGE410',
 TOLERANCE='10%',
 MATERIAL='X7S',
 PHYS_PAGE='289',
 XY='(-4500,6075)',
 ROT='0',
 VER='1',
 PACK_TYPE='C0201',
 LOCATION='C664',
 CDS_LIB='pure_quanta',
 CDS_PART_NAME='Q_CAP_C0201-0.1UF,10V,10%,X7S,CH4102K6E00',
 VOLTAGE='10V',
 PART_NUMBER='CH4102K6E00',
 VALUE='0.1UF',
 PRIM_FILE='./archive_libs/logical/q_cap/chips/chips.prt';

PART_NAME
 C665 'Q_CAP_C0805-100UF,4V,20%,X6S,CH710KMEA01':;

SECTION_NUMBER 1
 '@T6G_MB_LIB.T6G(SCH_1):PAGE422_I25@PURE_QUANTA.Q_CAP(CHIPS)':
 C_PATH='@t6g_mb_lib.t6g(sch_1):page422_i25@pure_quanta.q_cap(chips)',
 P_PATH='@t6g_mb_lib.t6g(sch_1):page301_i25@pure_quanta.q_cap(chips)',
 PATH='I25',
 DRAWING='@T6G_MB_LIB.T6G(SCH_1):PAGE422',
 TOLERANCE='20%',
 MATERIAL='X6S',
 PHYS_PAGE='301',
 XY='(-6900,5300)',
 ROT='0',
 VER='1',
 PACK_TYPE='C0805',
 LOCATION='C665',
 CDS_LIB='pure_quanta',
 CDS_PART_NAME='Q_CAP_C0805-100UF,4V,20%,X6S,CH710KMEA01',
 VOLTAGE='4V',
 PART_NUMBER='CH710KMEA01',
 VALUE='100UF',
 PRIM_FILE='./archive_libs/logical/q_cap/chips/chips.prt';

PART_NAME
 C666 'Q_CAP_C0805-100UF,4V,20%,X6S,CH710KMEA01':;

SECTION_NUMBER 1
 '@T6G_MB_LIB.T6G(SCH_1):PAGE422_I6@PURE_QUANTA.Q_CAP(CHIPS)':
 C_PATH='@t6g_mb_lib.t6g(sch_1):page422_i6@pure_quanta.q_cap(chips)',
 P_PATH='@t6g_mb_lib.t6g(sch_1):page301_i6@pure_quanta.q_cap(chips)',
 PATH='I6',
 DRAWING='@T6G_MB_LIB.T6G(SCH_1):PAGE422',
 TOLERANCE='20%',
 MATERIAL='X6S',
 PHYS_PAGE='301',
 XY='(-7050,4475)',
 ROT='0',
 VER='1',
 PACK_TYPE='C0805',
 LOCATION='C666',
 CDS_LIB='pure_quanta',
 CDS_PART_NAME='Q_CAP_C0805-100UF,4V,20%,X6S,CH710KMEA01',
 VOLTAGE='4V',
 PART_NUMBER='CH710KMEA01',
 VALUE='100UF',
 PRIM_FILE='./archive_libs/logical/q_cap/chips/chips.prt';

PART_NAME
 C667 'Q_CAP_C0402-22UF,4V,20%,X6S,CH622KMEB02':;

SECTION_NUMBER 1
 '@T6G_MB_LIB.T6G(SCH_1):PAGE422_I27@PURE_QUANTA.Q_CAP(CHIPS)':
 C_PATH='@t6g_mb_lib.t6g(sch_1):page422_i27@pure_quanta.q_cap(chips)',
 P_PATH='@t6g_mb_lib.t6g(sch_1):page301_i27@pure_quanta.q_cap(chips)',
 PATH='I27',
 DRAWING='@T6G_MB_LIB.T6G(SCH_1):PAGE422',
 TOLERANCE='20%',
 MATERIAL='X6S',
 PHYS_PAGE='301',
 XY='(-6650,5300)',
 ROT='0',
 VER='1',
 PACK_TYPE='C0402',
 LOCATION='C667',
 CDS_LIB='pure_quanta',
 CDS_PART_NAME='Q_CAP_C0402-22UF,4V,20%,X6S,CH622KMEB02',
 VOLTAGE='4V',
 PART_NUMBER='CH622KMEB02',
 VALUE='22UF',
 PRIM_FILE='./archive_libs/logical/q_cap/chips/chips.prt';

PART_NAME
 C668 'Q_CAP_C0402-22UF,4V,20%,X6S,CH622KMEB02':;

SECTION_NUMBER 1
 '@T6G_MB_LIB.T6G(SCH_1):PAGE422_I7@PURE_QUANTA.Q_CAP(CHIPS)':
 C_PATH='@t6g_mb_lib.t6g(sch_1):page422_i7@pure_quanta.q_cap(chips)',
 P_PATH='@t6g_mb_lib.t6g(sch_1):page301_i7@pure_quanta.q_cap(chips)',
 PATH='I7',
 DRAWING='@T6G_MB_LIB.T6G(SCH_1):PAGE422',
 TOLERANCE='20%',
 MATERIAL='X6S',
 PHYS_PAGE='301',
 XY='(-6825,4475)',
 ROT='0',
 VER='1',
 PACK_TYPE='C0402',
 LOCATION='C668',
 CDS_LIB='pure_quanta',
 CDS_PART_NAME='Q_CAP_C0402-22UF,4V,20%,X6S,CH622KMEB02',
 VOLTAGE='4V',
 PART_NUMBER='CH622KMEB02',
 VALUE='22UF',
 PRIM_FILE='./archive_libs/logical/q_cap/chips/chips.prt';

PART_NAME
 C669 'Q_CAP_C0402-10UF,6.3V,20%,X6S,CH6101MEB01':;

SECTION_NUMBER 1
 '@T6G_MB_LIB.T6G(SCH_1):PAGE422_I26@PURE_QUANTA.Q_CAP(CHIPS)':
 C_PATH='@t6g_mb_lib.t6g(sch_1):page422_i26@pure_quanta.q_cap(chips)',
 P_PATH='@t6g_mb_lib.t6g(sch_1):page301_i26@pure_quanta.q_cap(chips)',
 PATH='I26',
 DRAWING='@T6G_MB_LIB.T6G(SCH_1):PAGE422',
 TOLERANCE='20%',
 MATERIAL='X6S',
 PHYS_PAGE='301',
 XY='(-6400,5275)',
 ROT='0',
 VER='1',
 PACK_TYPE='C0402',
 LOCATION='C669',
 CDS_LIB='pure_quanta',
 CDS_PART_NAME='Q_CAP_C0402-10UF,6.3V,20%,X6S,CH6101MEB01',
 VOLTAGE='6.3V',
 PART_NUMBER='CH6101MEB01',
 VALUE='10UF',
 PRIM_FILE='./archive_libs/logical/q_cap/chips/chips.prt';

PART_NAME
 C670 'Q_CAP_0402-4.7UF,6.3V,20%,X6S,CH5471MEB01':;

SECTION_NUMBER 1
 '@T6G_MB_LIB.T6G(SCH_1):PAGE422_I13@PURE_QUANTA.Q_CAP(CHIPS)':
 C_PATH='@t6g_mb_lib.t6g(sch_1):page422_i13@pure_quanta.q_cap(chips)',
 P_PATH='@t6g_mb_lib.t6g(sch_1):page301_i13@pure_quanta.q_cap(chips)',
 PATH='I13',
 DRAWING='@T6G_MB_LIB.T6G(SCH_1):PAGE422',
 TOLERANCE='20%',
 MATERIAL='X6S',
 PHYS_PAGE='301',
 XY='(-6425,4475)',
 ROT='0',
 VER='1',
 PACK_TYPE='0402',
 LOCATION='C670',
 CDS_LIB='pure_quanta',
 CDS_PART_NAME='Q_CAP_0402-4.7UF,6.3V,20%,X6S,CH5471MEB01',
 VOLTAGE='6.3V',
 PART_NUMBER='CH5471MEB01',
 VALUE='4.7UF',
 PRIM_FILE='./archive_libs/logical/q_cap/chips/chips.prt';

PART_NAME
 C671 'Q_CAP_C0402-10UF,6.3V,20%,X6S,CH6101MEB01':;

SECTION_NUMBER 1
 '@T6G_MB_LIB.T6G(SCH_1):PAGE422_I12@PURE_QUANTA.Q_CAP(CHIPS)':
 C_PATH='@t6g_mb_lib.t6g(sch_1):page422_i12@pure_quanta.q_cap(chips)',
 P_PATH='@t6g_mb_lib.t6g(sch_1):page301_i12@pure_quanta.q_cap(chips)',
 PATH='I12',
 DRAWING='@T6G_MB_LIB.T6G(SCH_1):PAGE422',
 TOLERANCE='20%',
 MATERIAL='X6S',
 PHYS_PAGE='301',
 XY='(-6625,4475)',
 ROT='0',
 VER='1',
 PACK_TYPE='C0402',
 LOCATION='C671',
 CDS_LIB='pure_quanta',
 CDS_PART_NAME='Q_CAP_C0402-10UF,6.3V,20%,X6S,CH6101MEB01',
 VOLTAGE='6.3V',
 PART_NUMBER='CH6101MEB01',
 VALUE='10UF',
 PRIM_FILE='./archive_libs/logical/q_cap/chips/chips.prt';

PART_NAME
 C672 'Q_CAP_0402-4.7UF,6.3V,20%,X6S,CH5471MEB01':;

SECTION_NUMBER 1
 '@T6G_MB_LIB.T6G(SCH_1):PAGE422_I29@PURE_QUANTA.Q_CAP(CHIPS)':
 C_PATH='@t6g_mb_lib.t6g(sch_1):page422_i29@pure_quanta.q_cap(chips)',
 P_PATH='@t6g_mb_lib.t6g(sch_1):page301_i29@pure_quanta.q_cap(chips)',
 PATH='I29',
 DRAWING='@T6G_MB_LIB.T6G(SCH_1):PAGE422',
 TOLERANCE='20%',
 MATERIAL='X6S',
 PHYS_PAGE='301',
 XY='(-6150,5275)',
 ROT='0',
 VER='1',
 PACK_TYPE='0402',
 LOCATION='C672',
 CDS_LIB='pure_quanta',
 CDS_PART_NAME='Q_CAP_0402-4.7UF,6.3V,20%,X6S,CH5471MEB01',
 VOLTAGE='6.3V',
 PART_NUMBER='CH5471MEB01',
 VALUE='4.7UF',
 PRIM_FILE='./archive_libs/logical/q_cap/chips/chips.prt';

PART_NAME
 C673 'Q_CAP_0201-1UF,4V,20%,X6S,CH-10KMEE00':;

SECTION_NUMBER 1
 '@T6G_MB_LIB.T6G(SCH_1):PAGE422_I15@PURE_QUANTA.Q_CAP(CHIPS)':
 C_PATH='@t6g_mb_lib.t6g(sch_1):page422_i15@pure_quanta.q_cap(chips)',
 P_PATH='@t6g_mb_lib.t6g(sch_1):page301_i15@pure_quanta.q_cap(chips)',
 PATH='I15',
 DRAWING='@T6G_MB_LIB.T6G(SCH_1):PAGE422',
 TOLERANCE='20%',
 MATERIAL='X6S',
 PHYS_PAGE='301',
 XY='(-6200,4475)',
 ROT='0',
 VER='1',
 PACK_TYPE='0201',
 LOCATION='C673',
 CDS_LIB='pure_quanta',
 CDS_PART_NAME='Q_CAP_0201-1UF,4V,20%,X6S,CH-10KMEE00',
 VOLTAGE='4V',
 PART_NUMBER='CH-10KMEE00',
 VALUE='1UF',
 PRIM_FILE='./archive_libs/logical/q_cap/chips/chips.prt';

PART_NAME
 C674 'Q_CAP_0402-0.1UF,25V,10%,EMPTY,CH4104K1B00':;

SECTION_NUMBER 1
 '@T6G_MB_LIB.T6G(SCH_1):PAGE184_I4@PURE_QUANTA.Q_CAP(CHIPS)':
 C_PATH='@t6g_mb_lib.t6g(sch_1):page184_i4@pure_quanta.q_cap(chips)',
 P_PATH='@t6g_mb_lib.t6g(sch_1):page209_i4@pure_quanta.q_cap(chips)',
 PATH='I4',
 DRAWING='@T6G_MB_LIB.T6G(SCH_1):PAGE184',
 TOLERANCE='10%',
 MATERIAL='EMPTY',
 PHYS_PAGE='209',
 XY='(-8575,3375)',
 ROT='2',
 VER='1',
 PACK_TYPE='0402',
 LOCATION='C674',
 CDS_LIB='pure_quanta',
 CDS_PART_NAME='Q_CAP_0402-0.1UF,25V,10%,EMPTY,CH4104K1B00',
 VOLTAGE='25V',
 PART_NUMBER='CH4104K1B00',
 VALUE='0.1UF',
 PRIM_FILE='./archive_libs/logical/q_cap/chips/chips.prt';

PART_NAME
 C675 'Q_CAP_0402-0.1UF,25V,10%,EMPTY,CH4104K1B00':;

SECTION_NUMBER 1
 '@T6G_MB_LIB.T6G(SCH_1):PAGE201_I6@PURE_QUANTA.Q_CAP(CHIPS)':
 C_PATH='@t6g_mb_lib.t6g(sch_1):page201_i6@pure_quanta.q_cap(chips)',
 P_PATH='@t6g_mb_lib.t6g(sch_1):page226_i6@pure_quanta.q_cap(chips)',
 PATH='I6',
 DRAWING='@T6G_MB_LIB.T6G(SCH_1):PAGE201',
 TOLERANCE='10%',
 MATERIAL='EMPTY',
 PHYS_PAGE='226',
 XY='(-7725,3850)',
 ROT='2',
 VER='1',
 PACK_TYPE='0402',
 LOCATION='C675',
 CDS_LIB='pure_quanta',
 CDS_PART_NAME='Q_CAP_0402-0.1UF,25V,10%,EMPTY,CH4104K1B00',
 VOLTAGE='25V',
 PART_NUMBER='CH4104K1B00',
 VALUE='0.1UF',
 PRIM_FILE='./archive_libs/logical/q_cap/chips/chips.prt';

PART_NAME
 C676 'Q_CAP_0201-1UF,4V,20%,X6S,CH-10KMEE00':;

SECTION_NUMBER 1
 '@T6G_MB_LIB.T6G(SCH_1):PAGE422_I9@PURE_QUANTA.Q_CAP(CHIPS)':
 C_PATH='@t6g_mb_lib.t6g(sch_1):page422_i9@pure_quanta.q_cap(chips)',
 P_PATH='@t6g_mb_lib.t6g(sch_1):page301_i9@pure_quanta.q_cap(chips)',
 PATH='I9',
 DRAWING='@T6G_MB_LIB.T6G(SCH_1):PAGE422',
 TOLERANCE='20%',
 MATERIAL='X6S',
 PHYS_PAGE='301',
 XY='(-6625,3400)',
 ROT='0',
 VER='1',
 PACK_TYPE='0201',
 LOCATION='C676',
 CDS_LIB='pure_quanta',
 CDS_PART_NAME='Q_CAP_0201-1UF,4V,20%,X6S,CH-10KMEE00',
 VOLTAGE='4V',
 PART_NUMBER='CH-10KMEE00',
 VALUE='1UF',
 PRIM_FILE='./archive_libs/logical/q_cap/chips/chips.prt';

PART_NAME
 C677 'Q_CAP_0201-1UF,4V,20%,X6S,CH-10KMEE00':;

SECTION_NUMBER 1
 '@T6G_MB_LIB.T6G(SCH_1):PAGE422_I16@PURE_QUANTA.Q_CAP(CHIPS)':
 C_PATH='@t6g_mb_lib.t6g(sch_1):page422_i16@pure_quanta.q_cap(chips)',
 P_PATH='@t6g_mb_lib.t6g(sch_1):page301_i16@pure_quanta.q_cap(chips)',
 PATH='I16',
 DRAWING='@T6G_MB_LIB.T6G(SCH_1):PAGE422',
 TOLERANCE='20%',
 MATERIAL='X6S',
 PHYS_PAGE='301',
 XY='(-6000,4475)',
 ROT='0',
 VER='1',
 PACK_TYPE='0201',
 LOCATION='C677',
 CDS_LIB='pure_quanta',
 CDS_PART_NAME='Q_CAP_0201-1UF,4V,20%,X6S,CH-10KMEE00',
 VOLTAGE='4V',
 PART_NUMBER='CH-10KMEE00',
 VALUE='1UF',
 PRIM_FILE='./archive_libs/logical/q_cap/chips/chips.prt';

PART_NAME
 C678 'Q_CAP_DIFFBUS_C0201-DIFF BUS_0.22UF,6.3V,20%,X6S,SA':;

SECTION_NUMBER 1
 '@T6G_MB_LIB.T6G(SCH_1):PAGE355_I251@PURE_QUANTA.Q_CAP_DIFFBUS(CHIPS)':
 C_PATH='@t6g_mb_lib.t6g(sch_1):page355_i251@pure_quanta.q_cap_diffbus(chips)',
 P_PATH='@t6g_mb_lib.t6g(sch_1):page67_i251@pure_quanta.q_cap_diffbus(chips)',
 PATH='I251',
 DRAWING='@T6G_MB_LIB.T6G(SCH_1):PAGE355',
 PIN_NAMES_ROTATE='TRUE',
 TOLERANCE='20%',
 MATERIAL='X6S',
 PHYS_PAGE='67',
 XY='(3125,4500)',
 ROT='2',
 VER='2',
 PACK_TYPE='C0201',
 LOCATION='C678',
 CDS_LIB='pure_quanta',
 CDS_PART_NAME='Q_CAP_DIFFBUS_C0201-DIFF BUS_0.22UF,6.3V,20%,X6S,SA',
 VOLTAGE='6.3V',
 PART_NUMBER='SP_CH4221MEE01',
 VALUE='DIFF BUS_0.22UF',
 PRIM_FILE='./archive_libs/logical/q_cap_diffbus/chips/chips.prt';

PART_NAME
 C679 'Q_CAP_DIFFBUS_C0201-DIFF BUS_0.22UF,6.3V,20%,X6S,SA':;

SECTION_NUMBER 1
 '@T6G_MB_LIB.T6G(SCH_1):PAGE355_I250@PURE_QUANTA.Q_CAP_DIFFBUS(CHIPS)':
 C_PATH='@t6g_mb_lib.t6g(sch_1):page355_i250@pure_quanta.q_cap_diffbus(chips)',
 P_PATH='@t6g_mb_lib.t6g(sch_1):page67_i250@pure_quanta.q_cap_diffbus(chips)',
 PATH='I250',
 DRAWING='@T6G_MB_LIB.T6G(SCH_1):PAGE355',
 PIN_NAMES_ROTATE='TRUE',
 TOLERANCE='20%',
 MATERIAL='X6S',
 PHYS_PAGE='67',
 XY='(3125,4450)',
 ROT='2',
 VER='2',
 PACK_TYPE='C0201',
 LOCATION='C679',
 CDS_LIB='pure_quanta',
 CDS_PART_NAME='Q_CAP_DIFFBUS_C0201-DIFF BUS_0.22UF,6.3V,20%,X6S,SA',
 VOLTAGE='6.3V',
 PART_NUMBER='SP_CH4221MEE01',
 VALUE='DIFF BUS_0.22UF',
 PRIM_FILE='./archive_libs/logical/q_cap_diffbus/chips/chips.prt';

PART_NAME
 C680 'Q_CAP_DIFFBUS_C0201-DIFF BUS_0.22UF,6.3V,20%,X6S,SA':;

SECTION_NUMBER 1
 '@T6G_MB_LIB.T6G(SCH_1):PAGE355_I249@PURE_QUANTA.Q_CAP_DIFFBUS(CHIPS)':
 C_PATH='@t6g_mb_lib.t6g(sch_1):page355_i249@pure_quanta.q_cap_diffbus(chips)',
 P_PATH='@t6g_mb_lib.t6g(sch_1):page67_i249@pure_quanta.q_cap_diffbus(chips)',
 PATH='I249',
 DRAWING='@T6G_MB_LIB.T6G(SCH_1):PAGE355',
 PIN_NAMES_ROTATE='TRUE',
 TOLERANCE='20%',
 MATERIAL='X6S',
 PHYS_PAGE='67',
 XY='(3125,4300)',
 ROT='2',
 VER='2',
 PACK_TYPE='C0201',
 LOCATION='C680',
 CDS_LIB='pure_quanta',
 CDS_PART_NAME='Q_CAP_DIFFBUS_C0201-DIFF BUS_0.22UF,6.3V,20%,X6S,SA',
 VOLTAGE='6.3V',
 PART_NUMBER='SP_CH4221MEE01',
 VALUE='DIFF BUS_0.22UF',
 PRIM_FILE='./archive_libs/logical/q_cap_diffbus/chips/chips.prt';

PART_NAME
 C681 'Q_CAP_DIFFBUS_C0201-DIFF BUS_0.22UF,6.3V,20%,X6S,SA':;

SECTION_NUMBER 1
 '@T6G_MB_LIB.T6G(SCH_1):PAGE355_I248@PURE_QUANTA.Q_CAP_DIFFBUS(CHIPS)':
 C_PATH='@t6g_mb_lib.t6g(sch_1):page355_i248@pure_quanta.q_cap_diffbus(chips)',
 P_PATH='@t6g_mb_lib.t6g(sch_1):page67_i248@pure_quanta.q_cap_diffbus(chips)',
 PATH='I248',
 DRAWING='@T6G_MB_LIB.T6G(SCH_1):PAGE355',
 PIN_NAMES_ROTATE='TRUE',
 TOLERANCE='20%',
 MATERIAL='X6S',
 PHYS_PAGE='67',
 XY='(3125,4250)',
 ROT='2',
 VER='2',
 PACK_TYPE='C0201',
 LOCATION='C681',
 CDS_LIB='pure_quanta',
 CDS_PART_NAME='Q_CAP_DIFFBUS_C0201-DIFF BUS_0.22UF,6.3V,20%,X6S,SA',
 VOLTAGE='6.3V',
 PART_NUMBER='SP_CH4221MEE01',
 VALUE='DIFF BUS_0.22UF',
 PRIM_FILE='./archive_libs/logical/q_cap_diffbus/chips/chips.prt';

PART_NAME
 C682 'Q_CAP_DIFFBUS_C0201-DIFF BUS_0.22UF,6.3V,20%,X6S,SA':;

SECTION_NUMBER 1
 '@T6G_MB_LIB.T6G(SCH_1):PAGE355_I247@PURE_QUANTA.Q_CAP_DIFFBUS(CHIPS)':
 C_PATH='@t6g_mb_lib.t6g(sch_1):page355_i247@pure_quanta.q_cap_diffbus(chips)',
 P_PATH='@t6g_mb_lib.t6g(sch_1):page67_i247@pure_quanta.q_cap_diffbus(chips)',
 PATH='I247',
 DRAWING='@T6G_MB_LIB.T6G(SCH_1):PAGE355',
 PIN_NAMES_ROTATE='TRUE',
 TOLERANCE='20%',
 MATERIAL='X6S',
 PHYS_PAGE='67',
 XY='(3125,4100)',
 ROT='2',
 VER='2',
 PACK_TYPE='C0201',
 LOCATION='C682',
 CDS_LIB='pure_quanta',
 CDS_PART_NAME='Q_CAP_DIFFBUS_C0201-DIFF BUS_0.22UF,6.3V,20%,X6S,SA',
 VOLTAGE='6.3V',
 PART_NUMBER='SP_CH4221MEE01',
 VALUE='DIFF BUS_0.22UF',
 PRIM_FILE='./archive_libs/logical/q_cap_diffbus/chips/chips.prt';

PART_NAME
 C683 'Q_CAP_DIFFBUS_C0201-DIFF BUS_0.22UF,6.3V,20%,X6S,SA':;

SECTION_NUMBER 1
 '@T6G_MB_LIB.T6G(SCH_1):PAGE355_I236@PURE_QUANTA.Q_CAP_DIFFBUS(CHIPS)':
 C_PATH='@t6g_mb_lib.t6g(sch_1):page355_i236@pure_quanta.q_cap_diffbus(chips)',
 P_PATH='@t6g_mb_lib.t6g(sch_1):page67_i236@pure_quanta.q_cap_diffbus(chips)',
 PATH='I236',
 DRAWING='@T6G_MB_LIB.T6G(SCH_1):PAGE355',
 PIN_NAMES_ROTATE='TRUE',
 TOLERANCE='20%',
 MATERIAL='X6S',
 PHYS_PAGE='67',
 XY='(3125,4050)',
 ROT='2',
 VER='2',
 PACK_TYPE='C0201',
 LOCATION='C683',
 CDS_LIB='pure_quanta',
 CDS_PART_NAME='Q_CAP_DIFFBUS_C0201-DIFF BUS_0.22UF,6.3V,20%,X6S,SA',
 VOLTAGE='6.3V',
 PART_NUMBER='SP_CH4221MEE01',
 VALUE='DIFF BUS_0.22UF',
 PRIM_FILE='./archive_libs/logical/q_cap_diffbus/chips/chips.prt';

PART_NAME
 C684 'Q_CAP_DIFFBUS_C0201-DIFF BUS_0.22UF,6.3V,20%,X6S,SA':;

SECTION_NUMBER 1
 '@T6G_MB_LIB.T6G(SCH_1):PAGE355_I225@PURE_QUANTA.Q_CAP_DIFFBUS(CHIPS)':
 C_PATH='@t6g_mb_lib.t6g(sch_1):page355_i225@pure_quanta.q_cap_diffbus(chips)',
 P_PATH='@t6g_mb_lib.t6g(sch_1):page67_i225@pure_quanta.q_cap_diffbus(chips)',
 PATH='I225',
 DRAWING='@T6G_MB_LIB.T6G(SCH_1):PAGE355',
 PIN_NAMES_ROTATE='TRUE',
 TOLERANCE='20%',
 MATERIAL='X6S',
 PHYS_PAGE='67',
 XY='(3125,3900)',
 ROT='2',
 VER='2',
 PACK_TYPE='C0201',
 LOCATION='C684',
 CDS_LIB='pure_quanta',
 CDS_PART_NAME='Q_CAP_DIFFBUS_C0201-DIFF BUS_0.22UF,6.3V,20%,X6S,SA',
 VOLTAGE='6.3V',
 PART_NUMBER='SP_CH4221MEE01',
 VALUE='DIFF BUS_0.22UF',
 PRIM_FILE='./archive_libs/logical/q_cap_diffbus/chips/chips.prt';

PART_NAME
 C685 'Q_CAP_DIFFBUS_C0201-DIFF BUS_0.22UF,6.3V,20%,X6S,SA':;

SECTION_NUMBER 1
 '@T6G_MB_LIB.T6G(SCH_1):PAGE355_I224@PURE_QUANTA.Q_CAP_DIFFBUS(CHIPS)':
 C_PATH='@t6g_mb_lib.t6g(sch_1):page355_i224@pure_quanta.q_cap_diffbus(chips)',
 P_PATH='@t6g_mb_lib.t6g(sch_1):page67_i224@pure_quanta.q_cap_diffbus(chips)',
 PATH='I224',
 DRAWING='@T6G_MB_LIB.T6G(SCH_1):PAGE355',
 PIN_NAMES_ROTATE='TRUE',
 TOLERANCE='20%',
 MATERIAL='X6S',
 PHYS_PAGE='67',
 XY='(3125,3850)',
 ROT='2',
 VER='2',
 PACK_TYPE='C0201',
 LOCATION='C685',
 CDS_LIB='pure_quanta',
 CDS_PART_NAME='Q_CAP_DIFFBUS_C0201-DIFF BUS_0.22UF,6.3V,20%,X6S,SA',
 VOLTAGE='6.3V',
 PART_NUMBER='SP_CH4221MEE01',
 VALUE='DIFF BUS_0.22UF',
 PRIM_FILE='./archive_libs/logical/q_cap_diffbus/chips/chips.prt';

PART_NAME
 C686 'Q_CAP_DIFFBUS_C0201-DIFF BUS_0.22UF,6.3V,20%,X6S,SA':;

SECTION_NUMBER 1
 '@T6G_MB_LIB.T6G(SCH_1):PAGE355_I223@PURE_QUANTA.Q_CAP_DIFFBUS(CHIPS)':
 C_PATH='@t6g_mb_lib.t6g(sch_1):page355_i223@pure_quanta.q_cap_diffbus(chips)',
 P_PATH='@t6g_mb_lib.t6g(sch_1):page67_i223@pure_quanta.q_cap_diffbus(chips)',
 PATH='I223',
 DRAWING='@T6G_MB_LIB.T6G(SCH_1):PAGE355',
 PIN_NAMES_ROTATE='TRUE',
 TOLERANCE='20%',
 MATERIAL='X6S',
 PHYS_PAGE='67',
 XY='(3125,3700)',
 ROT='2',
 VER='2',
 PACK_TYPE='C0201',
 LOCATION='C686',
 CDS_LIB='pure_quanta',
 CDS_PART_NAME='Q_CAP_DIFFBUS_C0201-DIFF BUS_0.22UF,6.3V,20%,X6S,SA',
 VOLTAGE='6.3V',
 PART_NUMBER='SP_CH4221MEE01',
 VALUE='DIFF BUS_0.22UF',
 PRIM_FILE='./archive_libs/logical/q_cap_diffbus/chips/chips.prt';

PART_NAME
 C687 'Q_CAP_DIFFBUS_C0201-DIFF BUS_0.22UF,6.3V,20%,X6S,SA':;

SECTION_NUMBER 1
 '@T6G_MB_LIB.T6G(SCH_1):PAGE355_I222@PURE_QUANTA.Q_CAP_DIFFBUS(CHIPS)':
 C_PATH='@t6g_mb_lib.t6g(sch_1):page355_i222@pure_quanta.q_cap_diffbus(chips)',
 P_PATH='@t6g_mb_lib.t6g(sch_1):page67_i222@pure_quanta.q_cap_diffbus(chips)',
 PATH='I222',
 DRAWING='@T6G_MB_LIB.T6G(SCH_1):PAGE355',
 PIN_NAMES_ROTATE='TRUE',
 TOLERANCE='20%',
 MATERIAL='X6S',
 PHYS_PAGE='67',
 XY='(3125,3650)',
 ROT='2',
 VER='2',
 PACK_TYPE='C0201',
 LOCATION='C687',
 CDS_LIB='pure_quanta',
 CDS_PART_NAME='Q_CAP_DIFFBUS_C0201-DIFF BUS_0.22UF,6.3V,20%,X6S,SA',
 VOLTAGE='6.3V',
 PART_NUMBER='SP_CH4221MEE01',
 VALUE='DIFF BUS_0.22UF',
 PRIM_FILE='./archive_libs/logical/q_cap_diffbus/chips/chips.prt';

PART_NAME
 C688 'Q_CAP_DIFFBUS_C0201-DIFF BUS_0.22UF,6.3V,20%,X6S,SA':;

SECTION_NUMBER 1
 '@T6G_MB_LIB.T6G(SCH_1):PAGE355_I220@PURE_QUANTA.Q_CAP_DIFFBUS(CHIPS)':
 C_PATH='@t6g_mb_lib.t6g(sch_1):page355_i220@pure_quanta.q_cap_diffbus(chips)',
 P_PATH='@t6g_mb_lib.t6g(sch_1):page67_i220@pure_quanta.q_cap_diffbus(chips)',
 PATH='I220',
 DRAWING='@T6G_MB_LIB.T6G(SCH_1):PAGE355',
 PIN_NAMES_ROTATE='TRUE',
 TOLERANCE='20%',
 MATERIAL='X6S',
 PHYS_PAGE='67',
 XY='(3125,3500)',
 ROT='2',
 VER='2',
 PACK_TYPE='C0201',
 LOCATION='C688',
 CDS_LIB='pure_quanta',
 CDS_PART_NAME='Q_CAP_DIFFBUS_C0201-DIFF BUS_0.22UF,6.3V,20%,X6S,SA',
 VOLTAGE='6.3V',
 PART_NUMBER='SP_CH4221MEE01',
 VALUE='DIFF BUS_0.22UF',
 PRIM_FILE='./archive_libs/logical/q_cap_diffbus/chips/chips.prt';

PART_NAME
 C689 'Q_CAP_DIFFBUS_C0201-DIFF BUS_0.22UF,6.3V,20%,X6S,SA':;

SECTION_NUMBER 1
 '@T6G_MB_LIB.T6G(SCH_1):PAGE355_I221@PURE_QUANTA.Q_CAP_DIFFBUS(CHIPS)':
 C_PATH='@t6g_mb_lib.t6g(sch_1):page355_i221@pure_quanta.q_cap_diffbus(chips)',
 P_PATH='@t6g_mb_lib.t6g(sch_1):page67_i221@pure_quanta.q_cap_diffbus(chips)',
 PATH='I221',
 DRAWING='@T6G_MB_LIB.T6G(SCH_1):PAGE355',
 PIN_NAMES_ROTATE='TRUE',
 TOLERANCE='20%',
 MATERIAL='X6S',
 PHYS_PAGE='67',
 XY='(3125,3450)',
 ROT='2',
 VER='2',
 PACK_TYPE='C0201',
 LOCATION='C689',
 CDS_LIB='pure_quanta',
 CDS_PART_NAME='Q_CAP_DIFFBUS_C0201-DIFF BUS_0.22UF,6.3V,20%,X6S,SA',
 VOLTAGE='6.3V',
 PART_NUMBER='SP_CH4221MEE01',
 VALUE='DIFF BUS_0.22UF',
 PRIM_FILE='./archive_libs/logical/q_cap_diffbus/chips/chips.prt';

PART_NAME
 C690 'Q_CAP_DIFFBUS_C0201-DIFF BUS_0.22UF,6.3V,20%,X6S,SA':;

SECTION_NUMBER 1
 '@T6G_MB_LIB.T6G(SCH_1):PAGE355_I219@PURE_QUANTA.Q_CAP_DIFFBUS(CHIPS)':
 C_PATH='@t6g_mb_lib.t6g(sch_1):page355_i219@pure_quanta.q_cap_diffbus(chips)',
 P_PATH='@t6g_mb_lib.t6g(sch_1):page67_i219@pure_quanta.q_cap_diffbus(chips)',
 PATH='I219',
 DRAWING='@T6G_MB_LIB.T6G(SCH_1):PAGE355',
 PIN_NAMES_ROTATE='TRUE',
 TOLERANCE='20%',
 MATERIAL='X6S',
 PHYS_PAGE='67',
 XY='(3125,3300)',
 ROT='2',
 VER='2',
 PACK_TYPE='C0201',
 LOCATION='C690',
 CDS_LIB='pure_quanta',
 CDS_PART_NAME='Q_CAP_DIFFBUS_C0201-DIFF BUS_0.22UF,6.3V,20%,X6S,SA',
 VOLTAGE='6.3V',
 PART_NUMBER='SP_CH4221MEE01',
 VALUE='DIFF BUS_0.22UF',
 PRIM_FILE='./archive_libs/logical/q_cap_diffbus/chips/chips.prt';

PART_NAME
 C691 'Q_CAP_DIFFBUS_C0201-DIFF BUS_0.22UF,6.3V,20%,X6S,SA':;

SECTION_NUMBER 1
 '@T6G_MB_LIB.T6G(SCH_1):PAGE355_I218@PURE_QUANTA.Q_CAP_DIFFBUS(CHIPS)':
 C_PATH='@t6g_mb_lib.t6g(sch_1):page355_i218@pure_quanta.q_cap_diffbus(chips)',
 P_PATH='@t6g_mb_lib.t6g(sch_1):page67_i218@pure_quanta.q_cap_diffbus(chips)',
 PATH='I218',
 DRAWING='@T6G_MB_LIB.T6G(SCH_1):PAGE355',
 PIN_NAMES_ROTATE='TRUE',
 TOLERANCE='20%',
 MATERIAL='X6S',
 PHYS_PAGE='67',
 XY='(3125,3250)',
 ROT='2',
 VER='2',
 PACK_TYPE='C0201',
 LOCATION='C691',
 CDS_LIB='pure_quanta',
 CDS_PART_NAME='Q_CAP_DIFFBUS_C0201-DIFF BUS_0.22UF,6.3V,20%,X6S,SA',
 VOLTAGE='6.3V',
 PART_NUMBER='SP_CH4221MEE01',
 VALUE='DIFF BUS_0.22UF',
 PRIM_FILE='./archive_libs/logical/q_cap_diffbus/chips/chips.prt';

PART_NAME
 C692 'Q_CAP_DIFFBUS_C0201-DIFF BUS_0.22UF,6.3V,20%,X6S,SA':;

SECTION_NUMBER 1
 '@T6G_MB_LIB.T6G(SCH_1):PAGE355_I217@PURE_QUANTA.Q_CAP_DIFFBUS(CHIPS)':
 C_PATH='@t6g_mb_lib.t6g(sch_1):page355_i217@pure_quanta.q_cap_diffbus(chips)',
 P_PATH='@t6g_mb_lib.t6g(sch_1):page67_i217@pure_quanta.q_cap_diffbus(chips)',
 PATH='I217',
 DRAWING='@T6G_MB_LIB.T6G(SCH_1):PAGE355',
 PIN_NAMES_ROTATE='TRUE',
 TOLERANCE='20%',
 MATERIAL='X6S',
 PHYS_PAGE='67',
 XY='(3125,3100)',
 ROT='2',
 VER='2',
 PACK_TYPE='C0201',
 LOCATION='C692',
 CDS_LIB='pure_quanta',
 CDS_PART_NAME='Q_CAP_DIFFBUS_C0201-DIFF BUS_0.22UF,6.3V,20%,X6S,SA',
 VOLTAGE='6.3V',
 PART_NUMBER='SP_CH4221MEE01',
 VALUE='DIFF BUS_0.22UF',
 PRIM_FILE='./archive_libs/logical/q_cap_diffbus/chips/chips.prt';

PART_NAME
 C693 'Q_CAP_0402-0.1UF,25V,10%,X7R,CH4104K1B00':;

SECTION_NUMBER 1
 '@T6G_MB_LIB.T6G(SCH_1):PAGE144_I39@PURE_QUANTA.Q_CAP(CHIPS)':
 C_PATH='@t6g_mb_lib.t6g(sch_1):page144_i39@pure_quanta.q_cap(chips)',
 P_PATH='@t6g_mb_lib.t6g(sch_1):page167_i39@pure_quanta.q_cap(chips)',
 PATH='I39',
 DRAWING='@T6G_MB_LIB.T6G(SCH_1):PAGE144',
 TOLERANCE='10%',
 MATERIAL='X7R',
 PHYS_PAGE='167',
 XY='(-4875,1075)',
 ROT='0',
 VER='1',
 PACK_TYPE='0402',
 LOCATION='C693',
 CDS_LIB='pure_quanta',
 CDS_PART_NAME='Q_CAP_0402-0.1UF,25V,10%,X7R,CH4104K1B00',
 VOLTAGE='25V',
 PART_NUMBER='CH4104K1B00',
 VALUE='0.1UF',
 PRIM_FILE='./archive_libs/logical/q_cap/chips/chips.prt';

PART_NAME
 C694 'Q_CAP_DIFFBUS_C0201-DIFF BUS_0.22UF,6.3V,20%,X6S,SA':;

SECTION_NUMBER 1
 '@T6G_MB_LIB.T6G(SCH_1):PAGE355_I206@PURE_QUANTA.Q_CAP_DIFFBUS(CHIPS)':
 C_PATH='@t6g_mb_lib.t6g(sch_1):page355_i206@pure_quanta.q_cap_diffbus(chips)',
 P_PATH='@t6g_mb_lib.t6g(sch_1):page67_i206@pure_quanta.q_cap_diffbus(chips)',
 PATH='I206',
 DRAWING='@T6G_MB_LIB.T6G(SCH_1):PAGE355',
 PIN_NAMES_ROTATE='TRUE',
 TOLERANCE='20%',
 MATERIAL='X6S',
 PHYS_PAGE='67',
 XY='(3125,2900)',
 ROT='2',
 VER='2',
 PACK_TYPE='C0201',
 LOCATION='C694',
 CDS_LIB='pure_quanta',
 CDS_PART_NAME='Q_CAP_DIFFBUS_C0201-DIFF BUS_0.22UF,6.3V,20%,X6S,SA',
 VOLTAGE='6.3V',
 PART_NUMBER='SP_CH4221MEE01',
 VALUE='DIFF BUS_0.22UF',
 PRIM_FILE='./archive_libs/logical/q_cap_diffbus/chips/chips.prt';

PART_NAME
 C695 'Q_CAP_DIFFBUS_C0201-DIFF BUS_0.22UF,6.3V,20%,X6S,SA':;

SECTION_NUMBER 1
 '@T6G_MB_LIB.T6G(SCH_1):PAGE355_I205@PURE_QUANTA.Q_CAP_DIFFBUS(CHIPS)':
 C_PATH='@t6g_mb_lib.t6g(sch_1):page355_i205@pure_quanta.q_cap_diffbus(chips)',
 P_PATH='@t6g_mb_lib.t6g(sch_1):page67_i205@pure_quanta.q_cap_diffbus(chips)',
 PATH='I205',
 DRAWING='@T6G_MB_LIB.T6G(SCH_1):PAGE355',
 PIN_NAMES_ROTATE='TRUE',
 TOLERANCE='20%',
 MATERIAL='X6S',
 PHYS_PAGE='67',
 XY='(3125,2850)',
 ROT='2',
 VER='2',
 PACK_TYPE='C0201',
 LOCATION='C695',
 CDS_LIB='pure_quanta',
 CDS_PART_NAME='Q_CAP_DIFFBUS_C0201-DIFF BUS_0.22UF,6.3V,20%,X6S,SA',
 VOLTAGE='6.3V',
 PART_NUMBER='SP_CH4221MEE01',
 VALUE='DIFF BUS_0.22UF',
 PRIM_FILE='./archive_libs/logical/q_cap_diffbus/chips/chips.prt';

PART_NAME
 C696 'Q_CAP_DIFFBUS_C0201-DIFF BUS_0.22UF,6.3V,20%,X6S,SA':;

SECTION_NUMBER 1
 '@T6G_MB_LIB.T6G(SCH_1):PAGE355_I204@PURE_QUANTA.Q_CAP_DIFFBUS(CHIPS)':
 C_PATH='@t6g_mb_lib.t6g(sch_1):page355_i204@pure_quanta.q_cap_diffbus(chips)',
 P_PATH='@t6g_mb_lib.t6g(sch_1):page67_i204@pure_quanta.q_cap_diffbus(chips)',
 PATH='I204',
 DRAWING='@T6G_MB_LIB.T6G(SCH_1):PAGE355',
 PIN_NAMES_ROTATE='TRUE',
 TOLERANCE='20%',
 MATERIAL='X6S',
 PHYS_PAGE='67',
 XY='(3125,2700)',
 ROT='2',
 VER='2',
 PACK_TYPE='C0201',
 LOCATION='C696',
 CDS_LIB='pure_quanta',
 CDS_PART_NAME='Q_CAP_DIFFBUS_C0201-DIFF BUS_0.22UF,6.3V,20%,X6S,SA',
 VOLTAGE='6.3V',
 PART_NUMBER='SP_CH4221MEE01',
 VALUE='DIFF BUS_0.22UF',
 PRIM_FILE='./archive_libs/logical/q_cap_diffbus/chips/chips.prt';

PART_NAME
 C697 'Q_CAP_DIFFBUS_C0201-DIFF BUS_0.22UF,6.3V,20%,X6S,SA':;

SECTION_NUMBER 1
 '@T6G_MB_LIB.T6G(SCH_1):PAGE355_I203@PURE_QUANTA.Q_CAP_DIFFBUS(CHIPS)':
 C_PATH='@t6g_mb_lib.t6g(sch_1):page355_i203@pure_quanta.q_cap_diffbus(chips)',
 P_PATH='@t6g_mb_lib.t6g(sch_1):page67_i203@pure_quanta.q_cap_diffbus(chips)',
 PATH='I203',
 DRAWING='@T6G_MB_LIB.T6G(SCH_1):PAGE355',
 PIN_NAMES_ROTATE='TRUE',
 TOLERANCE='20%',
 MATERIAL='X6S',
 PHYS_PAGE='67',
 XY='(3125,2650)',
 ROT='2',
 VER='2',
 PACK_TYPE='C0201',
 LOCATION='C697',
 CDS_LIB='pure_quanta',
 CDS_PART_NAME='Q_CAP_DIFFBUS_C0201-DIFF BUS_0.22UF,6.3V,20%,X6S,SA',
 VOLTAGE='6.3V',
 PART_NUMBER='SP_CH4221MEE01',
 VALUE='DIFF BUS_0.22UF',
 PRIM_FILE='./archive_libs/logical/q_cap_diffbus/chips/chips.prt';

PART_NAME
 C698 'Q_CAP_DIFFBUS_C0201-DIFF BUS_0.22UF,6.3V,20%,X6S,SA':;

SECTION_NUMBER 1
 '@T6G_MB_LIB.T6G(SCH_1):PAGE355_I201@PURE_QUANTA.Q_CAP_DIFFBUS(CHIPS)':
 C_PATH='@t6g_mb_lib.t6g(sch_1):page355_i201@pure_quanta.q_cap_diffbus(chips)',
 P_PATH='@t6g_mb_lib.t6g(sch_1):page67_i201@pure_quanta.q_cap_diffbus(chips)',
 PATH='I201',
 DRAWING='@T6G_MB_LIB.T6G(SCH_1):PAGE355',
 PIN_NAMES_ROTATE='TRUE',
 TOLERANCE='20%',
 MATERIAL='X6S',
 PHYS_PAGE='67',
 XY='(3125,2500)',
 ROT='2',
 VER='2',
 PACK_TYPE='C0201',
 LOCATION='C698',
 CDS_LIB='pure_quanta',
 CDS_PART_NAME='Q_CAP_DIFFBUS_C0201-DIFF BUS_0.22UF,6.3V,20%,X6S,SA',
 VOLTAGE='6.3V',
 PART_NUMBER='SP_CH4221MEE01',
 VALUE='DIFF BUS_0.22UF',
 PRIM_FILE='./archive_libs/logical/q_cap_diffbus/chips/chips.prt';

PART_NAME
 C699 'Q_CAP_DIFFBUS_C0201-DIFF BUS_0.22UF,6.3V,20%,X6S,SA':;

SECTION_NUMBER 1
 '@T6G_MB_LIB.T6G(SCH_1):PAGE355_I202@PURE_QUANTA.Q_CAP_DIFFBUS(CHIPS)':
 C_PATH='@t6g_mb_lib.t6g(sch_1):page355_i202@pure_quanta.q_cap_diffbus(chips)',
 P_PATH='@t6g_mb_lib.t6g(sch_1):page67_i202@pure_quanta.q_cap_diffbus(chips)',
 PATH='I202',
 DRAWING='@T6G_MB_LIB.T6G(SCH_1):PAGE355',
 PIN_NAMES_ROTATE='TRUE',
 TOLERANCE='20%',
 MATERIAL='X6S',
 PHYS_PAGE='67',
 XY='(3125,2450)',
 ROT='2',
 VER='2',
 PACK_TYPE='C0201',
 LOCATION='C699',
 CDS_LIB='pure_quanta',
 CDS_PART_NAME='Q_CAP_DIFFBUS_C0201-DIFF BUS_0.22UF,6.3V,20%,X6S,SA',
 VOLTAGE='6.3V',
 PART_NUMBER='SP_CH4221MEE01',
 VALUE='DIFF BUS_0.22UF',
 PRIM_FILE='./archive_libs/logical/q_cap_diffbus/chips/chips.prt';

PART_NAME
 C700 'Q_CAP_DIFFBUS_C0201-DIFF BUS_0.22UF,6.3V,20%,X6S,SA':;

SECTION_NUMBER 1
 '@T6G_MB_LIB.T6G(SCH_1):PAGE355_I200@PURE_QUANTA.Q_CAP_DIFFBUS(CHIPS)':
 C_PATH='@t6g_mb_lib.t6g(sch_1):page355_i200@pure_quanta.q_cap_diffbus(chips)',
 P_PATH='@t6g_mb_lib.t6g(sch_1):page67_i200@pure_quanta.q_cap_diffbus(chips)',
 PATH='I200',
 DRAWING='@T6G_MB_LIB.T6G(SCH_1):PAGE355',
 PIN_NAMES_ROTATE='TRUE',
 TOLERANCE='20%',
 MATERIAL='X6S',
 PHYS_PAGE='67',
 XY='(3125,2300)',
 ROT='2',
 VER='2',
 PACK_TYPE='C0201',
 LOCATION='C700',
 CDS_LIB='pure_quanta',
 CDS_PART_NAME='Q_CAP_DIFFBUS_C0201-DIFF BUS_0.22UF,6.3V,20%,X6S,SA',
 VOLTAGE='6.3V',
 PART_NUMBER='SP_CH4221MEE01',
 VALUE='DIFF BUS_0.22UF',
 PRIM_FILE='./archive_libs/logical/q_cap_diffbus/chips/chips.prt';

PART_NAME
 C701 'Q_CAP_DIFFBUS_C0201-DIFF BUS_0.22UF,6.3V,20%,X6S,SA':;

SECTION_NUMBER 1
 '@T6G_MB_LIB.T6G(SCH_1):PAGE355_I199@PURE_QUANTA.Q_CAP_DIFFBUS(CHIPS)':
 C_PATH='@t6g_mb_lib.t6g(sch_1):page355_i199@pure_quanta.q_cap_diffbus(chips)',
 P_PATH='@t6g_mb_lib.t6g(sch_1):page67_i199@pure_quanta.q_cap_diffbus(chips)',
 PATH='I199',
 DRAWING='@T6G_MB_LIB.T6G(SCH_1):PAGE355',
 PIN_NAMES_ROTATE='TRUE',
 TOLERANCE='20%',
 MATERIAL='X6S',
 PHYS_PAGE='67',
 XY='(3125,2250)',
 ROT='2',
 VER='2',
 PACK_TYPE='C0201',
 LOCATION='C701',
 CDS_LIB='pure_quanta',
 CDS_PART_NAME='Q_CAP_DIFFBUS_C0201-DIFF BUS_0.22UF,6.3V,20%,X6S,SA',
 VOLTAGE='6.3V',
 PART_NUMBER='SP_CH4221MEE01',
 VALUE='DIFF BUS_0.22UF',
 PRIM_FILE='./archive_libs/logical/q_cap_diffbus/chips/chips.prt';

PART_NAME
 C702 'Q_CAP_DIFFBUS_C0201-DIFF BUS_0.22UF,6.3V,20%,X6S,SA':;

SECTION_NUMBER 1
 '@T6G_MB_LIB.T6G(SCH_1):PAGE355_I197@PURE_QUANTA.Q_CAP_DIFFBUS(CHIPS)':
 C_PATH='@t6g_mb_lib.t6g(sch_1):page355_i197@pure_quanta.q_cap_diffbus(chips)',
 P_PATH='@t6g_mb_lib.t6g(sch_1):page67_i197@pure_quanta.q_cap_diffbus(chips)',
 PATH='I197',
 DRAWING='@T6G_MB_LIB.T6G(SCH_1):PAGE355',
 PIN_NAMES_ROTATE='TRUE',
 TOLERANCE='20%',
 MATERIAL='X6S',
 PHYS_PAGE='67',
 XY='(3125,2100)',
 ROT='2',
 VER='2',
 PACK_TYPE='C0201',
 LOCATION='C702',
 CDS_LIB='pure_quanta',
 CDS_PART_NAME='Q_CAP_DIFFBUS_C0201-DIFF BUS_0.22UF,6.3V,20%,X6S,SA',
 VOLTAGE='6.3V',
 PART_NUMBER='SP_CH4221MEE01',
 VALUE='DIFF BUS_0.22UF',
 PRIM_FILE='./archive_libs/logical/q_cap_diffbus/chips/chips.prt';

PART_NAME
 C703 'Q_CAP_DIFFBUS_C0201-DIFF BUS_0.22UF,6.3V,20%,X6S,SA':;

SECTION_NUMBER 1
 '@T6G_MB_LIB.T6G(SCH_1):PAGE355_I198@PURE_QUANTA.Q_CAP_DIFFBUS(CHIPS)':
 C_PATH='@t6g_mb_lib.t6g(sch_1):page355_i198@pure_quanta.q_cap_diffbus(chips)',
 P_PATH='@t6g_mb_lib.t6g(sch_1):page67_i198@pure_quanta.q_cap_diffbus(chips)',
 PATH='I198',
 DRAWING='@T6G_MB_LIB.T6G(SCH_1):PAGE355',
 PIN_NAMES_ROTATE='TRUE',
 TOLERANCE='20%',
 MATERIAL='X6S',
 PHYS_PAGE='67',
 XY='(3125,2050)',
 ROT='2',
 VER='2',
 PACK_TYPE='C0201',
 LOCATION='C703',
 CDS_LIB='pure_quanta',
 CDS_PART_NAME='Q_CAP_DIFFBUS_C0201-DIFF BUS_0.22UF,6.3V,20%,X6S,SA',
 VOLTAGE='6.3V',
 PART_NUMBER='SP_CH4221MEE01',
 VALUE='DIFF BUS_0.22UF',
 PRIM_FILE='./archive_libs/logical/q_cap_diffbus/chips/chips.prt';

PART_NAME
 C704 'Q_CAP_DIFFBUS_C0201-DIFF BUS_0.22UF,6.3V,20%,X6S,SA':;

SECTION_NUMBER 1
 '@T6G_MB_LIB.T6G(SCH_1):PAGE355_I170@PURE_QUANTA.Q_CAP_DIFFBUS(CHIPS)':
 C_PATH='@t6g_mb_lib.t6g(sch_1):page355_i170@pure_quanta.q_cap_diffbus(chips)',
 P_PATH='@t6g_mb_lib.t6g(sch_1):page67_i170@pure_quanta.q_cap_diffbus(chips)',
 PATH='I170',
 DRAWING='@T6G_MB_LIB.T6G(SCH_1):PAGE355',
 PIN_NAMES_ROTATE='TRUE',
 TOLERANCE='20%',
 MATERIAL='X6S',
 PHYS_PAGE='67',
 XY='(3125,1900)',
 ROT='2',
 VER='2',
 PACK_TYPE='C0201',
 LOCATION='C704',
 CDS_LIB='pure_quanta',
 CDS_PART_NAME='Q_CAP_DIFFBUS_C0201-DIFF BUS_0.22UF,6.3V,20%,X6S,SA',
 VOLTAGE='6.3V',
 PART_NUMBER='SP_CH4221MEE01',
 VALUE='DIFF BUS_0.22UF',
 PRIM_FILE='./archive_libs/logical/q_cap_diffbus/chips/chips.prt';

PART_NAME
 C705 'Q_CAP_DIFFBUS_C0201-DIFF BUS_0.22UF,6.3V,20%,X6S,SA':;

SECTION_NUMBER 1
 '@T6G_MB_LIB.T6G(SCH_1):PAGE355_I169@PURE_QUANTA.Q_CAP_DIFFBUS(CHIPS)':
 C_PATH='@t6g_mb_lib.t6g(sch_1):page355_i169@pure_quanta.q_cap_diffbus(chips)',
 P_PATH='@t6g_mb_lib.t6g(sch_1):page67_i169@pure_quanta.q_cap_diffbus(chips)',
 PATH='I169',
 DRAWING='@T6G_MB_LIB.T6G(SCH_1):PAGE355',
 PIN_NAMES_ROTATE='TRUE',
 TOLERANCE='20%',
 MATERIAL='X6S',
 PHYS_PAGE='67',
 XY='(3125,1850)',
 ROT='2',
 VER='2',
 PACK_TYPE='C0201',
 LOCATION='C705',
 CDS_LIB='pure_quanta',
 CDS_PART_NAME='Q_CAP_DIFFBUS_C0201-DIFF BUS_0.22UF,6.3V,20%,X6S,SA',
 VOLTAGE='6.3V',
 PART_NUMBER='SP_CH4221MEE01',
 VALUE='DIFF BUS_0.22UF',
 PRIM_FILE='./archive_libs/logical/q_cap_diffbus/chips/chips.prt';

PART_NAME
 C706 'Q_CAP_DIFFBUS_C0201-DIFF BUS_0.22UF,6.3V,20%,X6S,SA':;

SECTION_NUMBER 1
 '@T6G_MB_LIB.T6G(SCH_1):PAGE355_I167@PURE_QUANTA.Q_CAP_DIFFBUS(CHIPS)':
 C_PATH='@t6g_mb_lib.t6g(sch_1):page355_i167@pure_quanta.q_cap_diffbus(chips)',
 P_PATH='@t6g_mb_lib.t6g(sch_1):page67_i167@pure_quanta.q_cap_diffbus(chips)',
 PATH='I167',
 DRAWING='@T6G_MB_LIB.T6G(SCH_1):PAGE355',
 PIN_NAMES_ROTATE='TRUE',
 TOLERANCE='20%',
 MATERIAL='X6S',
 PHYS_PAGE='67',
 XY='(3125,1700)',
 ROT='2',
 VER='2',
 PACK_TYPE='C0201',
 LOCATION='C706',
 CDS_LIB='pure_quanta',
 CDS_PART_NAME='Q_CAP_DIFFBUS_C0201-DIFF BUS_0.22UF,6.3V,20%,X6S,SA',
 VOLTAGE='6.3V',
 PART_NUMBER='SP_CH4221MEE01',
 VALUE='DIFF BUS_0.22UF',
 PRIM_FILE='./archive_libs/logical/q_cap_diffbus/chips/chips.prt';

PART_NAME
 C707 'Q_CAP_DIFFBUS_C0201-DIFF BUS_0.22UF,6.3V,20%,X6S,SA':;

SECTION_NUMBER 1
 '@T6G_MB_LIB.T6G(SCH_1):PAGE355_I168@PURE_QUANTA.Q_CAP_DIFFBUS(CHIPS)':
 C_PATH='@t6g_mb_lib.t6g(sch_1):page355_i168@pure_quanta.q_cap_diffbus(chips)',
 P_PATH='@t6g_mb_lib.t6g(sch_1):page67_i168@pure_quanta.q_cap_diffbus(chips)',
 PATH='I168',
 DRAWING='@T6G_MB_LIB.T6G(SCH_1):PAGE355',
 PIN_NAMES_ROTATE='TRUE',
 TOLERANCE='20%',
 MATERIAL='X6S',
 PHYS_PAGE='67',
 XY='(3125,1650)',
 ROT='2',
 VER='2',
 PACK_TYPE='C0201',
 LOCATION='C707',
 CDS_LIB='pure_quanta',
 CDS_PART_NAME='Q_CAP_DIFFBUS_C0201-DIFF BUS_0.22UF,6.3V,20%,X6S,SA',
 VOLTAGE='6.3V',
 PART_NUMBER='SP_CH4221MEE01',
 VALUE='DIFF BUS_0.22UF',
 PRIM_FILE='./archive_libs/logical/q_cap_diffbus/chips/chips.prt';

PART_NAME
 C708 'Q_CAP_DIFFBUS_C0201-DIFF BUS_0.22UF,6.3V,20%,X6S,SA':;

SECTION_NUMBER 1
 '@T6G_MB_LIB.T6G(SCH_1):PAGE355_I166@PURE_QUANTA.Q_CAP_DIFFBUS(CHIPS)':
 C_PATH='@t6g_mb_lib.t6g(sch_1):page355_i166@pure_quanta.q_cap_diffbus(chips)',
 P_PATH='@t6g_mb_lib.t6g(sch_1):page67_i166@pure_quanta.q_cap_diffbus(chips)',
 PATH='I166',
 DRAWING='@T6G_MB_LIB.T6G(SCH_1):PAGE355',
 PIN_NAMES_ROTATE='TRUE',
 TOLERANCE='20%',
 MATERIAL='X6S',
 PHYS_PAGE='67',
 XY='(3125,1500)',
 ROT='2',
 VER='2',
 PACK_TYPE='C0201',
 LOCATION='C708',
 CDS_LIB='pure_quanta',
 CDS_PART_NAME='Q_CAP_DIFFBUS_C0201-DIFF BUS_0.22UF,6.3V,20%,X6S,SA',
 VOLTAGE='6.3V',
 PART_NUMBER='SP_CH4221MEE01',
 VALUE='DIFF BUS_0.22UF',
 PRIM_FILE='./archive_libs/logical/q_cap_diffbus/chips/chips.prt';

PART_NAME
 C709 'Q_CAP_DIFFBUS_C0201-DIFF BUS_0.22UF,6.3V,20%,X6S,SA':;

SECTION_NUMBER 1
 '@T6G_MB_LIB.T6G(SCH_1):PAGE355_I165@PURE_QUANTA.Q_CAP_DIFFBUS(CHIPS)':
 C_PATH='@t6g_mb_lib.t6g(sch_1):page355_i165@pure_quanta.q_cap_diffbus(chips)',
 P_PATH='@t6g_mb_lib.t6g(sch_1):page67_i165@pure_quanta.q_cap_diffbus(chips)',
 PATH='I165',
 DRAWING='@T6G_MB_LIB.T6G(SCH_1):PAGE355',
 PIN_NAMES_ROTATE='TRUE',
 TOLERANCE='20%',
 MATERIAL='X6S',
 PHYS_PAGE='67',
 XY='(3125,1450)',
 ROT='2',
 VER='2',
 PACK_TYPE='C0201',
 LOCATION='C709',
 CDS_LIB='pure_quanta',
 CDS_PART_NAME='Q_CAP_DIFFBUS_C0201-DIFF BUS_0.22UF,6.3V,20%,X6S,SA',
 VOLTAGE='6.3V',
 PART_NUMBER='SP_CH4221MEE01',
 VALUE='DIFF BUS_0.22UF',
 PRIM_FILE='./archive_libs/logical/q_cap_diffbus/chips/chips.prt';

PART_NAME
 C710 'Q_CAP_DIFFBUS_C0201-DIFF BUS_0.22UF,6.3V,20%,X6S,SA':;

SECTION_NUMBER 1
 '@T6G_MB_LIB.T6G(SCH_1):PAGE354_I299@PURE_QUANTA.Q_CAP_DIFFBUS(CHIPS)':
 C_PATH='@t6g_mb_lib.t6g(sch_1):page354_i299@pure_quanta.q_cap_diffbus(chips)',
 P_PATH='@t6g_mb_lib.t6g(sch_1):page66_i299@pure_quanta.q_cap_diffbus(chips)',
 PATH='I299',
 DRAWING='@T6G_MB_LIB.T6G(SCH_1):PAGE354',
 PIN_NAMES_ROTATE='TRUE',
 TOLERANCE='20%',
 MATERIAL='X6S',
 PHYS_PAGE='66',
 XY='(-950,3600)',
 ROT='2',
 VER='2',
 PACK_TYPE='C0201',
 LOCATION='C710',
 CDS_LIB='pure_quanta',
 CDS_PART_NAME='Q_CAP_DIFFBUS_C0201-DIFF BUS_0.22UF,6.3V,20%,X6S,SA',
 VOLTAGE='6.3V',
 PART_NUMBER='SP_CH4221MEE01',
 VALUE='DIFF BUS_0.22UF',
 PRIM_FILE='./archive_libs/logical/q_cap_diffbus/chips/chips.prt';

PART_NAME
 C711 'Q_CAP_DIFFBUS_C0201-DIFF BUS_0.22UF,6.3V,20%,X6S,SA':;

SECTION_NUMBER 1
 '@T6G_MB_LIB.T6G(SCH_1):PAGE354_I298@PURE_QUANTA.Q_CAP_DIFFBUS(CHIPS)':
 C_PATH='@t6g_mb_lib.t6g(sch_1):page354_i298@pure_quanta.q_cap_diffbus(chips)',
 P_PATH='@t6g_mb_lib.t6g(sch_1):page66_i298@pure_quanta.q_cap_diffbus(chips)',
 PATH='I298',
 DRAWING='@T6G_MB_LIB.T6G(SCH_1):PAGE354',
 PIN_NAMES_ROTATE='TRUE',
 TOLERANCE='20%',
 MATERIAL='X6S',
 PHYS_PAGE='66',
 XY='(-950,3550)',
 ROT='2',
 VER='2',
 PACK_TYPE='C0201',
 LOCATION='C711',
 CDS_LIB='pure_quanta',
 CDS_PART_NAME='Q_CAP_DIFFBUS_C0201-DIFF BUS_0.22UF,6.3V,20%,X6S,SA',
 VOLTAGE='6.3V',
 PART_NUMBER='SP_CH4221MEE01',
 VALUE='DIFF BUS_0.22UF',
 PRIM_FILE='./archive_libs/logical/q_cap_diffbus/chips/chips.prt';

PART_NAME
 C712 'Q_CAP_DIFFBUS_C0201-DIFF BUS_0.22UF,6.3V,20%,X6S,SA':;

SECTION_NUMBER 1
 '@T6G_MB_LIB.T6G(SCH_1):PAGE354_I296@PURE_QUANTA.Q_CAP_DIFFBUS(CHIPS)':
 C_PATH='@t6g_mb_lib.t6g(sch_1):page354_i296@pure_quanta.q_cap_diffbus(chips)',
 P_PATH='@t6g_mb_lib.t6g(sch_1):page66_i296@pure_quanta.q_cap_diffbus(chips)',
 PATH='I296',
 DRAWING='@T6G_MB_LIB.T6G(SCH_1):PAGE354',
 PIN_NAMES_ROTATE='TRUE',
 TOLERANCE='20%',
 MATERIAL='X6S',
 PHYS_PAGE='66',
 XY='(-950,3400)',
 ROT='2',
 VER='2',
 PACK_TYPE='C0201',
 LOCATION='C712',
 CDS_LIB='pure_quanta',
 CDS_PART_NAME='Q_CAP_DIFFBUS_C0201-DIFF BUS_0.22UF,6.3V,20%,X6S,SA',
 VOLTAGE='6.3V',
 PART_NUMBER='SP_CH4221MEE01',
 VALUE='DIFF BUS_0.22UF',
 PRIM_FILE='./archive_libs/logical/q_cap_diffbus/chips/chips.prt';

PART_NAME
 C713 'Q_CAP_DIFFBUS_C0201-DIFF BUS_0.22UF,6.3V,20%,X6S,SA':;

SECTION_NUMBER 1
 '@T6G_MB_LIB.T6G(SCH_1):PAGE354_I297@PURE_QUANTA.Q_CAP_DIFFBUS(CHIPS)':
 C_PATH='@t6g_mb_lib.t6g(sch_1):page354_i297@pure_quanta.q_cap_diffbus(chips)',
 P_PATH='@t6g_mb_lib.t6g(sch_1):page66_i297@pure_quanta.q_cap_diffbus(chips)',
 PATH='I297',
 DRAWING='@T6G_MB_LIB.T6G(SCH_1):PAGE354',
 PIN_NAMES_ROTATE='TRUE',
 TOLERANCE='20%',
 MATERIAL='X6S',
 PHYS_PAGE='66',
 XY='(-950,3350)',
 ROT='2',
 VER='2',
 PACK_TYPE='C0201',
 LOCATION='C713',
 CDS_LIB='pure_quanta',
 CDS_PART_NAME='Q_CAP_DIFFBUS_C0201-DIFF BUS_0.22UF,6.3V,20%,X6S,SA',
 VOLTAGE='6.3V',
 PART_NUMBER='SP_CH4221MEE01',
 VALUE='DIFF BUS_0.22UF',
 PRIM_FILE='./archive_libs/logical/q_cap_diffbus/chips/chips.prt';

PART_NAME
 C714 'Q_CAP_DIFFBUS_C0201-DIFF BUS_0.22UF,6.3V,20%,X6S,SA':;

SECTION_NUMBER 1
 '@T6G_MB_LIB.T6G(SCH_1):PAGE354_I295@PURE_QUANTA.Q_CAP_DIFFBUS(CHIPS)':
 C_PATH='@t6g_mb_lib.t6g(sch_1):page354_i295@pure_quanta.q_cap_diffbus(chips)',
 P_PATH='@t6g_mb_lib.t6g(sch_1):page66_i295@pure_quanta.q_cap_diffbus(chips)',
 PATH='I295',
 DRAWING='@T6G_MB_LIB.T6G(SCH_1):PAGE354',
 PIN_NAMES_ROTATE='TRUE',
 TOLERANCE='20%',
 MATERIAL='X6S',
 PHYS_PAGE='66',
 XY='(-950,3200)',
 ROT='2',
 VER='2',
 PACK_TYPE='C0201',
 LOCATION='C714',
 CDS_LIB='pure_quanta',
 CDS_PART_NAME='Q_CAP_DIFFBUS_C0201-DIFF BUS_0.22UF,6.3V,20%,X6S,SA',
 VOLTAGE='6.3V',
 PART_NUMBER='SP_CH4221MEE01',
 VALUE='DIFF BUS_0.22UF',
 PRIM_FILE='./archive_libs/logical/q_cap_diffbus/chips/chips.prt';

PART_NAME
 C715 'Q_CAP_DIFFBUS_C0201-DIFF BUS_0.22UF,6.3V,20%,X6S,SA':;

SECTION_NUMBER 1
 '@T6G_MB_LIB.T6G(SCH_1):PAGE354_I294@PURE_QUANTA.Q_CAP_DIFFBUS(CHIPS)':
 C_PATH='@t6g_mb_lib.t6g(sch_1):page354_i294@pure_quanta.q_cap_diffbus(chips)',
 P_PATH='@t6g_mb_lib.t6g(sch_1):page66_i294@pure_quanta.q_cap_diffbus(chips)',
 PATH='I294',
 DRAWING='@T6G_MB_LIB.T6G(SCH_1):PAGE354',
 PIN_NAMES_ROTATE='TRUE',
 TOLERANCE='20%',
 MATERIAL='X6S',
 PHYS_PAGE='66',
 XY='(-950,3150)',
 ROT='2',
 VER='2',
 PACK_TYPE='C0201',
 LOCATION='C715',
 CDS_LIB='pure_quanta',
 CDS_PART_NAME='Q_CAP_DIFFBUS_C0201-DIFF BUS_0.22UF,6.3V,20%,X6S,SA',
 VOLTAGE='6.3V',
 PART_NUMBER='SP_CH4221MEE01',
 VALUE='DIFF BUS_0.22UF',
 PRIM_FILE='./archive_libs/logical/q_cap_diffbus/chips/chips.prt';

PART_NAME
 C716 'Q_CAP_DIFFBUS_C0201-DIFF BUS_0.22UF,6.3V,20%,X6S,SA':;

SECTION_NUMBER 1
 '@T6G_MB_LIB.T6G(SCH_1):PAGE354_I283@PURE_QUANTA.Q_CAP_DIFFBUS(CHIPS)':
 C_PATH='@t6g_mb_lib.t6g(sch_1):page354_i283@pure_quanta.q_cap_diffbus(chips)',
 P_PATH='@t6g_mb_lib.t6g(sch_1):page66_i283@pure_quanta.q_cap_diffbus(chips)',
 PATH='I283',
 DRAWING='@T6G_MB_LIB.T6G(SCH_1):PAGE354',
 PIN_NAMES_ROTATE='TRUE',
 TOLERANCE='20%',
 MATERIAL='X6S',
 PHYS_PAGE='66',
 XY='(-950,3000)',
 ROT='2',
 VER='2',
 PACK_TYPE='C0201',
 LOCATION='C716',
 CDS_LIB='pure_quanta',
 CDS_PART_NAME='Q_CAP_DIFFBUS_C0201-DIFF BUS_0.22UF,6.3V,20%,X6S,SA',
 VOLTAGE='6.3V',
 PART_NUMBER='SP_CH4221MEE01',
 VALUE='DIFF BUS_0.22UF',
 PRIM_FILE='./archive_libs/logical/q_cap_diffbus/chips/chips.prt';

PART_NAME
 C717 'Q_CAP_DIFFBUS_C0201-DIFF BUS_0.22UF,6.3V,20%,X6S,SA':;

SECTION_NUMBER 1
 '@T6G_MB_LIB.T6G(SCH_1):PAGE354_I282@PURE_QUANTA.Q_CAP_DIFFBUS(CHIPS)':
 C_PATH='@t6g_mb_lib.t6g(sch_1):page354_i282@pure_quanta.q_cap_diffbus(chips)',
 P_PATH='@t6g_mb_lib.t6g(sch_1):page66_i282@pure_quanta.q_cap_diffbus(chips)',
 PATH='I282',
 DRAWING='@T6G_MB_LIB.T6G(SCH_1):PAGE354',
 PIN_NAMES_ROTATE='TRUE',
 TOLERANCE='20%',
 MATERIAL='X6S',
 PHYS_PAGE='66',
 XY='(-950,2950)',
 ROT='2',
 VER='2',
 PACK_TYPE='C0201',
 LOCATION='C717',
 CDS_LIB='pure_quanta',
 CDS_PART_NAME='Q_CAP_DIFFBUS_C0201-DIFF BUS_0.22UF,6.3V,20%,X6S,SA',
 VOLTAGE='6.3V',
 PART_NUMBER='SP_CH4221MEE01',
 VALUE='DIFF BUS_0.22UF',
 PRIM_FILE='./archive_libs/logical/q_cap_diffbus/chips/chips.prt';

PART_NAME
 C718 'Q_CAP_DIFFBUS_C0201-DIFF BUS_0.22UF,6.3V,20%,X6S,SA':;

SECTION_NUMBER 1
 '@T6G_MB_LIB.T6G(SCH_1):PAGE354_I281@PURE_QUANTA.Q_CAP_DIFFBUS(CHIPS)':
 C_PATH='@t6g_mb_lib.t6g(sch_1):page354_i281@pure_quanta.q_cap_diffbus(chips)',
 P_PATH='@t6g_mb_lib.t6g(sch_1):page66_i281@pure_quanta.q_cap_diffbus(chips)',
 PATH='I281',
 DRAWING='@T6G_MB_LIB.T6G(SCH_1):PAGE354',
 PIN_NAMES_ROTATE='TRUE',
 TOLERANCE='20%',
 MATERIAL='X6S',
 PHYS_PAGE='66',
 XY='(-950,2800)',
 ROT='2',
 VER='2',
 PACK_TYPE='C0201',
 LOCATION='C718',
 CDS_LIB='pure_quanta',
 CDS_PART_NAME='Q_CAP_DIFFBUS_C0201-DIFF BUS_0.22UF,6.3V,20%,X6S,SA',
 VOLTAGE='6.3V',
 PART_NUMBER='SP_CH4221MEE01',
 VALUE='DIFF BUS_0.22UF',
 PRIM_FILE='./archive_libs/logical/q_cap_diffbus/chips/chips.prt';

PART_NAME
 C719 'Q_CAP_DIFFBUS_C0201-DIFF BUS_0.22UF,6.3V,20%,X6S,SA':;

SECTION_NUMBER 1
 '@T6G_MB_LIB.T6G(SCH_1):PAGE354_I280@PURE_QUANTA.Q_CAP_DIFFBUS(CHIPS)':
 C_PATH='@t6g_mb_lib.t6g(sch_1):page354_i280@pure_quanta.q_cap_diffbus(chips)',
 P_PATH='@t6g_mb_lib.t6g(sch_1):page66_i280@pure_quanta.q_cap_diffbus(chips)',
 PATH='I280',
 DRAWING='@T6G_MB_LIB.T6G(SCH_1):PAGE354',
 PIN_NAMES_ROTATE='TRUE',
 TOLERANCE='20%',
 MATERIAL='X6S',
 PHYS_PAGE='66',
 XY='(-950,2750)',
 ROT='2',
 VER='2',
 PACK_TYPE='C0201',
 LOCATION='C719',
 CDS_LIB='pure_quanta',
 CDS_PART_NAME='Q_CAP_DIFFBUS_C0201-DIFF BUS_0.22UF,6.3V,20%,X6S,SA',
 VOLTAGE='6.3V',
 PART_NUMBER='SP_CH4221MEE01',
 VALUE='DIFF BUS_0.22UF',
 PRIM_FILE='./archive_libs/logical/q_cap_diffbus/chips/chips.prt';

PART_NAME
 C720 'Q_CAP_DIFFBUS_C0201-DIFF BUS_0.22UF,6.3V,20%,X6S,SA':;

SECTION_NUMBER 1
 '@T6G_MB_LIB.T6G(SCH_1):PAGE354_I279@PURE_QUANTA.Q_CAP_DIFFBUS(CHIPS)':
 C_PATH='@t6g_mb_lib.t6g(sch_1):page354_i279@pure_quanta.q_cap_diffbus(chips)',
 P_PATH='@t6g_mb_lib.t6g(sch_1):page66_i279@pure_quanta.q_cap_diffbus(chips)',
 PATH='I279',
 DRAWING='@T6G_MB_LIB.T6G(SCH_1):PAGE354',
 PIN_NAMES_ROTATE='TRUE',
 TOLERANCE='20%',
 MATERIAL='X6S',
 PHYS_PAGE='66',
 XY='(-950,2600)',
 ROT='2',
 VER='2',
 PACK_TYPE='C0201',
 LOCATION='C720',
 CDS_LIB='pure_quanta',
 CDS_PART_NAME='Q_CAP_DIFFBUS_C0201-DIFF BUS_0.22UF,6.3V,20%,X6S,SA',
 VOLTAGE='6.3V',
 PART_NUMBER='SP_CH4221MEE01',
 VALUE='DIFF BUS_0.22UF',
 PRIM_FILE='./archive_libs/logical/q_cap_diffbus/chips/chips.prt';

PART_NAME
 C721 'Q_CAP_DIFFBUS_C0201-DIFF BUS_0.22UF,6.3V,20%,X6S,SA':;

SECTION_NUMBER 1
 '@T6G_MB_LIB.T6G(SCH_1):PAGE354_I278@PURE_QUANTA.Q_CAP_DIFFBUS(CHIPS)':
 C_PATH='@t6g_mb_lib.t6g(sch_1):page354_i278@pure_quanta.q_cap_diffbus(chips)',
 P_PATH='@t6g_mb_lib.t6g(sch_1):page66_i278@pure_quanta.q_cap_diffbus(chips)',
 PATH='I278',
 DRAWING='@T6G_MB_LIB.T6G(SCH_1):PAGE354',
 PIN_NAMES_ROTATE='TRUE',
 TOLERANCE='20%',
 MATERIAL='X6S',
 PHYS_PAGE='66',
 XY='(-950,2550)',
 ROT='2',
 VER='2',
 PACK_TYPE='C0201',
 LOCATION='C721',
 CDS_LIB='pure_quanta',
 CDS_PART_NAME='Q_CAP_DIFFBUS_C0201-DIFF BUS_0.22UF,6.3V,20%,X6S,SA',
 VOLTAGE='6.3V',
 PART_NUMBER='SP_CH4221MEE01',
 VALUE='DIFF BUS_0.22UF',
 PRIM_FILE='./archive_libs/logical/q_cap_diffbus/chips/chips.prt';

PART_NAME
 C722 'Q_CAP_DIFFBUS_C0201-DIFF BUS_0.22UF,6.3V,20%,X6S,SA':;

SECTION_NUMBER 1
 '@T6G_MB_LIB.T6G(SCH_1):PAGE354_I276@PURE_QUANTA.Q_CAP_DIFFBUS(CHIPS)':
 C_PATH='@t6g_mb_lib.t6g(sch_1):page354_i276@pure_quanta.q_cap_diffbus(chips)',
 P_PATH='@t6g_mb_lib.t6g(sch_1):page66_i276@pure_quanta.q_cap_diffbus(chips)',
 PATH='I276',
 DRAWING='@T6G_MB_LIB.T6G(SCH_1):PAGE354',
 PIN_NAMES_ROTATE='TRUE',
 TOLERANCE='20%',
 MATERIAL='X6S',
 PHYS_PAGE='66',
 XY='(-950,2400)',
 ROT='2',
 VER='2',
 PACK_TYPE='C0201',
 LOCATION='C722',
 CDS_LIB='pure_quanta',
 CDS_PART_NAME='Q_CAP_DIFFBUS_C0201-DIFF BUS_0.22UF,6.3V,20%,X6S,SA',
 VOLTAGE='6.3V',
 PART_NUMBER='SP_CH4221MEE01',
 VALUE='DIFF BUS_0.22UF',
 PRIM_FILE='./archive_libs/logical/q_cap_diffbus/chips/chips.prt';

PART_NAME
 C723 'Q_CAP_DIFFBUS_C0201-DIFF BUS_0.22UF,6.3V,20%,X6S,SA':;

SECTION_NUMBER 1
 '@T6G_MB_LIB.T6G(SCH_1):PAGE354_I277@PURE_QUANTA.Q_CAP_DIFFBUS(CHIPS)':
 C_PATH='@t6g_mb_lib.t6g(sch_1):page354_i277@pure_quanta.q_cap_diffbus(chips)',
 P_PATH='@t6g_mb_lib.t6g(sch_1):page66_i277@pure_quanta.q_cap_diffbus(chips)',
 PATH='I277',
 DRAWING='@T6G_MB_LIB.T6G(SCH_1):PAGE354',
 PIN_NAMES_ROTATE='TRUE',
 TOLERANCE='20%',
 MATERIAL='X6S',
 PHYS_PAGE='66',
 XY='(-950,2350)',
 ROT='2',
 VER='2',
 PACK_TYPE='C0201',
 LOCATION='C723',
 CDS_LIB='pure_quanta',
 CDS_PART_NAME='Q_CAP_DIFFBUS_C0201-DIFF BUS_0.22UF,6.3V,20%,X6S,SA',
 VOLTAGE='6.3V',
 PART_NUMBER='SP_CH4221MEE01',
 VALUE='DIFF BUS_0.22UF',
 PRIM_FILE='./archive_libs/logical/q_cap_diffbus/chips/chips.prt';

PART_NAME
 C724 'Q_CAP_DIFFBUS_C0201-DIFF BUS_0.22UF,6.3V,20%,X6S,SA':;

SECTION_NUMBER 1
 '@T6G_MB_LIB.T6G(SCH_1):PAGE354_I275@PURE_QUANTA.Q_CAP_DIFFBUS(CHIPS)':
 C_PATH='@t6g_mb_lib.t6g(sch_1):page354_i275@pure_quanta.q_cap_diffbus(chips)',
 P_PATH='@t6g_mb_lib.t6g(sch_1):page66_i275@pure_quanta.q_cap_diffbus(chips)',
 PATH='I275',
 DRAWING='@T6G_MB_LIB.T6G(SCH_1):PAGE354',
 PIN_NAMES_ROTATE='TRUE',
 TOLERANCE='20%',
 MATERIAL='X6S',
 PHYS_PAGE='66',
 XY='(-950,2200)',
 ROT='2',
 VER='2',
 PACK_TYPE='C0201',
 LOCATION='C724',
 CDS_LIB='pure_quanta',
 CDS_PART_NAME='Q_CAP_DIFFBUS_C0201-DIFF BUS_0.22UF,6.3V,20%,X6S,SA',
 VOLTAGE='6.3V',
 PART_NUMBER='SP_CH4221MEE01',
 VALUE='DIFF BUS_0.22UF',
 PRIM_FILE='./archive_libs/logical/q_cap_diffbus/chips/chips.prt';

PART_NAME
 C725 'Q_CAP_DIFFBUS_C0201-DIFF BUS_0.22UF,6.3V,20%,X6S,SA':;

SECTION_NUMBER 1
 '@T6G_MB_LIB.T6G(SCH_1):PAGE354_I274@PURE_QUANTA.Q_CAP_DIFFBUS(CHIPS)':
 C_PATH='@t6g_mb_lib.t6g(sch_1):page354_i274@pure_quanta.q_cap_diffbus(chips)',
 P_PATH='@t6g_mb_lib.t6g(sch_1):page66_i274@pure_quanta.q_cap_diffbus(chips)',
 PATH='I274',
 DRAWING='@T6G_MB_LIB.T6G(SCH_1):PAGE354',
 PIN_NAMES_ROTATE='TRUE',
 TOLERANCE='20%',
 MATERIAL='X6S',
 PHYS_PAGE='66',
 XY='(-950,2150)',
 ROT='2',
 VER='2',
 PACK_TYPE='C0201',
 LOCATION='C725',
 CDS_LIB='pure_quanta',
 CDS_PART_NAME='Q_CAP_DIFFBUS_C0201-DIFF BUS_0.22UF,6.3V,20%,X6S,SA',
 VOLTAGE='6.3V',
 PART_NUMBER='SP_CH4221MEE01',
 VALUE='DIFF BUS_0.22UF',
 PRIM_FILE='./archive_libs/logical/q_cap_diffbus/chips/chips.prt';

PART_NAME
 C726 'Q_CAP_DIFFBUS_C0201-DIFF BUS_0.22UF,6.3V,20%,X6S,SA':;

SECTION_NUMBER 1
 '@T6G_MB_LIB.T6G(SCH_1):PAGE354_I312@PURE_QUANTA.Q_CAP_DIFFBUS(CHIPS)':
 C_PATH='@t6g_mb_lib.t6g(sch_1):page354_i312@pure_quanta.q_cap_diffbus(chips)',
 P_PATH='@t6g_mb_lib.t6g(sch_1):page66_i312@pure_quanta.q_cap_diffbus(chips)',
 PATH='I312',
 DRAWING='@T6G_MB_LIB.T6G(SCH_1):PAGE354',
 PIN_NAMES_ROTATE='TRUE',
 TOLERANCE='20%',
 MATERIAL='X6S',
 PHYS_PAGE='66',
 XY='(-950,1625)',
 ROT='2',
 VER='2',
 PACK_TYPE='C0201',
 LOCATION='C726',
 CDS_LIB='pure_quanta',
 CDS_PART_NAME='Q_CAP_DIFFBUS_C0201-DIFF BUS_0.22UF,6.3V,20%,X6S,SA',
 VOLTAGE='6.3V',
 PART_NUMBER='SP_CH4221MEE01',
 VALUE='DIFF BUS_0.22UF',
 PRIM_FILE='./archive_libs/logical/q_cap_diffbus/chips/chips.prt';

PART_NAME
 C727 'Q_CAP_DIFFBUS_C0201-DIFF BUS_0.22UF,6.3V,20%,X6S,SA':;

SECTION_NUMBER 1
 '@T6G_MB_LIB.T6G(SCH_1):PAGE354_I251@PURE_QUANTA.Q_CAP_DIFFBUS(CHIPS)':
 C_PATH='@t6g_mb_lib.t6g(sch_1):page354_i251@pure_quanta.q_cap_diffbus(chips)',
 P_PATH='@t6g_mb_lib.t6g(sch_1):page66_i251@pure_quanta.q_cap_diffbus(chips)',
 PATH='I251',
 DRAWING='@T6G_MB_LIB.T6G(SCH_1):PAGE354',
 PIN_NAMES_ROTATE='TRUE',
 TOLERANCE='20%',
 MATERIAL='X6S',
 PHYS_PAGE='66',
 XY='(-950,1575)',
 ROT='2',
 VER='2',
 PACK_TYPE='C0201',
 LOCATION='C727',
 CDS_LIB='pure_quanta',
 CDS_PART_NAME='Q_CAP_DIFFBUS_C0201-DIFF BUS_0.22UF,6.3V,20%,X6S,SA',
 VOLTAGE='6.3V',
 PART_NUMBER='SP_CH4221MEE01',
 VALUE='DIFF BUS_0.22UF',
 PRIM_FILE='./archive_libs/logical/q_cap_diffbus/chips/chips.prt';

PART_NAME
 C728 'Q_CAP_DIFFBUS_C0201-DIFF BUS_0.22UF,6.3V,20%,X6S,SA':;

SECTION_NUMBER 1
 '@T6G_MB_LIB.T6G(SCH_1):PAGE354_I250@PURE_QUANTA.Q_CAP_DIFFBUS(CHIPS)':
 C_PATH='@t6g_mb_lib.t6g(sch_1):page354_i250@pure_quanta.q_cap_diffbus(chips)',
 P_PATH='@t6g_mb_lib.t6g(sch_1):page66_i250@pure_quanta.q_cap_diffbus(chips)',
 PATH='I250',
 DRAWING='@T6G_MB_LIB.T6G(SCH_1):PAGE354',
 PIN_NAMES_ROTATE='TRUE',
 TOLERANCE='20%',
 MATERIAL='X6S',
 PHYS_PAGE='66',
 XY='(-950,1425)',
 ROT='2',
 VER='2',
 PACK_TYPE='C0201',
 LOCATION='C728',
 CDS_LIB='pure_quanta',
 CDS_PART_NAME='Q_CAP_DIFFBUS_C0201-DIFF BUS_0.22UF,6.3V,20%,X6S,SA',
 VOLTAGE='6.3V',
 PART_NUMBER='SP_CH4221MEE01',
 VALUE='DIFF BUS_0.22UF',
 PRIM_FILE='./archive_libs/logical/q_cap_diffbus/chips/chips.prt';

PART_NAME
 C729 'Q_CAP_DIFFBUS_C0201-DIFF BUS_0.22UF,6.3V,20%,X6S,SA':;

SECTION_NUMBER 1
 '@T6G_MB_LIB.T6G(SCH_1):PAGE354_I249@PURE_QUANTA.Q_CAP_DIFFBUS(CHIPS)':
 C_PATH='@t6g_mb_lib.t6g(sch_1):page354_i249@pure_quanta.q_cap_diffbus(chips)',
 P_PATH='@t6g_mb_lib.t6g(sch_1):page66_i249@pure_quanta.q_cap_diffbus(chips)',
 PATH='I249',
 DRAWING='@T6G_MB_LIB.T6G(SCH_1):PAGE354',
 PIN_NAMES_ROTATE='TRUE',
 TOLERANCE='20%',
 MATERIAL='X6S',
 PHYS_PAGE='66',
 XY='(-950,1375)',
 ROT='2',
 VER='2',
 PACK_TYPE='C0201',
 LOCATION='C729',
 CDS_LIB='pure_quanta',
 CDS_PART_NAME='Q_CAP_DIFFBUS_C0201-DIFF BUS_0.22UF,6.3V,20%,X6S,SA',
 VOLTAGE='6.3V',
 PART_NUMBER='SP_CH4221MEE01',
 VALUE='DIFF BUS_0.22UF',
 PRIM_FILE='./archive_libs/logical/q_cap_diffbus/chips/chips.prt';

PART_NAME
 C730 'Q_CAP_DIFFBUS_C0201-DIFF BUS_0.22UF,6.3V,20%,X6S,SA':;

SECTION_NUMBER 1
 '@T6G_MB_LIB.T6G(SCH_1):PAGE354_I248@PURE_QUANTA.Q_CAP_DIFFBUS(CHIPS)':
 C_PATH='@t6g_mb_lib.t6g(sch_1):page354_i248@pure_quanta.q_cap_diffbus(chips)',
 P_PATH='@t6g_mb_lib.t6g(sch_1):page66_i248@pure_quanta.q_cap_diffbus(chips)',
 PATH='I248',
 DRAWING='@T6G_MB_LIB.T6G(SCH_1):PAGE354',
 PIN_NAMES_ROTATE='TRUE',
 TOLERANCE='20%',
 MATERIAL='X6S',
 PHYS_PAGE='66',
 XY='(-950,1225)',
 ROT='2',
 VER='2',
 PACK_TYPE='C0201',
 LOCATION='C730',
 CDS_LIB='pure_quanta',
 CDS_PART_NAME='Q_CAP_DIFFBUS_C0201-DIFF BUS_0.22UF,6.3V,20%,X6S,SA',
 VOLTAGE='6.3V',
 PART_NUMBER='SP_CH4221MEE01',
 VALUE='DIFF BUS_0.22UF',
 PRIM_FILE='./archive_libs/logical/q_cap_diffbus/chips/chips.prt';

PART_NAME
 C731 'Q_CAP_DIFFBUS_C0201-DIFF BUS_0.22UF,6.3V,20%,X6S,SA':;

SECTION_NUMBER 1
 '@T6G_MB_LIB.T6G(SCH_1):PAGE354_I247@PURE_QUANTA.Q_CAP_DIFFBUS(CHIPS)':
 C_PATH='@t6g_mb_lib.t6g(sch_1):page354_i247@pure_quanta.q_cap_diffbus(chips)',
 P_PATH='@t6g_mb_lib.t6g(sch_1):page66_i247@pure_quanta.q_cap_diffbus(chips)',
 PATH='I247',
 DRAWING='@T6G_MB_LIB.T6G(SCH_1):PAGE354',
 PIN_NAMES_ROTATE='TRUE',
 TOLERANCE='20%',
 MATERIAL='X6S',
 PHYS_PAGE='66',
 XY='(-950,1175)',
 ROT='2',
 VER='2',
 PACK_TYPE='C0201',
 LOCATION='C731',
 CDS_LIB='pure_quanta',
 CDS_PART_NAME='Q_CAP_DIFFBUS_C0201-DIFF BUS_0.22UF,6.3V,20%,X6S,SA',
 VOLTAGE='6.3V',
 PART_NUMBER='SP_CH4221MEE01',
 VALUE='DIFF BUS_0.22UF',
 PRIM_FILE='./archive_libs/logical/q_cap_diffbus/chips/chips.prt';

PART_NAME
 C732 'Q_CAP_DIFFBUS_C0201-DIFF BUS_0.22UF,6.3V,20%,X6S,SA':;

SECTION_NUMBER 1
 '@T6G_MB_LIB.T6G(SCH_1):PAGE354_I246@PURE_QUANTA.Q_CAP_DIFFBUS(CHIPS)':
 C_PATH='@t6g_mb_lib.t6g(sch_1):page354_i246@pure_quanta.q_cap_diffbus(chips)',
 P_PATH='@t6g_mb_lib.t6g(sch_1):page66_i246@pure_quanta.q_cap_diffbus(chips)',
 PATH='I246',
 DRAWING='@T6G_MB_LIB.T6G(SCH_1):PAGE354',
 PIN_NAMES_ROTATE='TRUE',
 TOLERANCE='20%',
 MATERIAL='X6S',
 PHYS_PAGE='66',
 XY='(-950,1025)',
 ROT='2',
 VER='2',
 PACK_TYPE='C0201',
 LOCATION='C732',
 CDS_LIB='pure_quanta',
 CDS_PART_NAME='Q_CAP_DIFFBUS_C0201-DIFF BUS_0.22UF,6.3V,20%,X6S,SA',
 VOLTAGE='6.3V',
 PART_NUMBER='SP_CH4221MEE01',
 VALUE='DIFF BUS_0.22UF',
 PRIM_FILE='./archive_libs/logical/q_cap_diffbus/chips/chips.prt';

PART_NAME
 C733 'Q_CAP_DIFFBUS_C0201-DIFF BUS_0.22UF,6.3V,20%,X6S,SA':;

SECTION_NUMBER 1
 '@T6G_MB_LIB.T6G(SCH_1):PAGE354_I237@PURE_QUANTA.Q_CAP_DIFFBUS(CHIPS)':
 C_PATH='@t6g_mb_lib.t6g(sch_1):page354_i237@pure_quanta.q_cap_diffbus(chips)',
 P_PATH='@t6g_mb_lib.t6g(sch_1):page66_i237@pure_quanta.q_cap_diffbus(chips)',
 PATH='I237',
 DRAWING='@T6G_MB_LIB.T6G(SCH_1):PAGE354',
 PIN_NAMES_ROTATE='TRUE',
 TOLERANCE='20%',
 MATERIAL='X6S',
 PHYS_PAGE='66',
 XY='(-950,975)',
 ROT='2',
 VER='2',
 PACK_TYPE='C0201',
 LOCATION='C733',
 CDS_LIB='pure_quanta',
 CDS_PART_NAME='Q_CAP_DIFFBUS_C0201-DIFF BUS_0.22UF,6.3V,20%,X6S,SA',
 VOLTAGE='6.3V',
 PART_NUMBER='SP_CH4221MEE01',
 VALUE='DIFF BUS_0.22UF',
 PRIM_FILE='./archive_libs/logical/q_cap_diffbus/chips/chips.prt';

PART_NAME
 C734 'Q_CAP_DIFFBUS_C0201-DIFF BUS_0.22UF,6.3V,20%,X6S,SA':;

SECTION_NUMBER 1
 '@T6G_MB_LIB.T6G(SCH_1):PAGE354_I235@PURE_QUANTA.Q_CAP_DIFFBUS(CHIPS)':
 C_PATH='@t6g_mb_lib.t6g(sch_1):page354_i235@pure_quanta.q_cap_diffbus(chips)',
 P_PATH='@t6g_mb_lib.t6g(sch_1):page66_i235@pure_quanta.q_cap_diffbus(chips)',
 PATH='I235',
 DRAWING='@T6G_MB_LIB.T6G(SCH_1):PAGE354',
 PIN_NAMES_ROTATE='TRUE',
 TOLERANCE='20%',
 MATERIAL='X6S',
 PHYS_PAGE='66',
 XY='(-950,825)',
 ROT='2',
 VER='2',
 PACK_TYPE='C0201',
 LOCATION='C734',
 CDS_LIB='pure_quanta',
 CDS_PART_NAME='Q_CAP_DIFFBUS_C0201-DIFF BUS_0.22UF,6.3V,20%,X6S,SA',
 VOLTAGE='6.3V',
 PART_NUMBER='SP_CH4221MEE01',
 VALUE='DIFF BUS_0.22UF',
 PRIM_FILE='./archive_libs/logical/q_cap_diffbus/chips/chips.prt';

PART_NAME
 C735 'Q_CAP_DIFFBUS_C0201-DIFF BUS_0.22UF,6.3V,20%,X6S,SA':;

SECTION_NUMBER 1
 '@T6G_MB_LIB.T6G(SCH_1):PAGE354_I236@PURE_QUANTA.Q_CAP_DIFFBUS(CHIPS)':
 C_PATH='@t6g_mb_lib.t6g(sch_1):page354_i236@pure_quanta.q_cap_diffbus(chips)',
 P_PATH='@t6g_mb_lib.t6g(sch_1):page66_i236@pure_quanta.q_cap_diffbus(chips)',
 PATH='I236',
 DRAWING='@T6G_MB_LIB.T6G(SCH_1):PAGE354',
 PIN_NAMES_ROTATE='TRUE',
 TOLERANCE='20%',
 MATERIAL='X6S',
 PHYS_PAGE='66',
 XY='(-950,775)',
 ROT='2',
 VER='2',
 PACK_TYPE='C0201',
 LOCATION='C735',
 CDS_LIB='pure_quanta',
 CDS_PART_NAME='Q_CAP_DIFFBUS_C0201-DIFF BUS_0.22UF,6.3V,20%,X6S,SA',
 VOLTAGE='6.3V',
 PART_NUMBER='SP_CH4221MEE01',
 VALUE='DIFF BUS_0.22UF',
 PRIM_FILE='./archive_libs/logical/q_cap_diffbus/chips/chips.prt';

PART_NAME
 C736 'Q_CAP_DIFFBUS_C0201-DIFF BUS_0.22UF,6.3V,20%,X6S,SA':;

SECTION_NUMBER 1
 '@T6G_MB_LIB.T6G(SCH_1):PAGE354_I234@PURE_QUANTA.Q_CAP_DIFFBUS(CHIPS)':
 C_PATH='@t6g_mb_lib.t6g(sch_1):page354_i234@pure_quanta.q_cap_diffbus(chips)',
 P_PATH='@t6g_mb_lib.t6g(sch_1):page66_i234@pure_quanta.q_cap_diffbus(chips)',
 PATH='I234',
 DRAWING='@T6G_MB_LIB.T6G(SCH_1):PAGE354',
 PIN_NAMES_ROTATE='TRUE',
 TOLERANCE='20%',
 MATERIAL='X6S',
 PHYS_PAGE='66',
 XY='(-950,625)',
 ROT='2',
 VER='2',
 PACK_TYPE='C0201',
 LOCATION='C736',
 CDS_LIB='pure_quanta',
 CDS_PART_NAME='Q_CAP_DIFFBUS_C0201-DIFF BUS_0.22UF,6.3V,20%,X6S,SA',
 VOLTAGE='6.3V',
 PART_NUMBER='SP_CH4221MEE01',
 VALUE='DIFF BUS_0.22UF',
 PRIM_FILE='./archive_libs/logical/q_cap_diffbus/chips/chips.prt';

PART_NAME
 C737 'Q_CAP_DIFFBUS_C0201-DIFF BUS_0.22UF,6.3V,20%,X6S,SA':;

SECTION_NUMBER 1
 '@T6G_MB_LIB.T6G(SCH_1):PAGE354_I233@PURE_QUANTA.Q_CAP_DIFFBUS(CHIPS)':
 C_PATH='@t6g_mb_lib.t6g(sch_1):page354_i233@pure_quanta.q_cap_diffbus(chips)',
 P_PATH='@t6g_mb_lib.t6g(sch_1):page66_i233@pure_quanta.q_cap_diffbus(chips)',
 PATH='I233',
 DRAWING='@T6G_MB_LIB.T6G(SCH_1):PAGE354',
 PIN_NAMES_ROTATE='TRUE',
 TOLERANCE='20%',
 MATERIAL='X6S',
 PHYS_PAGE='66',
 XY='(-950,575)',
 ROT='2',
 VER='2',
 PACK_TYPE='C0201',
 LOCATION='C737',
 CDS_LIB='pure_quanta',
 CDS_PART_NAME='Q_CAP_DIFFBUS_C0201-DIFF BUS_0.22UF,6.3V,20%,X6S,SA',
 VOLTAGE='6.3V',
 PART_NUMBER='SP_CH4221MEE01',
 VALUE='DIFF BUS_0.22UF',
 PRIM_FILE='./archive_libs/logical/q_cap_diffbus/chips/chips.prt';

PART_NAME
 C738 'Q_CAP_DIFFBUS_C0201-DIFF BUS_0.22UF,6.3V,20%,X6S,SA':;

SECTION_NUMBER 1
 '@T6G_MB_LIB.T6G(SCH_1):PAGE354_I232@PURE_QUANTA.Q_CAP_DIFFBUS(CHIPS)':
 C_PATH='@t6g_mb_lib.t6g(sch_1):page354_i232@pure_quanta.q_cap_diffbus(chips)',
 P_PATH='@t6g_mb_lib.t6g(sch_1):page66_i232@pure_quanta.q_cap_diffbus(chips)',
 PATH='I232',
 DRAWING='@T6G_MB_LIB.T6G(SCH_1):PAGE354',
 PIN_NAMES_ROTATE='TRUE',
 TOLERANCE='20%',
 MATERIAL='X6S',
 PHYS_PAGE='66',
 XY='(-950,425)',
 ROT='2',
 VER='2',
 PACK_TYPE='C0201',
 LOCATION='C738',
 CDS_LIB='pure_quanta',
 CDS_PART_NAME='Q_CAP_DIFFBUS_C0201-DIFF BUS_0.22UF,6.3V,20%,X6S,SA',
 VOLTAGE='6.3V',
 PART_NUMBER='SP_CH4221MEE01',
 VALUE='DIFF BUS_0.22UF',
 PRIM_FILE='./archive_libs/logical/q_cap_diffbus/chips/chips.prt';

PART_NAME
 C739 'Q_CAP_DIFFBUS_C0201-DIFF BUS_0.22UF,6.3V,20%,X6S,SA':;

SECTION_NUMBER 1
 '@T6G_MB_LIB.T6G(SCH_1):PAGE354_I231@PURE_QUANTA.Q_CAP_DIFFBUS(CHIPS)':
 C_PATH='@t6g_mb_lib.t6g(sch_1):page354_i231@pure_quanta.q_cap_diffbus(chips)',
 P_PATH='@t6g_mb_lib.t6g(sch_1):page66_i231@pure_quanta.q_cap_diffbus(chips)',
 PATH='I231',
 DRAWING='@T6G_MB_LIB.T6G(SCH_1):PAGE354',
 PIN_NAMES_ROTATE='TRUE',
 TOLERANCE='20%',
 MATERIAL='X6S',
 PHYS_PAGE='66',
 XY='(-950,375)',
 ROT='2',
 VER='2',
 PACK_TYPE='C0201',
 LOCATION='C739',
 CDS_LIB='pure_quanta',
 CDS_PART_NAME='Q_CAP_DIFFBUS_C0201-DIFF BUS_0.22UF,6.3V,20%,X6S,SA',
 VOLTAGE='6.3V',
 PART_NUMBER='SP_CH4221MEE01',
 VALUE='DIFF BUS_0.22UF',
 PRIM_FILE='./archive_libs/logical/q_cap_diffbus/chips/chips.prt';

PART_NAME
 C740 'Q_CAP_DIFFBUS_C0201-DIFF BUS_0.22UF,6.3V,20%,X6S,SA':;

SECTION_NUMBER 1
 '@T6G_MB_LIB.T6G(SCH_1):PAGE354_I229@PURE_QUANTA.Q_CAP_DIFFBUS(CHIPS)':
 C_PATH='@t6g_mb_lib.t6g(sch_1):page354_i229@pure_quanta.q_cap_diffbus(chips)',
 P_PATH='@t6g_mb_lib.t6g(sch_1):page66_i229@pure_quanta.q_cap_diffbus(chips)',
 PATH='I229',
 DRAWING='@T6G_MB_LIB.T6G(SCH_1):PAGE354',
 PIN_NAMES_ROTATE='TRUE',
 TOLERANCE='20%',
 MATERIAL='X6S',
 PHYS_PAGE='66',
 XY='(-950,225)',
 ROT='2',
 VER='2',
 PACK_TYPE='C0201',
 LOCATION='C740',
 CDS_LIB='pure_quanta',
 CDS_PART_NAME='Q_CAP_DIFFBUS_C0201-DIFF BUS_0.22UF,6.3V,20%,X6S,SA',
 VOLTAGE='6.3V',
 PART_NUMBER='SP_CH4221MEE01',
 VALUE='DIFF BUS_0.22UF',
 PRIM_FILE='./archive_libs/logical/q_cap_diffbus/chips/chips.prt';

PART_NAME
 C741 'Q_CAP_DIFFBUS_C0201-DIFF BUS_0.22UF,6.3V,20%,X6S,SA':;

SECTION_NUMBER 1
 '@T6G_MB_LIB.T6G(SCH_1):PAGE354_I230@PURE_QUANTA.Q_CAP_DIFFBUS(CHIPS)':
 C_PATH='@t6g_mb_lib.t6g(sch_1):page354_i230@pure_quanta.q_cap_diffbus(chips)',
 P_PATH='@t6g_mb_lib.t6g(sch_1):page66_i230@pure_quanta.q_cap_diffbus(chips)',
 PATH='I230',
 DRAWING='@T6G_MB_LIB.T6G(SCH_1):PAGE354',
 PIN_NAMES_ROTATE='TRUE',
 TOLERANCE='20%',
 MATERIAL='X6S',
 PHYS_PAGE='66',
 XY='(-950,175)',
 ROT='2',
 VER='2',
 PACK_TYPE='C0201',
 LOCATION='C741',
 CDS_LIB='pure_quanta',
 CDS_PART_NAME='Q_CAP_DIFFBUS_C0201-DIFF BUS_0.22UF,6.3V,20%,X6S,SA',
 VOLTAGE='6.3V',
 PART_NUMBER='SP_CH4221MEE01',
 VALUE='DIFF BUS_0.22UF',
 PRIM_FILE='./archive_libs/logical/q_cap_diffbus/chips/chips.prt';

PART_NAME
 C742 'Q_CAP_DIFFBUS_C0201-DIFF BUS_0.22UF,6.3V,20%,X6S,SA':;

SECTION_NUMBER 1
 '@T6G_MB_LIB.T6G(SCH_1):PAGE354_I172@PURE_QUANTA.Q_CAP_DIFFBUS(CHIPS)':
 C_PATH='@t6g_mb_lib.t6g(sch_1):page354_i172@pure_quanta.q_cap_diffbus(chips)',
 P_PATH='@t6g_mb_lib.t6g(sch_1):page66_i172@pure_quanta.q_cap_diffbus(chips)',
 PATH='I172',
 DRAWING='@T6G_MB_LIB.T6G(SCH_1):PAGE354',
 PIN_NAMES_ROTATE='TRUE',
 TOLERANCE='20%',
 MATERIAL='X6S',
 PHYS_PAGE='66',
 XY='(3625,3625)',
 ROT='2',
 VER='2',
 PACK_TYPE='C0201',
 LOCATION='C742',
 CDS_LIB='pure_quanta',
 CDS_PART_NAME='Q_CAP_DIFFBUS_C0201-DIFF BUS_0.22UF,6.3V,20%,X6S,SA',
 VOLTAGE='6.3V',
 PART_NUMBER='SP_CH4221MEE01',
 VALUE='DIFF BUS_0.22UF',
 PRIM_FILE='./archive_libs/logical/q_cap_diffbus/chips/chips.prt';

PART_NAME
 C743 'Q_CAP_DIFFBUS_C0201-DIFF BUS_0.22UF,6.3V,20%,X6S,SA':;

SECTION_NUMBER 1
 '@T6G_MB_LIB.T6G(SCH_1):PAGE354_I171@PURE_QUANTA.Q_CAP_DIFFBUS(CHIPS)':
 C_PATH='@t6g_mb_lib.t6g(sch_1):page354_i171@pure_quanta.q_cap_diffbus(chips)',
 P_PATH='@t6g_mb_lib.t6g(sch_1):page66_i171@pure_quanta.q_cap_diffbus(chips)',
 PATH='I171',
 DRAWING='@T6G_MB_LIB.T6G(SCH_1):PAGE354',
 PIN_NAMES_ROTATE='TRUE',
 TOLERANCE='20%',
 MATERIAL='X6S',
 PHYS_PAGE='66',
 XY='(3625,3575)',
 ROT='2',
 VER='2',
 PACK_TYPE='C0201',
 LOCATION='C743',
 CDS_LIB='pure_quanta',
 CDS_PART_NAME='Q_CAP_DIFFBUS_C0201-DIFF BUS_0.22UF,6.3V,20%,X6S,SA',
 VOLTAGE='6.3V',
 PART_NUMBER='SP_CH4221MEE01',
 VALUE='DIFF BUS_0.22UF',
 PRIM_FILE='./archive_libs/logical/q_cap_diffbus/chips/chips.prt';

PART_NAME
 C744 'Q_CAP_DIFFBUS_C0201-DIFF BUS_0.22UF,6.3V,20%,X6S,SA':;

SECTION_NUMBER 1
 '@T6G_MB_LIB.T6G(SCH_1):PAGE354_I170@PURE_QUANTA.Q_CAP_DIFFBUS(CHIPS)':
 C_PATH='@t6g_mb_lib.t6g(sch_1):page354_i170@pure_quanta.q_cap_diffbus(chips)',
 P_PATH='@t6g_mb_lib.t6g(sch_1):page66_i170@pure_quanta.q_cap_diffbus(chips)',
 PATH='I170',
 DRAWING='@T6G_MB_LIB.T6G(SCH_1):PAGE354',
 PIN_NAMES_ROTATE='TRUE',
 TOLERANCE='20%',
 MATERIAL='X6S',
 PHYS_PAGE='66',
 XY='(3625,3425)',
 ROT='2',
 VER='2',
 PACK_TYPE='C0201',
 LOCATION='C744',
 CDS_LIB='pure_quanta',
 CDS_PART_NAME='Q_CAP_DIFFBUS_C0201-DIFF BUS_0.22UF,6.3V,20%,X6S,SA',
 VOLTAGE='6.3V',
 PART_NUMBER='SP_CH4221MEE01',
 VALUE='DIFF BUS_0.22UF',
 PRIM_FILE='./archive_libs/logical/q_cap_diffbus/chips/chips.prt';

PART_NAME
 C745 'Q_CAP_DIFFBUS_C0201-DIFF BUS_0.22UF,6.3V,20%,X6S,SA':;

SECTION_NUMBER 1
 '@T6G_MB_LIB.T6G(SCH_1):PAGE354_I169@PURE_QUANTA.Q_CAP_DIFFBUS(CHIPS)':
 C_PATH='@t6g_mb_lib.t6g(sch_1):page354_i169@pure_quanta.q_cap_diffbus(chips)',
 P_PATH='@t6g_mb_lib.t6g(sch_1):page66_i169@pure_quanta.q_cap_diffbus(chips)',
 PATH='I169',
 DRAWING='@T6G_MB_LIB.T6G(SCH_1):PAGE354',
 PIN_NAMES_ROTATE='TRUE',
 TOLERANCE='20%',
 MATERIAL='X6S',
 PHYS_PAGE='66',
 XY='(3625,3375)',
 ROT='2',
 VER='2',
 PACK_TYPE='C0201',
 LOCATION='C745',
 CDS_LIB='pure_quanta',
 CDS_PART_NAME='Q_CAP_DIFFBUS_C0201-DIFF BUS_0.22UF,6.3V,20%,X6S,SA',
 VOLTAGE='6.3V',
 PART_NUMBER='SP_CH4221MEE01',
 VALUE='DIFF BUS_0.22UF',
 PRIM_FILE='./archive_libs/logical/q_cap_diffbus/chips/chips.prt';

PART_NAME
 C746 'Q_CAP_DIFFBUS_C0201-DIFF BUS_0.22UF,6.3V,20%,X6S,SA':;

SECTION_NUMBER 1
 '@T6G_MB_LIB.T6G(SCH_1):PAGE354_I168@PURE_QUANTA.Q_CAP_DIFFBUS(CHIPS)':
 C_PATH='@t6g_mb_lib.t6g(sch_1):page354_i168@pure_quanta.q_cap_diffbus(chips)',
 P_PATH='@t6g_mb_lib.t6g(sch_1):page66_i168@pure_quanta.q_cap_diffbus(chips)',
 PATH='I168',
 DRAWING='@T6G_MB_LIB.T6G(SCH_1):PAGE354',
 PIN_NAMES_ROTATE='TRUE',
 TOLERANCE='20%',
 MATERIAL='X6S',
 PHYS_PAGE='66',
 XY='(3625,3225)',
 ROT='2',
 VER='2',
 PACK_TYPE='C0201',
 LOCATION='C746',
 CDS_LIB='pure_quanta',
 CDS_PART_NAME='Q_CAP_DIFFBUS_C0201-DIFF BUS_0.22UF,6.3V,20%,X6S,SA',
 VOLTAGE='6.3V',
 PART_NUMBER='SP_CH4221MEE01',
 VALUE='DIFF BUS_0.22UF',
 PRIM_FILE='./archive_libs/logical/q_cap_diffbus/chips/chips.prt';

PART_NAME
 C747 'Q_CAP_DIFFBUS_C0201-DIFF BUS_0.22UF,6.3V,20%,X6S,SA':;

SECTION_NUMBER 1
 '@T6G_MB_LIB.T6G(SCH_1):PAGE354_I167@PURE_QUANTA.Q_CAP_DIFFBUS(CHIPS)':
 C_PATH='@t6g_mb_lib.t6g(sch_1):page354_i167@pure_quanta.q_cap_diffbus(chips)',
 P_PATH='@t6g_mb_lib.t6g(sch_1):page66_i167@pure_quanta.q_cap_diffbus(chips)',
 PATH='I167',
 DRAWING='@T6G_MB_LIB.T6G(SCH_1):PAGE354',
 PIN_NAMES_ROTATE='TRUE',
 TOLERANCE='20%',
 MATERIAL='X6S',
 PHYS_PAGE='66',
 XY='(3625,3175)',
 ROT='2',
 VER='2',
 PACK_TYPE='C0201',
 LOCATION='C747',
 CDS_LIB='pure_quanta',
 CDS_PART_NAME='Q_CAP_DIFFBUS_C0201-DIFF BUS_0.22UF,6.3V,20%,X6S,SA',
 VOLTAGE='6.3V',
 PART_NUMBER='SP_CH4221MEE01',
 VALUE='DIFF BUS_0.22UF',
 PRIM_FILE='./archive_libs/logical/q_cap_diffbus/chips/chips.prt';

PART_NAME
 C748 'Q_CAP_DIFFBUS_C0201-DIFF BUS_0.22UF,6.3V,20%,X6S,SA':;

SECTION_NUMBER 1
 '@T6G_MB_LIB.T6G(SCH_1):PAGE354_I163@PURE_QUANTA.Q_CAP_DIFFBUS(CHIPS)':
 C_PATH='@t6g_mb_lib.t6g(sch_1):page354_i163@pure_quanta.q_cap_diffbus(chips)',
 P_PATH='@t6g_mb_lib.t6g(sch_1):page66_i163@pure_quanta.q_cap_diffbus(chips)',
 PATH='I163',
 DRAWING='@T6G_MB_LIB.T6G(SCH_1):PAGE354',
 PIN_NAMES_ROTATE='TRUE',
 TOLERANCE='20%',
 MATERIAL='X6S',
 PHYS_PAGE='66',
 XY='(3625,3025)',
 ROT='2',
 VER='2',
 PACK_TYPE='C0201',
 LOCATION='C748',
 CDS_LIB='pure_quanta',
 CDS_PART_NAME='Q_CAP_DIFFBUS_C0201-DIFF BUS_0.22UF,6.3V,20%,X6S,SA',
 VOLTAGE='6.3V',
 PART_NUMBER='SP_CH4221MEE01',
 VALUE='DIFF BUS_0.22UF',
 PRIM_FILE='./archive_libs/logical/q_cap_diffbus/chips/chips.prt';

PART_NAME
 C749 'Q_CAP_DIFFBUS_C0201-DIFF BUS_0.22UF,6.3V,20%,X6S,SA':;

SECTION_NUMBER 1
 '@T6G_MB_LIB.T6G(SCH_1):PAGE354_I162@PURE_QUANTA.Q_CAP_DIFFBUS(CHIPS)':
 C_PATH='@t6g_mb_lib.t6g(sch_1):page354_i162@pure_quanta.q_cap_diffbus(chips)',
 P_PATH='@t6g_mb_lib.t6g(sch_1):page66_i162@pure_quanta.q_cap_diffbus(chips)',
 PATH='I162',
 DRAWING='@T6G_MB_LIB.T6G(SCH_1):PAGE354',
 PIN_NAMES_ROTATE='TRUE',
 TOLERANCE='20%',
 MATERIAL='X6S',
 PHYS_PAGE='66',
 XY='(3625,2975)',
 ROT='2',
 VER='2',
 PACK_TYPE='C0201',
 LOCATION='C749',
 CDS_LIB='pure_quanta',
 CDS_PART_NAME='Q_CAP_DIFFBUS_C0201-DIFF BUS_0.22UF,6.3V,20%,X6S,SA',
 VOLTAGE='6.3V',
 PART_NUMBER='SP_CH4221MEE01',
 VALUE='DIFF BUS_0.22UF',
 PRIM_FILE='./archive_libs/logical/q_cap_diffbus/chips/chips.prt';

PART_NAME
 C750 'Q_CAP_DIFFBUS_C0201-DIFF BUS_0.22UF,6.3V,20%,X6S,SA':;

SECTION_NUMBER 1
 '@T6G_MB_LIB.T6G(SCH_1):PAGE354_I160@PURE_QUANTA.Q_CAP_DIFFBUS(CHIPS)':
 C_PATH='@t6g_mb_lib.t6g(sch_1):page354_i160@pure_quanta.q_cap_diffbus(chips)',
 P_PATH='@t6g_mb_lib.t6g(sch_1):page66_i160@pure_quanta.q_cap_diffbus(chips)',
 PATH='I160',
 DRAWING='@T6G_MB_LIB.T6G(SCH_1):PAGE354',
 PIN_NAMES_ROTATE='TRUE',
 TOLERANCE='20%',
 MATERIAL='X6S',
 PHYS_PAGE='66',
 XY='(3625,2825)',
 ROT='2',
 VER='2',
 PACK_TYPE='C0201',
 LOCATION='C750',
 CDS_LIB='pure_quanta',
 CDS_PART_NAME='Q_CAP_DIFFBUS_C0201-DIFF BUS_0.22UF,6.3V,20%,X6S,SA',
 VOLTAGE='6.3V',
 PART_NUMBER='SP_CH4221MEE01',
 VALUE='DIFF BUS_0.22UF',
 PRIM_FILE='./archive_libs/logical/q_cap_diffbus/chips/chips.prt';

PART_NAME
 C751 'Q_CAP_DIFFBUS_C0201-DIFF BUS_0.22UF,6.3V,20%,X6S,SA':;

SECTION_NUMBER 1
 '@T6G_MB_LIB.T6G(SCH_1):PAGE354_I161@PURE_QUANTA.Q_CAP_DIFFBUS(CHIPS)':
 C_PATH='@t6g_mb_lib.t6g(sch_1):page354_i161@pure_quanta.q_cap_diffbus(chips)',
 P_PATH='@t6g_mb_lib.t6g(sch_1):page66_i161@pure_quanta.q_cap_diffbus(chips)',
 PATH='I161',
 DRAWING='@T6G_MB_LIB.T6G(SCH_1):PAGE354',
 PIN_NAMES_ROTATE='TRUE',
 TOLERANCE='20%',
 MATERIAL='X6S',
 PHYS_PAGE='66',
 XY='(3625,2775)',
 ROT='2',
 VER='2',
 PACK_TYPE='C0201',
 LOCATION='C751',
 CDS_LIB='pure_quanta',
 CDS_PART_NAME='Q_CAP_DIFFBUS_C0201-DIFF BUS_0.22UF,6.3V,20%,X6S,SA',
 VOLTAGE='6.3V',
 PART_NUMBER='SP_CH4221MEE01',
 VALUE='DIFF BUS_0.22UF',
 PRIM_FILE='./archive_libs/logical/q_cap_diffbus/chips/chips.prt';

PART_NAME
 C752 'Q_CAP_DIFFBUS_C0201-DIFF BUS_0.22UF,6.3V,20%,X6S,SA':;

SECTION_NUMBER 1
 '@T6G_MB_LIB.T6G(SCH_1):PAGE354_I159@PURE_QUANTA.Q_CAP_DIFFBUS(CHIPS)':
 C_PATH='@t6g_mb_lib.t6g(sch_1):page354_i159@pure_quanta.q_cap_diffbus(chips)',
 P_PATH='@t6g_mb_lib.t6g(sch_1):page66_i159@pure_quanta.q_cap_diffbus(chips)',
 PATH='I159',
 DRAWING='@T6G_MB_LIB.T6G(SCH_1):PAGE354',
 PIN_NAMES_ROTATE='TRUE',
 TOLERANCE='20%',
 MATERIAL='X6S',
 PHYS_PAGE='66',
 XY='(3625,2625)',
 ROT='2',
 VER='2',
 PACK_TYPE='C0201',
 LOCATION='C752',
 CDS_LIB='pure_quanta',
 CDS_PART_NAME='Q_CAP_DIFFBUS_C0201-DIFF BUS_0.22UF,6.3V,20%,X6S,SA',
 VOLTAGE='6.3V',
 PART_NUMBER='SP_CH4221MEE01',
 VALUE='DIFF BUS_0.22UF',
 PRIM_FILE='./archive_libs/logical/q_cap_diffbus/chips/chips.prt';

PART_NAME
 C753 'Q_CAP_DIFFBUS_C0201-DIFF BUS_0.22UF,6.3V,20%,X6S,SA':;

SECTION_NUMBER 1
 '@T6G_MB_LIB.T6G(SCH_1):PAGE354_I158@PURE_QUANTA.Q_CAP_DIFFBUS(CHIPS)':
 C_PATH='@t6g_mb_lib.t6g(sch_1):page354_i158@pure_quanta.q_cap_diffbus(chips)',
 P_PATH='@t6g_mb_lib.t6g(sch_1):page66_i158@pure_quanta.q_cap_diffbus(chips)',
 PATH='I158',
 DRAWING='@T6G_MB_LIB.T6G(SCH_1):PAGE354',
 PIN_NAMES_ROTATE='TRUE',
 TOLERANCE='20%',
 MATERIAL='X6S',
 PHYS_PAGE='66',
 XY='(3625,2575)',
 ROT='2',
 VER='2',
 PACK_TYPE='C0201',
 LOCATION='C753',
 CDS_LIB='pure_quanta',
 CDS_PART_NAME='Q_CAP_DIFFBUS_C0201-DIFF BUS_0.22UF,6.3V,20%,X6S,SA',
 VOLTAGE='6.3V',
 PART_NUMBER='SP_CH4221MEE01',
 VALUE='DIFF BUS_0.22UF',
 PRIM_FILE='./archive_libs/logical/q_cap_diffbus/chips/chips.prt';

PART_NAME
 C754 'Q_CAP_DIFFBUS_C0201-DIFF BUS_0.22UF,6.3V,20%,X6S,SA':;

SECTION_NUMBER 1
 '@T6G_MB_LIB.T6G(SCH_1):PAGE354_I157@PURE_QUANTA.Q_CAP_DIFFBUS(CHIPS)':
 C_PATH='@t6g_mb_lib.t6g(sch_1):page354_i157@pure_quanta.q_cap_diffbus(chips)',
 P_PATH='@t6g_mb_lib.t6g(sch_1):page66_i157@pure_quanta.q_cap_diffbus(chips)',
 PATH='I157',
 DRAWING='@T6G_MB_LIB.T6G(SCH_1):PAGE354',
 PIN_NAMES_ROTATE='TRUE',
 TOLERANCE='20%',
 MATERIAL='X6S',
 PHYS_PAGE='66',
 XY='(3625,2425)',
 ROT='2',
 VER='2',
 PACK_TYPE='C0201',
 LOCATION='C754',
 CDS_LIB='pure_quanta',
 CDS_PART_NAME='Q_CAP_DIFFBUS_C0201-DIFF BUS_0.22UF,6.3V,20%,X6S,SA',
 VOLTAGE='6.3V',
 PART_NUMBER='SP_CH4221MEE01',
 VALUE='DIFF BUS_0.22UF',
 PRIM_FILE='./archive_libs/logical/q_cap_diffbus/chips/chips.prt';

PART_NAME
 C755 'Q_CAP_DIFFBUS_C0201-DIFF BUS_0.22UF,6.3V,20%,X6S,SA':;

SECTION_NUMBER 1
 '@T6G_MB_LIB.T6G(SCH_1):PAGE354_I156@PURE_QUANTA.Q_CAP_DIFFBUS(CHIPS)':
 C_PATH='@t6g_mb_lib.t6g(sch_1):page354_i156@pure_quanta.q_cap_diffbus(chips)',
 P_PATH='@t6g_mb_lib.t6g(sch_1):page66_i156@pure_quanta.q_cap_diffbus(chips)',
 PATH='I156',
 DRAWING='@T6G_MB_LIB.T6G(SCH_1):PAGE354',
 PIN_NAMES_ROTATE='TRUE',
 TOLERANCE='20%',
 MATERIAL='X6S',
 PHYS_PAGE='66',
 XY='(3625,2375)',
 ROT='2',
 VER='2',
 PACK_TYPE='C0201',
 LOCATION='C755',
 CDS_LIB='pure_quanta',
 CDS_PART_NAME='Q_CAP_DIFFBUS_C0201-DIFF BUS_0.22UF,6.3V,20%,X6S,SA',
 VOLTAGE='6.3V',
 PART_NUMBER='SP_CH4221MEE01',
 VALUE='DIFF BUS_0.22UF',
 PRIM_FILE='./archive_libs/logical/q_cap_diffbus/chips/chips.prt';

PART_NAME
 C756 'Q_CAP_DIFFBUS_C0201-DIFF BUS_0.22UF,6.3V,20%,X6S,SA':;

SECTION_NUMBER 1
 '@T6G_MB_LIB.T6G(SCH_1):PAGE354_I154@PURE_QUANTA.Q_CAP_DIFFBUS(CHIPS)':
 C_PATH='@t6g_mb_lib.t6g(sch_1):page354_i154@pure_quanta.q_cap_diffbus(chips)',
 P_PATH='@t6g_mb_lib.t6g(sch_1):page66_i154@pure_quanta.q_cap_diffbus(chips)',
 PATH='I154',
 DRAWING='@T6G_MB_LIB.T6G(SCH_1):PAGE354',
 PIN_NAMES_ROTATE='TRUE',
 TOLERANCE='20%',
 MATERIAL='X6S',
 PHYS_PAGE='66',
 XY='(3625,2225)',
 ROT='2',
 VER='2',
 PACK_TYPE='C0201',
 LOCATION='C756',
 CDS_LIB='pure_quanta',
 CDS_PART_NAME='Q_CAP_DIFFBUS_C0201-DIFF BUS_0.22UF,6.3V,20%,X6S,SA',
 VOLTAGE='6.3V',
 PART_NUMBER='SP_CH4221MEE01',
 VALUE='DIFF BUS_0.22UF',
 PRIM_FILE='./archive_libs/logical/q_cap_diffbus/chips/chips.prt';

PART_NAME
 C757 'Q_CAP_DIFFBUS_C0201-DIFF BUS_0.22UF,6.3V,20%,X6S,SA':;

SECTION_NUMBER 1
 '@T6G_MB_LIB.T6G(SCH_1):PAGE354_I155@PURE_QUANTA.Q_CAP_DIFFBUS(CHIPS)':
 C_PATH='@t6g_mb_lib.t6g(sch_1):page354_i155@pure_quanta.q_cap_diffbus(chips)',
 P_PATH='@t6g_mb_lib.t6g(sch_1):page66_i155@pure_quanta.q_cap_diffbus(chips)',
 PATH='I155',
 DRAWING='@T6G_MB_LIB.T6G(SCH_1):PAGE354',
 PIN_NAMES_ROTATE='TRUE',
 TOLERANCE='20%',
 MATERIAL='X6S',
 PHYS_PAGE='66',
 XY='(3625,2175)',
 ROT='2',
 VER='2',
 PACK_TYPE='C0201',
 LOCATION='C757',
 CDS_LIB='pure_quanta',
 CDS_PART_NAME='Q_CAP_DIFFBUS_C0201-DIFF BUS_0.22UF,6.3V,20%,X6S,SA',
 VOLTAGE='6.3V',
 PART_NUMBER='SP_CH4221MEE01',
 VALUE='DIFF BUS_0.22UF',
 PRIM_FILE='./archive_libs/logical/q_cap_diffbus/chips/chips.prt';

PART_NAME
 C758 'Q_CAP_DIFFBUS_C0201-DIFF BUS_0.22UF,6.3V,20%,X6S,SA':;

SECTION_NUMBER 1
 '@T6G_MB_LIB.T6G(SCH_1):PAGE354_I140@PURE_QUANTA.Q_CAP_DIFFBUS(CHIPS)':
 C_PATH='@t6g_mb_lib.t6g(sch_1):page354_i140@pure_quanta.q_cap_diffbus(chips)',
 P_PATH='@t6g_mb_lib.t6g(sch_1):page66_i140@pure_quanta.q_cap_diffbus(chips)',
 PATH='I140',
 DRAWING='@T6G_MB_LIB.T6G(SCH_1):PAGE354',
 PIN_NAMES_ROTATE='TRUE',
 TOLERANCE='20%',
 MATERIAL='X6S',
 PHYS_PAGE='66',
 XY='(3625,1650)',
 ROT='2',
 VER='2',
 PACK_TYPE='C0201',
 LOCATION='C758',
 CDS_LIB='pure_quanta',
 CDS_PART_NAME='Q_CAP_DIFFBUS_C0201-DIFF BUS_0.22UF,6.3V,20%,X6S,SA',
 VOLTAGE='6.3V',
 PART_NUMBER='SP_CH4221MEE01',
 VALUE='DIFF BUS_0.22UF',
 PRIM_FILE='./archive_libs/logical/q_cap_diffbus/chips/chips.prt';

PART_NAME
 C759 'Q_CAP_DIFFBUS_C0201-DIFF BUS_0.22UF,6.3V,20%,X6S,SA':;

SECTION_NUMBER 1
 '@T6G_MB_LIB.T6G(SCH_1):PAGE354_I139@PURE_QUANTA.Q_CAP_DIFFBUS(CHIPS)':
 C_PATH='@t6g_mb_lib.t6g(sch_1):page354_i139@pure_quanta.q_cap_diffbus(chips)',
 P_PATH='@t6g_mb_lib.t6g(sch_1):page66_i139@pure_quanta.q_cap_diffbus(chips)',
 PATH='I139',
 DRAWING='@T6G_MB_LIB.T6G(SCH_1):PAGE354',
 PIN_NAMES_ROTATE='TRUE',
 TOLERANCE='20%',
 MATERIAL='X6S',
 PHYS_PAGE='66',
 XY='(3625,1600)',
 ROT='2',
 VER='2',
 PACK_TYPE='C0201',
 LOCATION='C759',
 CDS_LIB='pure_quanta',
 CDS_PART_NAME='Q_CAP_DIFFBUS_C0201-DIFF BUS_0.22UF,6.3V,20%,X6S,SA',
 VOLTAGE='6.3V',
 PART_NUMBER='SP_CH4221MEE01',
 VALUE='DIFF BUS_0.22UF',
 PRIM_FILE='./archive_libs/logical/q_cap_diffbus/chips/chips.prt';

PART_NAME
 C760 'Q_CAP_DIFFBUS_C0201-DIFF BUS_0.22UF,6.3V,20%,X6S,SA':;

SECTION_NUMBER 1
 '@T6G_MB_LIB.T6G(SCH_1):PAGE354_I138@PURE_QUANTA.Q_CAP_DIFFBUS(CHIPS)':
 C_PATH='@t6g_mb_lib.t6g(sch_1):page354_i138@pure_quanta.q_cap_diffbus(chips)',
 P_PATH='@t6g_mb_lib.t6g(sch_1):page66_i138@pure_quanta.q_cap_diffbus(chips)',
 PATH='I138',
 DRAWING='@T6G_MB_LIB.T6G(SCH_1):PAGE354',
 PIN_NAMES_ROTATE='TRUE',
 TOLERANCE='20%',
 MATERIAL='X6S',
 PHYS_PAGE='66',
 XY='(3625,1450)',
 ROT='2',
 VER='2',
 PACK_TYPE='C0201',
 LOCATION='C760',
 CDS_LIB='pure_quanta',
 CDS_PART_NAME='Q_CAP_DIFFBUS_C0201-DIFF BUS_0.22UF,6.3V,20%,X6S,SA',
 VOLTAGE='6.3V',
 PART_NUMBER='SP_CH4221MEE01',
 VALUE='DIFF BUS_0.22UF',
 PRIM_FILE='./archive_libs/logical/q_cap_diffbus/chips/chips.prt';

PART_NAME
 C761 'Q_CAP_DIFFBUS_C0201-DIFF BUS_0.22UF,6.3V,20%,X6S,SA':;

SECTION_NUMBER 1
 '@T6G_MB_LIB.T6G(SCH_1):PAGE354_I137@PURE_QUANTA.Q_CAP_DIFFBUS(CHIPS)':
 C_PATH='@t6g_mb_lib.t6g(sch_1):page354_i137@pure_quanta.q_cap_diffbus(chips)',
 P_PATH='@t6g_mb_lib.t6g(sch_1):page66_i137@pure_quanta.q_cap_diffbus(chips)',
 PATH='I137',
 DRAWING='@T6G_MB_LIB.T6G(SCH_1):PAGE354',
 PIN_NAMES_ROTATE='TRUE',
 TOLERANCE='20%',
 MATERIAL='X6S',
 PHYS_PAGE='66',
 XY='(3625,1400)',
 ROT='2',
 VER='2',
 PACK_TYPE='C0201',
 LOCATION='C761',
 CDS_LIB='pure_quanta',
 CDS_PART_NAME='Q_CAP_DIFFBUS_C0201-DIFF BUS_0.22UF,6.3V,20%,X6S,SA',
 VOLTAGE='6.3V',
 PART_NUMBER='SP_CH4221MEE01',
 VALUE='DIFF BUS_0.22UF',
 PRIM_FILE='./archive_libs/logical/q_cap_diffbus/chips/chips.prt';

PART_NAME
 C762 'Q_CAP_DIFFBUS_C0201-DIFF BUS_0.22UF,6.3V,20%,X6S,SA':;

SECTION_NUMBER 1
 '@T6G_MB_LIB.T6G(SCH_1):PAGE354_I136@PURE_QUANTA.Q_CAP_DIFFBUS(CHIPS)':
 C_PATH='@t6g_mb_lib.t6g(sch_1):page354_i136@pure_quanta.q_cap_diffbus(chips)',
 P_PATH='@t6g_mb_lib.t6g(sch_1):page66_i136@pure_quanta.q_cap_diffbus(chips)',
 PATH='I136',
 DRAWING='@T6G_MB_LIB.T6G(SCH_1):PAGE354',
 PIN_NAMES_ROTATE='TRUE',
 TOLERANCE='20%',
 MATERIAL='X6S',
 PHYS_PAGE='66',
 XY='(3625,1250)',
 ROT='2',
 VER='2',
 PACK_TYPE='C0201',
 LOCATION='C762',
 CDS_LIB='pure_quanta',
 CDS_PART_NAME='Q_CAP_DIFFBUS_C0201-DIFF BUS_0.22UF,6.3V,20%,X6S,SA',
 VOLTAGE='6.3V',
 PART_NUMBER='SP_CH4221MEE01',
 VALUE='DIFF BUS_0.22UF',
 PRIM_FILE='./archive_libs/logical/q_cap_diffbus/chips/chips.prt';

PART_NAME
 C763 'Q_CAP_DIFFBUS_C0201-DIFF BUS_0.22UF,6.3V,20%,X6S,SA':;

SECTION_NUMBER 1
 '@T6G_MB_LIB.T6G(SCH_1):PAGE354_I135@PURE_QUANTA.Q_CAP_DIFFBUS(CHIPS)':
 C_PATH='@t6g_mb_lib.t6g(sch_1):page354_i135@pure_quanta.q_cap_diffbus(chips)',
 P_PATH='@t6g_mb_lib.t6g(sch_1):page66_i135@pure_quanta.q_cap_diffbus(chips)',
 PATH='I135',
 DRAWING='@T6G_MB_LIB.T6G(SCH_1):PAGE354',
 PIN_NAMES_ROTATE='TRUE',
 TOLERANCE='20%',
 MATERIAL='X6S',
 PHYS_PAGE='66',
 XY='(3625,1200)',
 ROT='2',
 VER='2',
 PACK_TYPE='C0201',
 LOCATION='C763',
 CDS_LIB='pure_quanta',
 CDS_PART_NAME='Q_CAP_DIFFBUS_C0201-DIFF BUS_0.22UF,6.3V,20%,X6S,SA',
 VOLTAGE='6.3V',
 PART_NUMBER='SP_CH4221MEE01',
 VALUE='DIFF BUS_0.22UF',
 PRIM_FILE='./archive_libs/logical/q_cap_diffbus/chips/chips.prt';

PART_NAME
 C764 'Q_CAP_DIFFBUS_C0201-DIFF BUS_0.22UF,6.3V,20%,X6S,SA':;

SECTION_NUMBER 1
 '@T6G_MB_LIB.T6G(SCH_1):PAGE354_I130@PURE_QUANTA.Q_CAP_DIFFBUS(CHIPS)':
 C_PATH='@t6g_mb_lib.t6g(sch_1):page354_i130@pure_quanta.q_cap_diffbus(chips)',
 P_PATH='@t6g_mb_lib.t6g(sch_1):page66_i130@pure_quanta.q_cap_diffbus(chips)',
 PATH='I130',
 DRAWING='@T6G_MB_LIB.T6G(SCH_1):PAGE354',
 PIN_NAMES_ROTATE='TRUE',
 TOLERANCE='20%',
 MATERIAL='X6S',
 PHYS_PAGE='66',
 XY='(3625,1050)',
 ROT='2',
 VER='2',
 PACK_TYPE='C0201',
 LOCATION='C764',
 CDS_LIB='pure_quanta',
 CDS_PART_NAME='Q_CAP_DIFFBUS_C0201-DIFF BUS_0.22UF,6.3V,20%,X6S,SA',
 VOLTAGE='6.3V',
 PART_NUMBER='SP_CH4221MEE01',
 VALUE='DIFF BUS_0.22UF',
 PRIM_FILE='./archive_libs/logical/q_cap_diffbus/chips/chips.prt';

PART_NAME
 C765 'Q_CAP_DIFFBUS_C0201-DIFF BUS_0.22UF,6.3V,20%,X6S,SA':;

SECTION_NUMBER 1
 '@T6G_MB_LIB.T6G(SCH_1):PAGE354_I131@PURE_QUANTA.Q_CAP_DIFFBUS(CHIPS)':
 C_PATH='@t6g_mb_lib.t6g(sch_1):page354_i131@pure_quanta.q_cap_diffbus(chips)',
 P_PATH='@t6g_mb_lib.t6g(sch_1):page66_i131@pure_quanta.q_cap_diffbus(chips)',
 PATH='I131',
 DRAWING='@T6G_MB_LIB.T6G(SCH_1):PAGE354',
 PIN_NAMES_ROTATE='TRUE',
 TOLERANCE='20%',
 MATERIAL='X6S',
 PHYS_PAGE='66',
 XY='(3625,1000)',
 ROT='2',
 VER='2',
 PACK_TYPE='C0201',
 LOCATION='C765',
 CDS_LIB='pure_quanta',
 CDS_PART_NAME='Q_CAP_DIFFBUS_C0201-DIFF BUS_0.22UF,6.3V,20%,X6S,SA',
 VOLTAGE='6.3V',
 PART_NUMBER='SP_CH4221MEE01',
 VALUE='DIFF BUS_0.22UF',
 PRIM_FILE='./archive_libs/logical/q_cap_diffbus/chips/chips.prt';

PART_NAME
 C766 'Q_CAP_DIFFBUS_C0201-DIFF BUS_0.22UF,6.3V,20%,X6S,SA':;

SECTION_NUMBER 1
 '@T6G_MB_LIB.T6G(SCH_1):PAGE354_I129@PURE_QUANTA.Q_CAP_DIFFBUS(CHIPS)':
 C_PATH='@t6g_mb_lib.t6g(sch_1):page354_i129@pure_quanta.q_cap_diffbus(chips)',
 P_PATH='@t6g_mb_lib.t6g(sch_1):page66_i129@pure_quanta.q_cap_diffbus(chips)',
 PATH='I129',
 DRAWING='@T6G_MB_LIB.T6G(SCH_1):PAGE354',
 PIN_NAMES_ROTATE='TRUE',
 TOLERANCE='20%',
 MATERIAL='X6S',
 PHYS_PAGE='66',
 XY='(3625,850)',
 ROT='2',
 VER='2',
 PACK_TYPE='C0201',
 LOCATION='C766',
 CDS_LIB='pure_quanta',
 CDS_PART_NAME='Q_CAP_DIFFBUS_C0201-DIFF BUS_0.22UF,6.3V,20%,X6S,SA',
 VOLTAGE='6.3V',
 PART_NUMBER='SP_CH4221MEE01',
 VALUE='DIFF BUS_0.22UF',
 PRIM_FILE='./archive_libs/logical/q_cap_diffbus/chips/chips.prt';

PART_NAME
 C767 'Q_CAP_DIFFBUS_C0201-DIFF BUS_0.22UF,6.3V,20%,X6S,SA':;

SECTION_NUMBER 1
 '@T6G_MB_LIB.T6G(SCH_1):PAGE354_I128@PURE_QUANTA.Q_CAP_DIFFBUS(CHIPS)':
 C_PATH='@t6g_mb_lib.t6g(sch_1):page354_i128@pure_quanta.q_cap_diffbus(chips)',
 P_PATH='@t6g_mb_lib.t6g(sch_1):page66_i128@pure_quanta.q_cap_diffbus(chips)',
 PATH='I128',
 DRAWING='@T6G_MB_LIB.T6G(SCH_1):PAGE354',
 PIN_NAMES_ROTATE='TRUE',
 TOLERANCE='20%',
 MATERIAL='X6S',
 PHYS_PAGE='66',
 XY='(3625,800)',
 ROT='2',
 VER='2',
 PACK_TYPE='C0201',
 LOCATION='C767',
 CDS_LIB='pure_quanta',
 CDS_PART_NAME='Q_CAP_DIFFBUS_C0201-DIFF BUS_0.22UF,6.3V,20%,X6S,SA',
 VOLTAGE='6.3V',
 PART_NUMBER='SP_CH4221MEE01',
 VALUE='DIFF BUS_0.22UF',
 PRIM_FILE='./archive_libs/logical/q_cap_diffbus/chips/chips.prt';

PART_NAME
 C768 'Q_CAP_DIFFBUS_C0201-DIFF BUS_0.22UF,6.3V,20%,X6S,SA':;

SECTION_NUMBER 1
 '@T6G_MB_LIB.T6G(SCH_1):PAGE354_I127@PURE_QUANTA.Q_CAP_DIFFBUS(CHIPS)':
 C_PATH='@t6g_mb_lib.t6g(sch_1):page354_i127@pure_quanta.q_cap_diffbus(chips)',
 P_PATH='@t6g_mb_lib.t6g(sch_1):page66_i127@pure_quanta.q_cap_diffbus(chips)',
 PATH='I127',
 DRAWING='@T6G_MB_LIB.T6G(SCH_1):PAGE354',
 PIN_NAMES_ROTATE='TRUE',
 TOLERANCE='20%',
 MATERIAL='X6S',
 PHYS_PAGE='66',
 XY='(3625,650)',
 ROT='2',
 VER='2',
 PACK_TYPE='C0201',
 LOCATION='C768',
 CDS_LIB='pure_quanta',
 CDS_PART_NAME='Q_CAP_DIFFBUS_C0201-DIFF BUS_0.22UF,6.3V,20%,X6S,SA',
 VOLTAGE='6.3V',
 PART_NUMBER='SP_CH4221MEE01',
 VALUE='DIFF BUS_0.22UF',
 PRIM_FILE='./archive_libs/logical/q_cap_diffbus/chips/chips.prt';

PART_NAME
 C769 'Q_CAP_DIFFBUS_C0201-DIFF BUS_0.22UF,6.3V,20%,X6S,SA':;

SECTION_NUMBER 1
 '@T6G_MB_LIB.T6G(SCH_1):PAGE354_I126@PURE_QUANTA.Q_CAP_DIFFBUS(CHIPS)':
 C_PATH='@t6g_mb_lib.t6g(sch_1):page354_i126@pure_quanta.q_cap_diffbus(chips)',
 P_PATH='@t6g_mb_lib.t6g(sch_1):page66_i126@pure_quanta.q_cap_diffbus(chips)',
 PATH='I126',
 DRAWING='@T6G_MB_LIB.T6G(SCH_1):PAGE354',
 PIN_NAMES_ROTATE='TRUE',
 TOLERANCE='20%',
 MATERIAL='X6S',
 PHYS_PAGE='66',
 XY='(3625,600)',
 ROT='2',
 VER='2',
 PACK_TYPE='C0201',
 LOCATION='C769',
 CDS_LIB='pure_quanta',
 CDS_PART_NAME='Q_CAP_DIFFBUS_C0201-DIFF BUS_0.22UF,6.3V,20%,X6S,SA',
 VOLTAGE='6.3V',
 PART_NUMBER='SP_CH4221MEE01',
 VALUE='DIFF BUS_0.22UF',
 PRIM_FILE='./archive_libs/logical/q_cap_diffbus/chips/chips.prt';

PART_NAME
 C770 'Q_CAP_DIFFBUS_C0201-DIFF BUS_0.22UF,6.3V,20%,X6S,SA':;

SECTION_NUMBER 1
 '@T6G_MB_LIB.T6G(SCH_1):PAGE354_I125@PURE_QUANTA.Q_CAP_DIFFBUS(CHIPS)':
 C_PATH='@t6g_mb_lib.t6g(sch_1):page354_i125@pure_quanta.q_cap_diffbus(chips)',
 P_PATH='@t6g_mb_lib.t6g(sch_1):page66_i125@pure_quanta.q_cap_diffbus(chips)',
 PATH='I125',
 DRAWING='@T6G_MB_LIB.T6G(SCH_1):PAGE354',
 PIN_NAMES_ROTATE='TRUE',
 TOLERANCE='20%',
 MATERIAL='X6S',
 PHYS_PAGE='66',
 XY='(3625,450)',
 ROT='2',
 VER='2',
 PACK_TYPE='C0201',
 LOCATION='C770',
 CDS_LIB='pure_quanta',
 CDS_PART_NAME='Q_CAP_DIFFBUS_C0201-DIFF BUS_0.22UF,6.3V,20%,X6S,SA',
 VOLTAGE='6.3V',
 PART_NUMBER='SP_CH4221MEE01',
 VALUE='DIFF BUS_0.22UF',
 PRIM_FILE='./archive_libs/logical/q_cap_diffbus/chips/chips.prt';

PART_NAME
 C771 'Q_CAP_DIFFBUS_C0201-DIFF BUS_0.22UF,6.3V,20%,X6S,SA':;

SECTION_NUMBER 1
 '@T6G_MB_LIB.T6G(SCH_1):PAGE354_I124@PURE_QUANTA.Q_CAP_DIFFBUS(CHIPS)':
 C_PATH='@t6g_mb_lib.t6g(sch_1):page354_i124@pure_quanta.q_cap_diffbus(chips)',
 P_PATH='@t6g_mb_lib.t6g(sch_1):page66_i124@pure_quanta.q_cap_diffbus(chips)',
 PATH='I124',
 DRAWING='@T6G_MB_LIB.T6G(SCH_1):PAGE354',
 PIN_NAMES_ROTATE='TRUE',
 TOLERANCE='20%',
 MATERIAL='X6S',
 PHYS_PAGE='66',
 XY='(3625,400)',
 ROT='2',
 VER='2',
 PACK_TYPE='C0201',
 LOCATION='C771',
 CDS_LIB='pure_quanta',
 CDS_PART_NAME='Q_CAP_DIFFBUS_C0201-DIFF BUS_0.22UF,6.3V,20%,X6S,SA',
 VOLTAGE='6.3V',
 PART_NUMBER='SP_CH4221MEE01',
 VALUE='DIFF BUS_0.22UF',
 PRIM_FILE='./archive_libs/logical/q_cap_diffbus/chips/chips.prt';

PART_NAME
 C772 'Q_CAP_DIFFBUS_C0201-DIFF BUS_0.22UF,6.3V,20%,X6S,SA':;

SECTION_NUMBER 1
 '@T6G_MB_LIB.T6G(SCH_1):PAGE354_I123@PURE_QUANTA.Q_CAP_DIFFBUS(CHIPS)':
 C_PATH='@t6g_mb_lib.t6g(sch_1):page354_i123@pure_quanta.q_cap_diffbus(chips)',
 P_PATH='@t6g_mb_lib.t6g(sch_1):page66_i123@pure_quanta.q_cap_diffbus(chips)',
 PATH='I123',
 DRAWING='@T6G_MB_LIB.T6G(SCH_1):PAGE354',
 PIN_NAMES_ROTATE='TRUE',
 TOLERANCE='20%',
 MATERIAL='X6S',
 PHYS_PAGE='66',
 XY='(3625,250)',
 ROT='2',
 VER='2',
 PACK_TYPE='C0201',
 LOCATION='C772',
 CDS_LIB='pure_quanta',
 CDS_PART_NAME='Q_CAP_DIFFBUS_C0201-DIFF BUS_0.22UF,6.3V,20%,X6S,SA',
 VOLTAGE='6.3V',
 PART_NUMBER='SP_CH4221MEE01',
 VALUE='DIFF BUS_0.22UF',
 PRIM_FILE='./archive_libs/logical/q_cap_diffbus/chips/chips.prt';

PART_NAME
 C773 'Q_CAP_DIFFBUS_C0201-DIFF BUS_0.22UF,6.3V,20%,X6S,SA':;

SECTION_NUMBER 1
 '@T6G_MB_LIB.T6G(SCH_1):PAGE354_I122@PURE_QUANTA.Q_CAP_DIFFBUS(CHIPS)':
 C_PATH='@t6g_mb_lib.t6g(sch_1):page354_i122@pure_quanta.q_cap_diffbus(chips)',
 P_PATH='@t6g_mb_lib.t6g(sch_1):page66_i122@pure_quanta.q_cap_diffbus(chips)',
 PATH='I122',
 DRAWING='@T6G_MB_LIB.T6G(SCH_1):PAGE354',
 PIN_NAMES_ROTATE='TRUE',
 TOLERANCE='20%',
 MATERIAL='X6S',
 PHYS_PAGE='66',
 XY='(3625,200)',
 ROT='2',
 VER='2',
 PACK_TYPE='C0201',
 LOCATION='C773',
 CDS_LIB='pure_quanta',
 CDS_PART_NAME='Q_CAP_DIFFBUS_C0201-DIFF BUS_0.22UF,6.3V,20%,X6S,SA',
 VOLTAGE='6.3V',
 PART_NUMBER='SP_CH4221MEE01',
 VALUE='DIFF BUS_0.22UF',
 PRIM_FILE='./archive_libs/logical/q_cap_diffbus/chips/chips.prt';

PART_NAME
 C774 'Q_CAP_C0201-0.1UF,10V,10%,X7S,CH4102K6E00':;

SECTION_NUMBER 1
 '@T6G_MB_LIB.T6G(SCH_1):PAGE422_I17@PURE_QUANTA.Q_CAP(CHIPS)':
 C_PATH='@t6g_mb_lib.t6g(sch_1):page422_i17@pure_quanta.q_cap(chips)',
 P_PATH='@t6g_mb_lib.t6g(sch_1):page301_i17@pure_quanta.q_cap(chips)',
 PATH='I17',
 DRAWING='@T6G_MB_LIB.T6G(SCH_1):PAGE422',
 TOLERANCE='10%',
 MATERIAL='X7S',
 PHYS_PAGE='301',
 XY='(-5775,4475)',
 ROT='0',
 VER='1',
 PACK_TYPE='C0201',
 LOCATION='C774',
 CDS_LIB='pure_quanta',
 CDS_PART_NAME='Q_CAP_C0201-0.1UF,10V,10%,X7S,CH4102K6E00',
 VOLTAGE='10V',
 PART_NUMBER='CH4102K6E00',
 VALUE='0.1UF',
 PRIM_FILE='./archive_libs/logical/q_cap/chips/chips.prt';

PART_NAME
 C775 'Q_CAP_C0201-0.1UF,10V,10%,X7S,CH4102K6E00':;

SECTION_NUMBER 1
 '@T6G_MB_LIB.T6G(SCH_1):PAGE422_I10@PURE_QUANTA.Q_CAP(CHIPS)':
 C_PATH='@t6g_mb_lib.t6g(sch_1):page422_i10@pure_quanta.q_cap(chips)',
 P_PATH='@t6g_mb_lib.t6g(sch_1):page301_i10@pure_quanta.q_cap(chips)',
 PATH='I10',
 DRAWING='@T6G_MB_LIB.T6G(SCH_1):PAGE422',
 TOLERANCE='10%',
 MATERIAL='X7S',
 PHYS_PAGE='301',
 XY='(-6350,3375)',
 ROT='0',
 VER='1',
 PACK_TYPE='C0201',
 LOCATION='C775',
 CDS_LIB='pure_quanta',
 CDS_PART_NAME='Q_CAP_C0201-0.1UF,10V,10%,X7S,CH4102K6E00',
 VOLTAGE='10V',
 PART_NUMBER='CH4102K6E00',
 VALUE='0.1UF',
 PRIM_FILE='./archive_libs/logical/q_cap/chips/chips.prt';

PART_NAME
 C776 'Q_CAP_C0201-0.1UF,10V,10%,X7S,CH4102K6E00':;

SECTION_NUMBER 1
 '@T6G_MB_LIB.T6G(SCH_1):PAGE422_I18@PURE_QUANTA.Q_CAP(CHIPS)':
 C_PATH='@t6g_mb_lib.t6g(sch_1):page422_i18@pure_quanta.q_cap(chips)',
 P_PATH='@t6g_mb_lib.t6g(sch_1):page301_i18@pure_quanta.q_cap(chips)',
 PATH='I18',
 DRAWING='@T6G_MB_LIB.T6G(SCH_1):PAGE422',
 TOLERANCE='10%',
 MATERIAL='X7S',
 PHYS_PAGE='301',
 XY='(-5525,4475)',
 ROT='0',
 VER='1',
 PACK_TYPE='C0201',
 LOCATION='C776',
 CDS_LIB='pure_quanta',
 CDS_PART_NAME='Q_CAP_C0201-0.1UF,10V,10%,X7S,CH4102K6E00',
 VOLTAGE='10V',
 PART_NUMBER='CH4102K6E00',
 VALUE='0.1UF',
 PRIM_FILE='./archive_libs/logical/q_cap/chips/chips.prt';

PART_NAME
 C777 'Q_CAP_C0201-0.1UF,10V,10%,X7S,CH4102K6E00':;

SECTION_NUMBER 1
 '@T6G_MB_LIB.T6G(SCH_1):PAGE422_I19@PURE_QUANTA.Q_CAP(CHIPS)':
 C_PATH='@t6g_mb_lib.t6g(sch_1):page422_i19@pure_quanta.q_cap(chips)',
 P_PATH='@t6g_mb_lib.t6g(sch_1):page301_i19@pure_quanta.q_cap(chips)',
 PATH='I19',
 DRAWING='@T6G_MB_LIB.T6G(SCH_1):PAGE422',
 TOLERANCE='10%',
 MATERIAL='X7S',
 PHYS_PAGE='301',
 XY='(-5275,4475)',
 ROT='0',
 VER='1',
 PACK_TYPE='C0201',
 LOCATION='C777',
 CDS_LIB='pure_quanta',
 CDS_PART_NAME='Q_CAP_C0201-0.1UF,10V,10%,X7S,CH4102K6E00',
 VOLTAGE='10V',
 PART_NUMBER='CH4102K6E00',
 VALUE='0.1UF',
 PRIM_FILE='./archive_libs/logical/q_cap/chips/chips.prt';

PART_NAME
 C778 'Q_CAP_C0201-0.1UF,10V,10%,X7S,CH4102K6E00':;

SECTION_NUMBER 1
 '@T6G_MB_LIB.T6G(SCH_1):PAGE422_I20@PURE_QUANTA.Q_CAP(CHIPS)':
 C_PATH='@t6g_mb_lib.t6g(sch_1):page422_i20@pure_quanta.q_cap(chips)',
 P_PATH='@t6g_mb_lib.t6g(sch_1):page301_i20@pure_quanta.q_cap(chips)',
 PATH='I20',
 DRAWING='@T6G_MB_LIB.T6G(SCH_1):PAGE422',
 TOLERANCE='10%',
 MATERIAL='X7S',
 PHYS_PAGE='301',
 XY='(-5000,4475)',
 ROT='0',
 VER='1',
 PACK_TYPE='C0201',
 LOCATION='C778',
 CDS_LIB='pure_quanta',
 CDS_PART_NAME='Q_CAP_C0201-0.1UF,10V,10%,X7S,CH4102K6E00',
 VOLTAGE='10V',
 PART_NUMBER='CH4102K6E00',
 VALUE='0.1UF',
 PRIM_FILE='./archive_libs/logical/q_cap/chips/chips.prt';

PART_NAME
 C779 'Q_CAP_0201-1UF,4V,20%,X6S,CH-10KMEE00':;

SECTION_NUMBER 1
 '@T6G_MB_LIB.T6G(SCH_1):PAGE422_I73@PURE_QUANTA.Q_CAP(CHIPS)':
 C_PATH='@t6g_mb_lib.t6g(sch_1):page422_i73@pure_quanta.q_cap(chips)',
 P_PATH='@t6g_mb_lib.t6g(sch_1):page301_i73@pure_quanta.q_cap(chips)',
 PATH='I73',
 DRAWING='@T6G_MB_LIB.T6G(SCH_1):PAGE422',
 TOLERANCE='20%',
 MATERIAL='X6S',
 PHYS_PAGE='301',
 XY='(-1250,3850)',
 ROT='0',
 VER='1',
 PACK_TYPE='0201',
 LOCATION='C779',
 CDS_LIB='pure_quanta',
 CDS_PART_NAME='Q_CAP_0201-1UF,4V,20%,X6S,CH-10KMEE00',
 VOLTAGE='4V',
 PART_NUMBER='CH-10KMEE00',
 VALUE='1UF',
 PRIM_FILE='./archive_libs/logical/q_cap/chips/chips.prt';

PART_NAME
 C780 'Q_CAP_C0201-0.1UF,10V,10%,X7S,CH4102K6E00':;

SECTION_NUMBER 1
 '@T6G_MB_LIB.T6G(SCH_1):PAGE422_I82@PURE_QUANTA.Q_CAP(CHIPS)':
 C_PATH='@t6g_mb_lib.t6g(sch_1):page422_i82@pure_quanta.q_cap(chips)',
 P_PATH='@t6g_mb_lib.t6g(sch_1):page301_i82@pure_quanta.q_cap(chips)',
 PATH='I82',
 DRAWING='@T6G_MB_LIB.T6G(SCH_1):PAGE422',
 TOLERANCE='10%',
 MATERIAL='X7S',
 PHYS_PAGE='301',
 XY='(-1775,5700)',
 ROT='0',
 VER='1',
 PACK_TYPE='C0201',
 LOCATION='C780',
 CDS_LIB='pure_quanta',
 CDS_PART_NAME='Q_CAP_C0201-0.1UF,10V,10%,X7S,CH4102K6E00',
 VOLTAGE='10V',
 PART_NUMBER='CH4102K6E00',
 VALUE='0.1UF',
 PRIM_FILE='./archive_libs/logical/q_cap/chips/chips.prt';

PART_NAME
 C781 'Q_CAP_0201-1UF,4V,20%,X6S,CH-10KMEE00':;

SECTION_NUMBER 1
 '@T6G_MB_LIB.T6G(SCH_1):PAGE422_I45@PURE_QUANTA.Q_CAP(CHIPS)':
 C_PATH='@t6g_mb_lib.t6g(sch_1):page422_i45@pure_quanta.q_cap(chips)',
 P_PATH='@t6g_mb_lib.t6g(sch_1):page301_i45@pure_quanta.q_cap(chips)',
 PATH='I45',
 DRAWING='@T6G_MB_LIB.T6G(SCH_1):PAGE422',
 TOLERANCE='20%',
 MATERIAL='X6S',
 PHYS_PAGE='301',
 XY='(-3100,3225)',
 ROT='0',
 VER='1',
 PACK_TYPE='0201',
 LOCATION='C781',
 CDS_LIB='pure_quanta',
 CDS_PART_NAME='Q_CAP_0201-1UF,4V,20%,X6S,CH-10KMEE00',
 VOLTAGE='4V',
 PART_NUMBER='CH-10KMEE00',
 VALUE='1UF',
 PRIM_FILE='./archive_libs/logical/q_cap/chips/chips.prt';

PART_NAME
 C782 'Q_CAP_C0201-0.1UF,10V,10%,X7S,CH4102K6E00':;

SECTION_NUMBER 1
 '@T6G_MB_LIB.T6G(SCH_1):PAGE422_I83@PURE_QUANTA.Q_CAP(CHIPS)':
 C_PATH='@t6g_mb_lib.t6g(sch_1):page422_i83@pure_quanta.q_cap(chips)',
 P_PATH='@t6g_mb_lib.t6g(sch_1):page301_i83@pure_quanta.q_cap(chips)',
 PATH='I83',
 DRAWING='@T6G_MB_LIB.T6G(SCH_1):PAGE422',
 TOLERANCE='10%',
 MATERIAL='X7S',
 PHYS_PAGE='301',
 XY='(-1500,5700)',
 ROT='0',
 VER='1',
 PACK_TYPE='C0201',
 LOCATION='C782',
 CDS_LIB='pure_quanta',
 CDS_PART_NAME='Q_CAP_C0201-0.1UF,10V,10%,X7S,CH4102K6E00',
 VOLTAGE='10V',
 PART_NUMBER='CH4102K6E00',
 VALUE='0.1UF',
 PRIM_FILE='./archive_libs/logical/q_cap/chips/chips.prt';

PART_NAME
 C783 'Q_CAP_0201-1UF,4V,20%,X6S,CH-10KMEE00':;

SECTION_NUMBER 1
 '@T6G_MB_LIB.T6G(SCH_1):PAGE422_I62@PURE_QUANTA.Q_CAP(CHIPS)':
 C_PATH='@t6g_mb_lib.t6g(sch_1):page422_i62@pure_quanta.q_cap(chips)',
 P_PATH='@t6g_mb_lib.t6g(sch_1):page301_i62@pure_quanta.q_cap(chips)',
 PATH='I62',
 DRAWING='@T6G_MB_LIB.T6G(SCH_1):PAGE422',
 TOLERANCE='20%',
 MATERIAL='X6S',
 PHYS_PAGE='301',
 XY='(-1725,3850)',
 ROT='0',
 VER='1',
 PACK_TYPE='0201',
 LOCATION='C783',
 CDS_LIB='pure_quanta',
 CDS_PART_NAME='Q_CAP_0201-1UF,4V,20%,X6S,CH-10KMEE00',
 VOLTAGE='4V',
 PART_NUMBER='CH-10KMEE00',
 VALUE='1UF',
 PRIM_FILE='./archive_libs/logical/q_cap/chips/chips.prt';

PART_NAME
 C784 'Q_CAP_C0201-0.1UF,10V,10%,X7S,CH4102K6E00':;

SECTION_NUMBER 1
 '@T6G_MB_LIB.T6G(SCH_1):PAGE422_I43@PURE_QUANTA.Q_CAP(CHIPS)':
 C_PATH='@t6g_mb_lib.t6g(sch_1):page422_i43@pure_quanta.q_cap(chips)',
 P_PATH='@t6g_mb_lib.t6g(sch_1):page301_i43@pure_quanta.q_cap(chips)',
 PATH='I43',
 DRAWING='@T6G_MB_LIB.T6G(SCH_1):PAGE422',
 TOLERANCE='10%',
 MATERIAL='X7S',
 PHYS_PAGE='301',
 XY='(-1750,2525)',
 ROT='0',
 VER='1',
 PACK_TYPE='C0201',
 LOCATION='C784',
 CDS_LIB='pure_quanta',
 CDS_PART_NAME='Q_CAP_C0201-0.1UF,10V,10%,X7S,CH4102K6E00',
 VOLTAGE='10V',
 PART_NUMBER='CH4102K6E00',
 VALUE='0.1UF',
 PRIM_FILE='./archive_libs/logical/q_cap/chips/chips.prt';

PART_NAME
 C785 'Q_CAP_C0201-0.1UF,10V,10%,X7S,CH4102K6E00':;

SECTION_NUMBER 1
 '@T6G_MB_LIB.T6G(SCH_1):PAGE422_I84@PURE_QUANTA.Q_CAP(CHIPS)':
 C_PATH='@t6g_mb_lib.t6g(sch_1):page422_i84@pure_quanta.q_cap(chips)',
 P_PATH='@t6g_mb_lib.t6g(sch_1):page301_i84@pure_quanta.q_cap(chips)',
 PATH='I84',
 DRAWING='@T6G_MB_LIB.T6G(SCH_1):PAGE422',
 TOLERANCE='10%',
 MATERIAL='X7S',
 PHYS_PAGE='301',
 XY='(-1250,5700)',
 ROT='0',
 VER='1',
 PACK_TYPE='C0201',
 LOCATION='C785',
 CDS_LIB='pure_quanta',
 CDS_PART_NAME='Q_CAP_C0201-0.1UF,10V,10%,X7S,CH4102K6E00',
 VOLTAGE='10V',
 PART_NUMBER='CH4102K6E00',
 VALUE='0.1UF',
 PRIM_FILE='./archive_libs/logical/q_cap/chips/chips.prt';

PART_NAME
 C786 'Q_CAP_0201-1UF,4V,20%,X6S,CH-10KMEE00':;

SECTION_NUMBER 1
 '@T6G_MB_LIB.T6G(SCH_1):PAGE422_I72@PURE_QUANTA.Q_CAP(CHIPS)':
 C_PATH='@t6g_mb_lib.t6g(sch_1):page422_i72@pure_quanta.q_cap(chips)',
 P_PATH='@t6g_mb_lib.t6g(sch_1):page301_i72@pure_quanta.q_cap(chips)',
 PATH='I72',
 DRAWING='@T6G_MB_LIB.T6G(SCH_1):PAGE422',
 TOLERANCE='20%',
 MATERIAL='X6S',
 PHYS_PAGE='301',
 XY='(-1500,3850)',
 ROT='0',
 VER='1',
 PACK_TYPE='0201',
 LOCATION='C786',
 CDS_LIB='pure_quanta',
 CDS_PART_NAME='Q_CAP_0201-1UF,4V,20%,X6S,CH-10KMEE00',
 VOLTAGE='4V',
 PART_NUMBER='CH-10KMEE00',
 VALUE='1UF',
 PRIM_FILE='./archive_libs/logical/q_cap/chips/chips.prt';

PART_NAME
 C787 'Q_CAP_0201-1UF,4V,20%,X6S,CH-10KMEE00':;

SECTION_NUMBER 1
 '@T6G_MB_LIB.T6G(SCH_1):PAGE422_I90@PURE_QUANTA.Q_CAP(CHIPS)':
 C_PATH='@t6g_mb_lib.t6g(sch_1):page422_i90@pure_quanta.q_cap(chips)',
 P_PATH='@t6g_mb_lib.t6g(sch_1):page301_i90@pure_quanta.q_cap(chips)',
 PATH='I90',
 DRAWING='@T6G_MB_LIB.T6G(SCH_1):PAGE422',
 TOLERANCE='20%',
 MATERIAL='X6S',
 PHYS_PAGE='301',
 XY='(-2875,1425)',
 ROT='0',
 VER='1',
 PACK_TYPE='0201',
 LOCATION='C787',
 CDS_LIB='pure_quanta',
 CDS_PART_NAME='Q_CAP_0201-1UF,4V,20%,X6S,CH-10KMEE00',
 VOLTAGE='4V',
 PART_NUMBER='CH-10KMEE00',
 VALUE='1UF',
 PRIM_FILE='./archive_libs/logical/q_cap/chips/chips.prt';

PART_NAME
 C788 'Q_CAP_0201-1UF,4V,20%,X6S,CH-10KMEE00':;

SECTION_NUMBER 1
 '@T6G_MB_LIB.T6G(SCH_1):PAGE422_I46@PURE_QUANTA.Q_CAP(CHIPS)':
 C_PATH='@t6g_mb_lib.t6g(sch_1):page422_i46@pure_quanta.q_cap(chips)',
 P_PATH='@t6g_mb_lib.t6g(sch_1):page301_i46@pure_quanta.q_cap(chips)',
 PATH='I46',
 DRAWING='@T6G_MB_LIB.T6G(SCH_1):PAGE422',
 TOLERANCE='20%',
 MATERIAL='X6S',
 PHYS_PAGE='301',
 XY='(-2850,3225)',
 ROT='0',
 VER='1',
 PACK_TYPE='0201',
 LOCATION='C788',
 CDS_LIB='pure_quanta',
 CDS_PART_NAME='Q_CAP_0201-1UF,4V,20%,X6S,CH-10KMEE00',
 VOLTAGE='4V',
 PART_NUMBER='CH-10KMEE00',
 VALUE='1UF',
 PRIM_FILE='./archive_libs/logical/q_cap/chips/chips.prt';

PART_NAME
 C789 'Q_CAP_C0201-0.1UF,10V,10%,X7S,CH4102K6E00':;

SECTION_NUMBER 1
 '@T6G_MB_LIB.T6G(SCH_1):PAGE422_I86@PURE_QUANTA.Q_CAP(CHIPS)':
 C_PATH='@t6g_mb_lib.t6g(sch_1):page422_i86@pure_quanta.q_cap(chips)',
 P_PATH='@t6g_mb_lib.t6g(sch_1):page301_i86@pure_quanta.q_cap(chips)',
 PATH='I86',
 DRAWING='@T6G_MB_LIB.T6G(SCH_1):PAGE422',
 TOLERANCE='10%',
 MATERIAL='X7S',
 PHYS_PAGE='301',
 XY='(-975,5700)',
 ROT='0',
 VER='1',
 PACK_TYPE='C0201',
 LOCATION='C789',
 CDS_LIB='pure_quanta',
 CDS_PART_NAME='Q_CAP_C0201-0.1UF,10V,10%,X7S,CH4102K6E00',
 VOLTAGE='10V',
 PART_NUMBER='CH4102K6E00',
 VALUE='0.1UF',
 PRIM_FILE='./archive_libs/logical/q_cap/chips/chips.prt';

PART_NAME
 C790 'Q_CAP_C0201-0.1UF,10V,10%,X7S,CH4102K6E00':;

SECTION_NUMBER 1
 '@T6G_MB_LIB.T6G(SCH_1):PAGE422_I40@PURE_QUANTA.Q_CAP(CHIPS)':
 C_PATH='@t6g_mb_lib.t6g(sch_1):page422_i40@pure_quanta.q_cap(chips)',
 P_PATH='@t6g_mb_lib.t6g(sch_1):page301_i40@pure_quanta.q_cap(chips)',
 PATH='I40',
 DRAWING='@T6G_MB_LIB.T6G(SCH_1):PAGE422',
 TOLERANCE='10%',
 MATERIAL='X7S',
 PHYS_PAGE='301',
 XY='(-2525,2525)',
 ROT='0',
 VER='1',
 PACK_TYPE='C0201',
 LOCATION='C790',
 CDS_LIB='pure_quanta',
 CDS_PART_NAME='Q_CAP_C0201-0.1UF,10V,10%,X7S,CH4102K6E00',
 VOLTAGE='10V',
 PART_NUMBER='CH4102K6E00',
 VALUE='0.1UF',
 PRIM_FILE='./archive_libs/logical/q_cap/chips/chips.prt';

PART_NAME
 C791 'Q_CAP_C0201-0.1UF,10V,10%,X7S,CH4102K6E00':;

SECTION_NUMBER 1
 '@T6G_MB_LIB.T6G(SCH_1):PAGE422_I36@PURE_QUANTA.Q_CAP(CHIPS)':
 C_PATH='@t6g_mb_lib.t6g(sch_1):page422_i36@pure_quanta.q_cap(chips)',
 P_PATH='@t6g_mb_lib.t6g(sch_1):page301_i36@pure_quanta.q_cap(chips)',
 PATH='I36',
 DRAWING='@T6G_MB_LIB.T6G(SCH_1):PAGE422',
 TOLERANCE='10%',
 MATERIAL='X7S',
 PHYS_PAGE='301',
 XY='(-2625,1425)',
 ROT='0',
 VER='1',
 PACK_TYPE='C0201',
 LOCATION='C791',
 CDS_LIB='pure_quanta',
 CDS_PART_NAME='Q_CAP_C0201-0.1UF,10V,10%,X7S,CH4102K6E00',
 VOLTAGE='10V',
 PART_NUMBER='CH4102K6E00',
 VALUE='0.1UF',
 PRIM_FILE='./archive_libs/logical/q_cap/chips/chips.prt';

PART_NAME
 C792 'Q_CAP_0201-1UF,4V,20%,X6S,CH-10KMEE00':;

SECTION_NUMBER 1
 '@T6G_MB_LIB.T6G(SCH_1):PAGE422_I52@PURE_QUANTA.Q_CAP(CHIPS)':
 C_PATH='@t6g_mb_lib.t6g(sch_1):page422_i52@pure_quanta.q_cap(chips)',
 P_PATH='@t6g_mb_lib.t6g(sch_1):page301_i52@pure_quanta.q_cap(chips)',
 PATH='I52',
 DRAWING='@T6G_MB_LIB.T6G(SCH_1):PAGE422',
 TOLERANCE='20%',
 MATERIAL='X6S',
 PHYS_PAGE='301',
 XY='(-2625,3225)',
 ROT='0',
 VER='1',
 PACK_TYPE='0201',
 LOCATION='C792',
 CDS_LIB='pure_quanta',
 CDS_PART_NAME='Q_CAP_0201-1UF,4V,20%,X6S,CH-10KMEE00',
 VOLTAGE='4V',
 PART_NUMBER='CH-10KMEE00',
 VALUE='1UF',
 PRIM_FILE='./archive_libs/logical/q_cap/chips/chips.prt';

PART_NAME
 C793 'Q_CAP_0201-1UF,4V,20%,X6S,CH-10KMEE00':;

SECTION_NUMBER 1
 '@T6G_MB_LIB.T6G(SCH_1):PAGE422_I91@PURE_QUANTA.Q_CAP(CHIPS)':
 C_PATH='@t6g_mb_lib.t6g(sch_1):page422_i91@pure_quanta.q_cap(chips)',
 P_PATH='@t6g_mb_lib.t6g(sch_1):page301_i91@pure_quanta.q_cap(chips)',
 PATH='I91',
 DRAWING='@T6G_MB_LIB.T6G(SCH_1):PAGE422',
 TOLERANCE='20%',
 MATERIAL='X6S',
 PHYS_PAGE='301',
 XY='(-2325,1425)',
 ROT='0',
 VER='1',
 PACK_TYPE='0201',
 LOCATION='C793',
 CDS_LIB='pure_quanta',
 CDS_PART_NAME='Q_CAP_0201-1UF,4V,20%,X6S,CH-10KMEE00',
 VOLTAGE='4V',
 PART_NUMBER='CH-10KMEE00',
 VALUE='1UF',
 PRIM_FILE='./archive_libs/logical/q_cap/chips/chips.prt';

PART_NAME
 C794 'Q_CAP_C0201-0.1UF,10V,10%,X7S,CH4102K6E00':;

SECTION_NUMBER 1
 '@T6G_MB_LIB.T6G(SCH_1):PAGE422_I39@PURE_QUANTA.Q_CAP(CHIPS)':
 C_PATH='@t6g_mb_lib.t6g(sch_1):page422_i39@pure_quanta.q_cap(chips)',
 P_PATH='@t6g_mb_lib.t6g(sch_1):page301_i39@pure_quanta.q_cap(chips)',
 PATH='I39',
 DRAWING='@T6G_MB_LIB.T6G(SCH_1):PAGE422',
 TOLERANCE='10%',
 MATERIAL='X7S',
 PHYS_PAGE='301',
 XY='(-2075,1425)',
 ROT='0',
 VER='1',
 PACK_TYPE='C0201',
 LOCATION='C794',
 CDS_LIB='pure_quanta',
 CDS_PART_NAME='Q_CAP_C0201-0.1UF,10V,10%,X7S,CH4102K6E00',
 VOLTAGE='10V',
 PART_NUMBER='CH4102K6E00',
 VALUE='0.1UF',
 PRIM_FILE='./archive_libs/logical/q_cap/chips/chips.prt';

PART_NAME
 C795 'Q_CAP_C0805-100UF,4V,20%,X6S,CH710KMEA01':;

SECTION_NUMBER 1
 '@T6G_MB_LIB.T6G(SCH_1):PAGE422_I48@PURE_QUANTA.Q_CAP(CHIPS)':
 C_PATH='@t6g_mb_lib.t6g(sch_1):page422_i48@pure_quanta.q_cap(chips)',
 P_PATH='@t6g_mb_lib.t6g(sch_1):page301_i48@pure_quanta.q_cap(chips)',
 PATH='I48',
 DRAWING='@T6G_MB_LIB.T6G(SCH_1):PAGE422',
 TOLERANCE='20%',
 MATERIAL='X6S',
 PHYS_PAGE='301',
 XY='(-3325,4475)',
 ROT='0',
 VER='1',
 PACK_TYPE='C0805',
 LOCATION='C795',
 CDS_LIB='pure_quanta',
 CDS_PART_NAME='Q_CAP_C0805-100UF,4V,20%,X6S,CH710KMEA01',
 VOLTAGE='4V',
 PART_NUMBER='CH710KMEA01',
 VALUE='100UF',
 PRIM_FILE='./archive_libs/logical/q_cap/chips/chips.prt';

PART_NAME
 C796 'Q_CAP_C0402-10UF,6.3V,20%,X6S,CH6101MEB01':;

SECTION_NUMBER 1
 '@T6G_MB_LIB.T6G(SCH_1):PAGE422_I47@PURE_QUANTA.Q_CAP(CHIPS)':
 C_PATH='@t6g_mb_lib.t6g(sch_1):page422_i47@pure_quanta.q_cap(chips)',
 P_PATH='@t6g_mb_lib.t6g(sch_1):page301_i47@pure_quanta.q_cap(chips)',
 PATH='I47',
 DRAWING='@T6G_MB_LIB.T6G(SCH_1):PAGE422',
 TOLERANCE='20%',
 MATERIAL='X6S',
 PHYS_PAGE='301',
 XY='(-3325,3850)',
 ROT='0',
 VER='1',
 PACK_TYPE='C0402',
 LOCATION='C796',
 CDS_LIB='pure_quanta',
 CDS_PART_NAME='Q_CAP_C0402-10UF,6.3V,20%,X6S,CH6101MEB01',
 VOLTAGE='6.3V',
 PART_NUMBER='CH6101MEB01',
 VALUE='10UF',
 PRIM_FILE='./archive_libs/logical/q_cap/chips/chips.prt';

PART_NAME
 C797 'Q_CAP_0201-1UF,4V,20%,X6S,CH-10KMEE00':;

SECTION_NUMBER 1
 '@T6G_MB_LIB.T6G(SCH_1):PAGE422_I44@PURE_QUANTA.Q_CAP(CHIPS)':
 C_PATH='@t6g_mb_lib.t6g(sch_1):page422_i44@pure_quanta.q_cap(chips)',
 P_PATH='@t6g_mb_lib.t6g(sch_1):page301_i44@pure_quanta.q_cap(chips)',
 PATH='I44',
 DRAWING='@T6G_MB_LIB.T6G(SCH_1):PAGE422',
 TOLERANCE='20%',
 MATERIAL='X6S',
 PHYS_PAGE='301',
 XY='(-3325,3225)',
 ROT='0',
 VER='1',
 PACK_TYPE='0201',
 LOCATION='C797',
 CDS_LIB='pure_quanta',
 CDS_PART_NAME='Q_CAP_0201-1UF,4V,20%,X6S,CH-10KMEE00',
 VOLTAGE='4V',
 PART_NUMBER='CH-10KMEE00',
 VALUE='1UF',
 PRIM_FILE='./archive_libs/logical/q_cap/chips/chips.prt';

PART_NAME
 C798 'Q_CAP_C0805-100UF,4V,20%,X6S,CH710KMEA01':;

SECTION_NUMBER 1
 '@T6G_MB_LIB.T6G(SCH_1):PAGE422_I50@PURE_QUANTA.Q_CAP(CHIPS)':
 C_PATH='@t6g_mb_lib.t6g(sch_1):page422_i50@pure_quanta.q_cap(chips)',
 P_PATH='@t6g_mb_lib.t6g(sch_1):page301_i50@pure_quanta.q_cap(chips)',
 PATH='I50',
 DRAWING='@T6G_MB_LIB.T6G(SCH_1):PAGE422',
 TOLERANCE='20%',
 MATERIAL='X6S',
 PHYS_PAGE='301',
 XY='(-3100,4475)',
 ROT='0',
 VER='1',
 PACK_TYPE='C0805',
 LOCATION='C798',
 CDS_LIB='pure_quanta',
 CDS_PART_NAME='Q_CAP_C0805-100UF,4V,20%,X6S,CH710KMEA01',
 VOLTAGE='4V',
 PART_NUMBER='CH710KMEA01',
 VALUE='100UF',
 PRIM_FILE='./archive_libs/logical/q_cap/chips/chips.prt';

PART_NAME
 C799 'Q_CAP_C0402-22UF,4V,20%,X6S,CH622KMEB02':;

SECTION_NUMBER 1
 '@T6G_MB_LIB.T6G(SCH_1):PAGE422_I65@PURE_QUANTA.Q_CAP(CHIPS)':
 C_PATH='@t6g_mb_lib.t6g(sch_1):page422_i65@pure_quanta.q_cap(chips)',
 P_PATH='@t6g_mb_lib.t6g(sch_1):page301_i65@pure_quanta.q_cap(chips)',
 PATH='I65',
 DRAWING='@T6G_MB_LIB.T6G(SCH_1):PAGE422',
 TOLERANCE='20%',
 MATERIAL='X6S',
 PHYS_PAGE='301',
 XY='(-1725,4475)',
 ROT='0',
 VER='1',
 PACK_TYPE='C0402',
 LOCATION='C799',
 CDS_LIB='pure_quanta',
 CDS_PART_NAME='Q_CAP_C0402-22UF,4V,20%,X6S,CH622KMEB02',
 VOLTAGE='4V',
 PART_NUMBER='CH622KMEB02',
 VALUE='22UF',
 PRIM_FILE='./archive_libs/logical/q_cap/chips/chips.prt';

PART_NAME
 C800 'Q_CAP_C0201-0.1UF,10V,10%,X7S,CH4102K6E00':;

SECTION_NUMBER 1
 '@T6G_MB_LIB.T6G(SCH_1):PAGE422_I42@PURE_QUANTA.Q_CAP(CHIPS)':
 C_PATH='@t6g_mb_lib.t6g(sch_1):page422_i42@pure_quanta.q_cap(chips)',
 P_PATH='@t6g_mb_lib.t6g(sch_1):page301_i42@pure_quanta.q_cap(chips)',
 PATH='I42',
 DRAWING='@T6G_MB_LIB.T6G(SCH_1):PAGE422',
 TOLERANCE='10%',
 MATERIAL='X7S',
 PHYS_PAGE='301',
 XY='(-2025,2525)',
 ROT='0',
 VER='1',
 PACK_TYPE='C0201',
 LOCATION='C800',
 CDS_LIB='pure_quanta',
 CDS_PART_NAME='Q_CAP_C0201-0.1UF,10V,10%,X7S,CH4102K6E00',
 VOLTAGE='10V',
 PART_NUMBER='CH4102K6E00',
 VALUE='0.1UF',
 PRIM_FILE='./archive_libs/logical/q_cap/chips/chips.prt';

PART_NAME
 C801 'Q_CAP_C0805-100UF,4V,20%,X6S,CH710KMEA01':;

SECTION_NUMBER 1
 '@T6G_MB_LIB.T6G(SCH_1):PAGE422_I77@PURE_QUANTA.Q_CAP(CHIPS)':
 C_PATH='@t6g_mb_lib.t6g(sch_1):page422_i77@pure_quanta.q_cap(chips)',
 P_PATH='@t6g_mb_lib.t6g(sch_1):page301_i77@pure_quanta.q_cap(chips)',
 PATH='I77',
 DRAWING='@T6G_MB_LIB.T6G(SCH_1):PAGE422',
 TOLERANCE='20%',
 MATERIAL='X6S',
 PHYS_PAGE='301',
 XY='(-3275,5750)',
 ROT='0',
 VER='1',
 PACK_TYPE='C0805',
 LOCATION='C801',
 CDS_LIB='pure_quanta',
 CDS_PART_NAME='Q_CAP_C0805-100UF,4V,20%,X6S,CH710KMEA01',
 VOLTAGE='4V',
 PART_NUMBER='CH710KMEA01',
 VALUE='100UF',
 PRIM_FILE='./archive_libs/logical/q_cap/chips/chips.prt';

PART_NAME
 C802 'Q_CAP_C0805-100UF,4V,20%,X6S,CH710KMEA01':;

SECTION_NUMBER 1
 '@T6G_MB_LIB.T6G(SCH_1):PAGE422_I51@PURE_QUANTA.Q_CAP(CHIPS)':
 C_PATH='@t6g_mb_lib.t6g(sch_1):page422_i51@pure_quanta.q_cap(chips)',
 P_PATH='@t6g_mb_lib.t6g(sch_1):page301_i51@pure_quanta.q_cap(chips)',
 PATH='I51',
 DRAWING='@T6G_MB_LIB.T6G(SCH_1):PAGE422',
 TOLERANCE='20%',
 MATERIAL='X6S',
 PHYS_PAGE='301',
 XY='(-2875,4475)',
 ROT='0',
 VER='1',
 PACK_TYPE='C0805',
 LOCATION='C802',
 CDS_LIB='pure_quanta',
 CDS_PART_NAME='Q_CAP_C0805-100UF,4V,20%,X6S,CH710KMEA01',
 VOLTAGE='4V',
 PART_NUMBER='CH710KMEA01',
 VALUE='100UF',
 PRIM_FILE='./archive_libs/logical/q_cap/chips/chips.prt';

PART_NAME
 C803 'Q_CAP_C0402-10UF,6.3V,20%,X6S,CH6101MEB01':;

SECTION_NUMBER 1
 '@T6G_MB_LIB.T6G(SCH_1):PAGE422_I87@PURE_QUANTA.Q_CAP(CHIPS)':
 C_PATH='@t6g_mb_lib.t6g(sch_1):page422_i87@pure_quanta.q_cap(chips)',
 P_PATH='@t6g_mb_lib.t6g(sch_1):page301_i87@pure_quanta.q_cap(chips)',
 PATH='I87',
 DRAWING='@T6G_MB_LIB.T6G(SCH_1):PAGE422',
 TOLERANCE='20%',
 MATERIAL='X6S',
 PHYS_PAGE='301',
 XY='(-3100,3850)',
 ROT='0',
 VER='1',
 PACK_TYPE='C0402',
 LOCATION='C803',
 CDS_LIB='pure_quanta',
 CDS_PART_NAME='Q_CAP_C0402-10UF,6.3V,20%,X6S,CH6101MEB01',
 VOLTAGE='6.3V',
 PART_NUMBER='CH6101MEB01',
 VALUE='10UF',
 PRIM_FILE='./archive_libs/logical/q_cap/chips/chips.prt';

PART_NAME
 C804 'Q_CAP_C0201-0.1UF,10V,10%,X7S,CH4102K6E00':;

SECTION_NUMBER 1
 '@T6G_MB_LIB.T6G(SCH_1):PAGE422_I68@PURE_QUANTA.Q_CAP(CHIPS)':
 C_PATH='@t6g_mb_lib.t6g(sch_1):page422_i68@pure_quanta.q_cap(chips)',
 P_PATH='@t6g_mb_lib.t6g(sch_1):page301_i68@pure_quanta.q_cap(chips)',
 PATH='I68',
 DRAWING='@T6G_MB_LIB.T6G(SCH_1):PAGE422',
 TOLERANCE='10%',
 MATERIAL='X7S',
 PHYS_PAGE='301',
 XY='(-1475,2525)',
 ROT='0',
 VER='1',
 PACK_TYPE='C0201',
 LOCATION='C804',
 CDS_LIB='pure_quanta',
 CDS_PART_NAME='Q_CAP_C0201-0.1UF,10V,10%,X7S,CH4102K6E00',
 VOLTAGE='10V',
 PART_NUMBER='CH4102K6E00',
 VALUE='0.1UF',
 PRIM_FILE='./archive_libs/logical/q_cap/chips/chips.prt';

PART_NAME
 C805 'Q_CAP_C0402-22UF,4V,20%,X6S,CH622KMEB02':;

SECTION_NUMBER 1
 '@T6G_MB_LIB.T6G(SCH_1):PAGE422_I78@PURE_QUANTA.Q_CAP(CHIPS)':
 C_PATH='@t6g_mb_lib.t6g(sch_1):page422_i78@pure_quanta.q_cap(chips)',
 P_PATH='@t6g_mb_lib.t6g(sch_1):page301_i78@pure_quanta.q_cap(chips)',
 PATH='I78',
 DRAWING='@T6G_MB_LIB.T6G(SCH_1):PAGE422',
 TOLERANCE='20%',
 MATERIAL='X6S',
 PHYS_PAGE='301',
 XY='(-3000,5750)',
 ROT='0',
 VER='1',
 PACK_TYPE='C0402',
 LOCATION='C805',
 CDS_LIB='pure_quanta',
 CDS_PART_NAME='Q_CAP_C0402-22UF,4V,20%,X6S,CH622KMEB02',
 VOLTAGE='4V',
 PART_NUMBER='CH622KMEB02',
 VALUE='22UF',
 PRIM_FILE='./archive_libs/logical/q_cap/chips/chips.prt';

PART_NAME
 C806 'Q_CAP_DIFFBUS_C0201-DIFF BUS_0.22UF,6.3V,20%,X6S,SA':;

SECTION_NUMBER 1
 '@T6G_MB_LIB.T6G(SCH_1):PAGE353_I377@PURE_QUANTA.Q_CAP_DIFFBUS(CHIPS)':
 C_PATH='@t6g_mb_lib.t6g(sch_1):page353_i377@pure_quanta.q_cap_diffbus(chips)',
 P_PATH='@t6g_mb_lib.t6g(sch_1):page65_i377@pure_quanta.q_cap_diffbus(chips)',
 PATH='I377',
 DRAWING='@T6G_MB_LIB.T6G(SCH_1):PAGE353',
 PIN_NAMES_ROTATE='TRUE',
 TOLERANCE='20%',
 MATERIAL='X6S',
 PHYS_PAGE='65',
 XY='(3575,3575)',
 ROT='2',
 VER='2',
 PACK_TYPE='C0201',
 LOCATION='C806',
 CDS_LIB='pure_quanta',
 CDS_PART_NAME='Q_CAP_DIFFBUS_C0201-DIFF BUS_0.22UF,6.3V,20%,X6S,SA',
 VOLTAGE='6.3V',
 PART_NUMBER='SP_CH4221MEE01',
 VALUE='DIFF BUS_0.22UF',
 PRIM_FILE='./archive_libs/logical/q_cap_diffbus/chips/chips.prt';

PART_NAME
 C807 'Q_CAP_DIFFBUS_C0201-DIFF BUS_0.22UF,6.3V,20%,X6S,SA':;

SECTION_NUMBER 1
 '@T6G_MB_LIB.T6G(SCH_1):PAGE353_I378@PURE_QUANTA.Q_CAP_DIFFBUS(CHIPS)':
 C_PATH='@t6g_mb_lib.t6g(sch_1):page353_i378@pure_quanta.q_cap_diffbus(chips)',
 P_PATH='@t6g_mb_lib.t6g(sch_1):page65_i378@pure_quanta.q_cap_diffbus(chips)',
 PATH='I378',
 DRAWING='@T6G_MB_LIB.T6G(SCH_1):PAGE353',
 PIN_NAMES_ROTATE='TRUE',
 TOLERANCE='20%',
 MATERIAL='X6S',
 PHYS_PAGE='65',
 XY='(3575,3525)',
 ROT='2',
 VER='2',
 PACK_TYPE='C0201',
 LOCATION='C807',
 CDS_LIB='pure_quanta',
 CDS_PART_NAME='Q_CAP_DIFFBUS_C0201-DIFF BUS_0.22UF,6.3V,20%,X6S,SA',
 VOLTAGE='6.3V',
 PART_NUMBER='SP_CH4221MEE01',
 VALUE='DIFF BUS_0.22UF',
 PRIM_FILE='./archive_libs/logical/q_cap_diffbus/chips/chips.prt';

PART_NAME
 C808 'Q_CAP_DIFFBUS_C0201-DIFF BUS_0.22UF,6.3V,20%,X6S,SA':;

SECTION_NUMBER 1
 '@T6G_MB_LIB.T6G(SCH_1):PAGE353_I376@PURE_QUANTA.Q_CAP_DIFFBUS(CHIPS)':
 C_PATH='@t6g_mb_lib.t6g(sch_1):page353_i376@pure_quanta.q_cap_diffbus(chips)',
 P_PATH='@t6g_mb_lib.t6g(sch_1):page65_i376@pure_quanta.q_cap_diffbus(chips)',
 PATH='I376',
 DRAWING='@T6G_MB_LIB.T6G(SCH_1):PAGE353',
 PIN_NAMES_ROTATE='TRUE',
 TOLERANCE='20%',
 MATERIAL='X6S',
 PHYS_PAGE='65',
 XY='(3575,3375)',
 ROT='2',
 VER='2',
 PACK_TYPE='C0201',
 LOCATION='C808',
 CDS_LIB='pure_quanta',
 CDS_PART_NAME='Q_CAP_DIFFBUS_C0201-DIFF BUS_0.22UF,6.3V,20%,X6S,SA',
 VOLTAGE='6.3V',
 PART_NUMBER='SP_CH4221MEE01',
 VALUE='DIFF BUS_0.22UF',
 PRIM_FILE='./archive_libs/logical/q_cap_diffbus/chips/chips.prt';

PART_NAME
 C809 'Q_CAP_DIFFBUS_C0201-DIFF BUS_0.22UF,6.3V,20%,X6S,SA':;

SECTION_NUMBER 1
 '@T6G_MB_LIB.T6G(SCH_1):PAGE353_I375@PURE_QUANTA.Q_CAP_DIFFBUS(CHIPS)':
 C_PATH='@t6g_mb_lib.t6g(sch_1):page353_i375@pure_quanta.q_cap_diffbus(chips)',
 P_PATH='@t6g_mb_lib.t6g(sch_1):page65_i375@pure_quanta.q_cap_diffbus(chips)',
 PATH='I375',
 DRAWING='@T6G_MB_LIB.T6G(SCH_1):PAGE353',
 PIN_NAMES_ROTATE='TRUE',
 TOLERANCE='20%',
 MATERIAL='X6S',
 PHYS_PAGE='65',
 XY='(3575,3325)',
 ROT='2',
 VER='2',
 PACK_TYPE='C0201',
 LOCATION='C809',
 CDS_LIB='pure_quanta',
 CDS_PART_NAME='Q_CAP_DIFFBUS_C0201-DIFF BUS_0.22UF,6.3V,20%,X6S,SA',
 VOLTAGE='6.3V',
 PART_NUMBER='SP_CH4221MEE01',
 VALUE='DIFF BUS_0.22UF',
 PRIM_FILE='./archive_libs/logical/q_cap_diffbus/chips/chips.prt';

PART_NAME
 C810 'Q_CAP_DIFFBUS_C0201-DIFF BUS_0.22UF,6.3V,20%,X6S,SA':;

SECTION_NUMBER 1
 '@T6G_MB_LIB.T6G(SCH_1):PAGE353_I374@PURE_QUANTA.Q_CAP_DIFFBUS(CHIPS)':
 C_PATH='@t6g_mb_lib.t6g(sch_1):page353_i374@pure_quanta.q_cap_diffbus(chips)',
 P_PATH='@t6g_mb_lib.t6g(sch_1):page65_i374@pure_quanta.q_cap_diffbus(chips)',
 PATH='I374',
 DRAWING='@T6G_MB_LIB.T6G(SCH_1):PAGE353',
 PIN_NAMES_ROTATE='TRUE',
 TOLERANCE='20%',
 MATERIAL='X6S',
 PHYS_PAGE='65',
 XY='(3575,3175)',
 ROT='2',
 VER='2',
 PACK_TYPE='C0201',
 LOCATION='C810',
 CDS_LIB='pure_quanta',
 CDS_PART_NAME='Q_CAP_DIFFBUS_C0201-DIFF BUS_0.22UF,6.3V,20%,X6S,SA',
 VOLTAGE='6.3V',
 PART_NUMBER='SP_CH4221MEE01',
 VALUE='DIFF BUS_0.22UF',
 PRIM_FILE='./archive_libs/logical/q_cap_diffbus/chips/chips.prt';

PART_NAME
 C811 'Q_CAP_DIFFBUS_C0201-DIFF BUS_0.22UF,6.3V,20%,X6S,SA':;

SECTION_NUMBER 1
 '@T6G_MB_LIB.T6G(SCH_1):PAGE353_I373@PURE_QUANTA.Q_CAP_DIFFBUS(CHIPS)':
 C_PATH='@t6g_mb_lib.t6g(sch_1):page353_i373@pure_quanta.q_cap_diffbus(chips)',
 P_PATH='@t6g_mb_lib.t6g(sch_1):page65_i373@pure_quanta.q_cap_diffbus(chips)',
 PATH='I373',
 DRAWING='@T6G_MB_LIB.T6G(SCH_1):PAGE353',
 PIN_NAMES_ROTATE='TRUE',
 TOLERANCE='20%',
 MATERIAL='X6S',
 PHYS_PAGE='65',
 XY='(3575,3125)',
 ROT='2',
 VER='2',
 PACK_TYPE='C0201',
 LOCATION='C811',
 CDS_LIB='pure_quanta',
 CDS_PART_NAME='Q_CAP_DIFFBUS_C0201-DIFF BUS_0.22UF,6.3V,20%,X6S,SA',
 VOLTAGE='6.3V',
 PART_NUMBER='SP_CH4221MEE01',
 VALUE='DIFF BUS_0.22UF',
 PRIM_FILE='./archive_libs/logical/q_cap_diffbus/chips/chips.prt';

PART_NAME
 C812 'Q_CAP_DIFFBUS_C0201-DIFF BUS_0.22UF,6.3V,20%,X6S,SA':;

SECTION_NUMBER 1
 '@T6G_MB_LIB.T6G(SCH_1):PAGE353_I371@PURE_QUANTA.Q_CAP_DIFFBUS(CHIPS)':
 C_PATH='@t6g_mb_lib.t6g(sch_1):page353_i371@pure_quanta.q_cap_diffbus(chips)',
 P_PATH='@t6g_mb_lib.t6g(sch_1):page65_i371@pure_quanta.q_cap_diffbus(chips)',
 PATH='I371',
 DRAWING='@T6G_MB_LIB.T6G(SCH_1):PAGE353',
 PIN_NAMES_ROTATE='TRUE',
 TOLERANCE='20%',
 MATERIAL='X6S',
 PHYS_PAGE='65',
 XY='(3575,2975)',
 ROT='2',
 VER='2',
 PACK_TYPE='C0201',
 LOCATION='C812',
 CDS_LIB='pure_quanta',
 CDS_PART_NAME='Q_CAP_DIFFBUS_C0201-DIFF BUS_0.22UF,6.3V,20%,X6S,SA',
 VOLTAGE='6.3V',
 PART_NUMBER='SP_CH4221MEE01',
 VALUE='DIFF BUS_0.22UF',
 PRIM_FILE='./archive_libs/logical/q_cap_diffbus/chips/chips.prt';

PART_NAME
 C813 'Q_CAP_DIFFBUS_C0201-DIFF BUS_0.22UF,6.3V,20%,X6S,SA':;

SECTION_NUMBER 1
 '@T6G_MB_LIB.T6G(SCH_1):PAGE353_I372@PURE_QUANTA.Q_CAP_DIFFBUS(CHIPS)':
 C_PATH='@t6g_mb_lib.t6g(sch_1):page353_i372@pure_quanta.q_cap_diffbus(chips)',
 P_PATH='@t6g_mb_lib.t6g(sch_1):page65_i372@pure_quanta.q_cap_diffbus(chips)',
 PATH='I372',
 DRAWING='@T6G_MB_LIB.T6G(SCH_1):PAGE353',
 PIN_NAMES_ROTATE='TRUE',
 TOLERANCE='20%',
 MATERIAL='X6S',
 PHYS_PAGE='65',
 XY='(3575,2925)',
 ROT='2',
 VER='2',
 PACK_TYPE='C0201',
 LOCATION='C813',
 CDS_LIB='pure_quanta',
 CDS_PART_NAME='Q_CAP_DIFFBUS_C0201-DIFF BUS_0.22UF,6.3V,20%,X6S,SA',
 VOLTAGE='6.3V',
 PART_NUMBER='SP_CH4221MEE01',
 VALUE='DIFF BUS_0.22UF',
 PRIM_FILE='./archive_libs/logical/q_cap_diffbus/chips/chips.prt';

PART_NAME
 C814 'Q_CAP_DIFFBUS_C0201-DIFF BUS_0.22UF,6.3V,20%,X6S,SA':;

SECTION_NUMBER 1
 '@T6G_MB_LIB.T6G(SCH_1):PAGE353_I370@PURE_QUANTA.Q_CAP_DIFFBUS(CHIPS)':
 C_PATH='@t6g_mb_lib.t6g(sch_1):page353_i370@pure_quanta.q_cap_diffbus(chips)',
 P_PATH='@t6g_mb_lib.t6g(sch_1):page65_i370@pure_quanta.q_cap_diffbus(chips)',
 PATH='I370',
 DRAWING='@T6G_MB_LIB.T6G(SCH_1):PAGE353',
 PIN_NAMES_ROTATE='TRUE',
 TOLERANCE='20%',
 MATERIAL='X6S',
 PHYS_PAGE='65',
 XY='(3575,2775)',
 ROT='2',
 VER='2',
 PACK_TYPE='C0201',
 LOCATION='C814',
 CDS_LIB='pure_quanta',
 CDS_PART_NAME='Q_CAP_DIFFBUS_C0201-DIFF BUS_0.22UF,6.3V,20%,X6S,SA',
 VOLTAGE='6.3V',
 PART_NUMBER='SP_CH4221MEE01',
 VALUE='DIFF BUS_0.22UF',
 PRIM_FILE='./archive_libs/logical/q_cap_diffbus/chips/chips.prt';

PART_NAME
 C815 'Q_CAP_DIFFBUS_C0201-DIFF BUS_0.22UF,6.3V,20%,X6S,SA':;

SECTION_NUMBER 1
 '@T6G_MB_LIB.T6G(SCH_1):PAGE353_I369@PURE_QUANTA.Q_CAP_DIFFBUS(CHIPS)':
 C_PATH='@t6g_mb_lib.t6g(sch_1):page353_i369@pure_quanta.q_cap_diffbus(chips)',
 P_PATH='@t6g_mb_lib.t6g(sch_1):page65_i369@pure_quanta.q_cap_diffbus(chips)',
 PATH='I369',
 DRAWING='@T6G_MB_LIB.T6G(SCH_1):PAGE353',
 PIN_NAMES_ROTATE='TRUE',
 TOLERANCE='20%',
 MATERIAL='X6S',
 PHYS_PAGE='65',
 XY='(3575,2725)',
 ROT='2',
 VER='2',
 PACK_TYPE='C0201',
 LOCATION='C815',
 CDS_LIB='pure_quanta',
 CDS_PART_NAME='Q_CAP_DIFFBUS_C0201-DIFF BUS_0.22UF,6.3V,20%,X6S,SA',
 VOLTAGE='6.3V',
 PART_NUMBER='SP_CH4221MEE01',
 VALUE='DIFF BUS_0.22UF',
 PRIM_FILE='./archive_libs/logical/q_cap_diffbus/chips/chips.prt';

PART_NAME
 C816 'Q_CAP_DIFFBUS_C0201-DIFF BUS_0.22UF,6.3V,20%,X6S,SA':;

SECTION_NUMBER 1
 '@T6G_MB_LIB.T6G(SCH_1):PAGE353_I368@PURE_QUANTA.Q_CAP_DIFFBUS(CHIPS)':
 C_PATH='@t6g_mb_lib.t6g(sch_1):page353_i368@pure_quanta.q_cap_diffbus(chips)',
 P_PATH='@t6g_mb_lib.t6g(sch_1):page65_i368@pure_quanta.q_cap_diffbus(chips)',
 PATH='I368',
 DRAWING='@T6G_MB_LIB.T6G(SCH_1):PAGE353',
 PIN_NAMES_ROTATE='TRUE',
 TOLERANCE='20%',
 MATERIAL='X6S',
 PHYS_PAGE='65',
 XY='(3575,2575)',
 ROT='2',
 VER='2',
 PACK_TYPE='C0201',
 LOCATION='C816',
 CDS_LIB='pure_quanta',
 CDS_PART_NAME='Q_CAP_DIFFBUS_C0201-DIFF BUS_0.22UF,6.3V,20%,X6S,SA',
 VOLTAGE='6.3V',
 PART_NUMBER='SP_CH4221MEE01',
 VALUE='DIFF BUS_0.22UF',
 PRIM_FILE='./archive_libs/logical/q_cap_diffbus/chips/chips.prt';

PART_NAME
 C817 'Q_CAP_DIFFBUS_C0201-DIFF BUS_0.22UF,6.3V,20%,X6S,SA':;

SECTION_NUMBER 1
 '@T6G_MB_LIB.T6G(SCH_1):PAGE353_I367@PURE_QUANTA.Q_CAP_DIFFBUS(CHIPS)':
 C_PATH='@t6g_mb_lib.t6g(sch_1):page353_i367@pure_quanta.q_cap_diffbus(chips)',
 P_PATH='@t6g_mb_lib.t6g(sch_1):page65_i367@pure_quanta.q_cap_diffbus(chips)',
 PATH='I367',
 DRAWING='@T6G_MB_LIB.T6G(SCH_1):PAGE353',
 PIN_NAMES_ROTATE='TRUE',
 TOLERANCE='20%',
 MATERIAL='X6S',
 PHYS_PAGE='65',
 XY='(3575,2525)',
 ROT='2',
 VER='2',
 PACK_TYPE='C0201',
 LOCATION='C817',
 CDS_LIB='pure_quanta',
 CDS_PART_NAME='Q_CAP_DIFFBUS_C0201-DIFF BUS_0.22UF,6.3V,20%,X6S,SA',
 VOLTAGE='6.3V',
 PART_NUMBER='SP_CH4221MEE01',
 VALUE='DIFF BUS_0.22UF',
 PRIM_FILE='./archive_libs/logical/q_cap_diffbus/chips/chips.prt';

PART_NAME
 C818 'Q_CAP_DIFFBUS_C0201-DIFF BUS_0.22UF,6.3V,20%,X6S,SA':;

SECTION_NUMBER 1
 '@T6G_MB_LIB.T6G(SCH_1):PAGE353_I365@PURE_QUANTA.Q_CAP_DIFFBUS(CHIPS)':
 C_PATH='@t6g_mb_lib.t6g(sch_1):page353_i365@pure_quanta.q_cap_diffbus(chips)',
 P_PATH='@t6g_mb_lib.t6g(sch_1):page65_i365@pure_quanta.q_cap_diffbus(chips)',
 PATH='I365',
 DRAWING='@T6G_MB_LIB.T6G(SCH_1):PAGE353',
 PIN_NAMES_ROTATE='TRUE',
 TOLERANCE='20%',
 MATERIAL='X6S',
 PHYS_PAGE='65',
 XY='(3575,2375)',
 ROT='2',
 VER='2',
 PACK_TYPE='C0201',
 LOCATION='C818',
 CDS_LIB='pure_quanta',
 CDS_PART_NAME='Q_CAP_DIFFBUS_C0201-DIFF BUS_0.22UF,6.3V,20%,X6S,SA',
 VOLTAGE='6.3V',
 PART_NUMBER='SP_CH4221MEE01',
 VALUE='DIFF BUS_0.22UF',
 PRIM_FILE='./archive_libs/logical/q_cap_diffbus/chips/chips.prt';

PART_NAME
 C819 'Q_CAP_DIFFBUS_C0201-DIFF BUS_0.22UF,6.3V,20%,X6S,SA':;

SECTION_NUMBER 1
 '@T6G_MB_LIB.T6G(SCH_1):PAGE353_I366@PURE_QUANTA.Q_CAP_DIFFBUS(CHIPS)':
 C_PATH='@t6g_mb_lib.t6g(sch_1):page353_i366@pure_quanta.q_cap_diffbus(chips)',
 P_PATH='@t6g_mb_lib.t6g(sch_1):page65_i366@pure_quanta.q_cap_diffbus(chips)',
 PATH='I366',
 DRAWING='@T6G_MB_LIB.T6G(SCH_1):PAGE353',
 PIN_NAMES_ROTATE='TRUE',
 TOLERANCE='20%',
 MATERIAL='X6S',
 PHYS_PAGE='65',
 XY='(3575,2325)',
 ROT='2',
 VER='2',
 PACK_TYPE='C0201',
 LOCATION='C819',
 CDS_LIB='pure_quanta',
 CDS_PART_NAME='Q_CAP_DIFFBUS_C0201-DIFF BUS_0.22UF,6.3V,20%,X6S,SA',
 VOLTAGE='6.3V',
 PART_NUMBER='SP_CH4221MEE01',
 VALUE='DIFF BUS_0.22UF',
 PRIM_FILE='./archive_libs/logical/q_cap_diffbus/chips/chips.prt';

PART_NAME
 C820 'Q_CAP_DIFFBUS_C0201-DIFF BUS_0.22UF,6.3V,20%,X6S,SA':;

SECTION_NUMBER 1
 '@T6G_MB_LIB.T6G(SCH_1):PAGE353_I363@PURE_QUANTA.Q_CAP_DIFFBUS(CHIPS)':
 C_PATH='@t6g_mb_lib.t6g(sch_1):page353_i363@pure_quanta.q_cap_diffbus(chips)',
 P_PATH='@t6g_mb_lib.t6g(sch_1):page65_i363@pure_quanta.q_cap_diffbus(chips)',
 PATH='I363',
 DRAWING='@T6G_MB_LIB.T6G(SCH_1):PAGE353',
 PIN_NAMES_ROTATE='TRUE',
 TOLERANCE='20%',
 MATERIAL='X6S',
 PHYS_PAGE='65',
 XY='(3575,2175)',
 ROT='2',
 VER='2',
 PACK_TYPE='C0201',
 LOCATION='C820',
 CDS_LIB='pure_quanta',
 CDS_PART_NAME='Q_CAP_DIFFBUS_C0201-DIFF BUS_0.22UF,6.3V,20%,X6S,SA',
 VOLTAGE='6.3V',
 PART_NUMBER='SP_CH4221MEE01',
 VALUE='DIFF BUS_0.22UF',
 PRIM_FILE='./archive_libs/logical/q_cap_diffbus/chips/chips.prt';

PART_NAME
 C821 'Q_CAP_DIFFBUS_C0201-DIFF BUS_0.22UF,6.3V,20%,X6S,SA':;

SECTION_NUMBER 1
 '@T6G_MB_LIB.T6G(SCH_1):PAGE353_I364@PURE_QUANTA.Q_CAP_DIFFBUS(CHIPS)':
 C_PATH='@t6g_mb_lib.t6g(sch_1):page353_i364@pure_quanta.q_cap_diffbus(chips)',
 P_PATH='@t6g_mb_lib.t6g(sch_1):page65_i364@pure_quanta.q_cap_diffbus(chips)',
 PATH='I364',
 DRAWING='@T6G_MB_LIB.T6G(SCH_1):PAGE353',
 PIN_NAMES_ROTATE='TRUE',
 TOLERANCE='20%',
 MATERIAL='X6S',
 PHYS_PAGE='65',
 XY='(3575,2125)',
 ROT='2',
 VER='2',
 PACK_TYPE='C0201',
 LOCATION='C821',
 CDS_LIB='pure_quanta',
 CDS_PART_NAME='Q_CAP_DIFFBUS_C0201-DIFF BUS_0.22UF,6.3V,20%,X6S,SA',
 VOLTAGE='6.3V',
 PART_NUMBER='SP_CH4221MEE01',
 VALUE='DIFF BUS_0.22UF',
 PRIM_FILE='./archive_libs/logical/q_cap_diffbus/chips/chips.prt';

PART_NAME
 C822 'Q_CAP_DIFFBUS_C0201-DIFF BUS_0.22UF,6.3V,20%,X6S,SA':;

SECTION_NUMBER 1
 '@T6G_MB_LIB.T6G(SCH_1):PAGE353_I345@PURE_QUANTA.Q_CAP_DIFFBUS(CHIPS)':
 C_PATH='@t6g_mb_lib.t6g(sch_1):page353_i345@pure_quanta.q_cap_diffbus(chips)',
 P_PATH='@t6g_mb_lib.t6g(sch_1):page65_i345@pure_quanta.q_cap_diffbus(chips)',
 PATH='I345',
 DRAWING='@T6G_MB_LIB.T6G(SCH_1):PAGE353',
 PIN_NAMES_ROTATE='TRUE',
 TOLERANCE='20%',
 MATERIAL='X6S',
 PHYS_PAGE='65',
 XY='(3575,1600)',
 ROT='2',
 VER='2',
 PACK_TYPE='C0201',
 LOCATION='C822',
 CDS_LIB='pure_quanta',
 CDS_PART_NAME='Q_CAP_DIFFBUS_C0201-DIFF BUS_0.22UF,6.3V,20%,X6S,SA',
 VOLTAGE='6.3V',
 PART_NUMBER='SP_CH4221MEE01',
 VALUE='DIFF BUS_0.22UF',
 PRIM_FILE='./archive_libs/logical/q_cap_diffbus/chips/chips.prt';

PART_NAME
 C823 'Q_CAP_DIFFBUS_C0201-DIFF BUS_0.22UF,6.3V,20%,X6S,SA':;

SECTION_NUMBER 1
 '@T6G_MB_LIB.T6G(SCH_1):PAGE353_I346@PURE_QUANTA.Q_CAP_DIFFBUS(CHIPS)':
 C_PATH='@t6g_mb_lib.t6g(sch_1):page353_i346@pure_quanta.q_cap_diffbus(chips)',
 P_PATH='@t6g_mb_lib.t6g(sch_1):page65_i346@pure_quanta.q_cap_diffbus(chips)',
 PATH='I346',
 DRAWING='@T6G_MB_LIB.T6G(SCH_1):PAGE353',
 PIN_NAMES_ROTATE='TRUE',
 TOLERANCE='20%',
 MATERIAL='X6S',
 PHYS_PAGE='65',
 XY='(3575,1550)',
 ROT='2',
 VER='2',
 PACK_TYPE='C0201',
 LOCATION='C823',
 CDS_LIB='pure_quanta',
 CDS_PART_NAME='Q_CAP_DIFFBUS_C0201-DIFF BUS_0.22UF,6.3V,20%,X6S,SA',
 VOLTAGE='6.3V',
 PART_NUMBER='SP_CH4221MEE01',
 VALUE='DIFF BUS_0.22UF',
 PRIM_FILE='./archive_libs/logical/q_cap_diffbus/chips/chips.prt';

PART_NAME
 C824 'Q_CAP_DIFFBUS_C0201-DIFF BUS_0.22UF,6.3V,20%,X6S,SA':;

SECTION_NUMBER 1
 '@T6G_MB_LIB.T6G(SCH_1):PAGE353_I416@PURE_QUANTA.Q_CAP_DIFFBUS(CHIPS)':
 C_PATH='@t6g_mb_lib.t6g(sch_1):page353_i416@pure_quanta.q_cap_diffbus(chips)',
 P_PATH='@t6g_mb_lib.t6g(sch_1):page65_i416@pure_quanta.q_cap_diffbus(chips)',
 PATH='I416',
 DRAWING='@T6G_MB_LIB.T6G(SCH_1):PAGE353',
 PIN_NAMES_ROTATE='TRUE',
 TOLERANCE='20%',
 MATERIAL='X6S',
 PHYS_PAGE='65',
 XY='(3575,1400)',
 ROT='2',
 VER='2',
 PACK_TYPE='C0201',
 LOCATION='C824',
 CDS_LIB='pure_quanta',
 CDS_PART_NAME='Q_CAP_DIFFBUS_C0201-DIFF BUS_0.22UF,6.3V,20%,X6S,SA',
 VOLTAGE='6.3V',
 PART_NUMBER='SP_CH4221MEE01',
 VALUE='DIFF BUS_0.22UF',
 PRIM_FILE='./archive_libs/logical/q_cap_diffbus/chips/chips.prt';

PART_NAME
 C825 'Q_CAP_DIFFBUS_C0201-DIFF BUS_0.22UF,6.3V,20%,X6S,SA':;

SECTION_NUMBER 1
 '@T6G_MB_LIB.T6G(SCH_1):PAGE353_I415@PURE_QUANTA.Q_CAP_DIFFBUS(CHIPS)':
 C_PATH='@t6g_mb_lib.t6g(sch_1):page353_i415@pure_quanta.q_cap_diffbus(chips)',
 P_PATH='@t6g_mb_lib.t6g(sch_1):page65_i415@pure_quanta.q_cap_diffbus(chips)',
 PATH='I415',
 DRAWING='@T6G_MB_LIB.T6G(SCH_1):PAGE353',
 PIN_NAMES_ROTATE='TRUE',
 TOLERANCE='20%',
 MATERIAL='X6S',
 PHYS_PAGE='65',
 XY='(3575,1350)',
 ROT='2',
 VER='2',
 PACK_TYPE='C0201',
 LOCATION='C825',
 CDS_LIB='pure_quanta',
 CDS_PART_NAME='Q_CAP_DIFFBUS_C0201-DIFF BUS_0.22UF,6.3V,20%,X6S,SA',
 VOLTAGE='6.3V',
 PART_NUMBER='SP_CH4221MEE01',
 VALUE='DIFF BUS_0.22UF',
 PRIM_FILE='./archive_libs/logical/q_cap_diffbus/chips/chips.prt';

PART_NAME
 C826 'Q_CAP_DIFFBUS_C0201-DIFF BUS_0.22UF,6.3V,20%,X6S,SA':;

SECTION_NUMBER 1
 '@T6G_MB_LIB.T6G(SCH_1):PAGE353_I344@PURE_QUANTA.Q_CAP_DIFFBUS(CHIPS)':
 C_PATH='@t6g_mb_lib.t6g(sch_1):page353_i344@pure_quanta.q_cap_diffbus(chips)',
 P_PATH='@t6g_mb_lib.t6g(sch_1):page65_i344@pure_quanta.q_cap_diffbus(chips)',
 PATH='I344',
 DRAWING='@T6G_MB_LIB.T6G(SCH_1):PAGE353',
 PIN_NAMES_ROTATE='TRUE',
 TOLERANCE='20%',
 MATERIAL='X6S',
 PHYS_PAGE='65',
 XY='(3575,1200)',
 ROT='2',
 VER='2',
 PACK_TYPE='C0201',
 LOCATION='C826',
 CDS_LIB='pure_quanta',
 CDS_PART_NAME='Q_CAP_DIFFBUS_C0201-DIFF BUS_0.22UF,6.3V,20%,X6S,SA',
 VOLTAGE='6.3V',
 PART_NUMBER='SP_CH4221MEE01',
 VALUE='DIFF BUS_0.22UF',
 PRIM_FILE='./archive_libs/logical/q_cap_diffbus/chips/chips.prt';

PART_NAME
 C827 'Q_CAP_DIFFBUS_C0201-DIFF BUS_0.22UF,6.3V,20%,X6S,SA':;

SECTION_NUMBER 1
 '@T6G_MB_LIB.T6G(SCH_1):PAGE353_I343@PURE_QUANTA.Q_CAP_DIFFBUS(CHIPS)':
 C_PATH='@t6g_mb_lib.t6g(sch_1):page353_i343@pure_quanta.q_cap_diffbus(chips)',
 P_PATH='@t6g_mb_lib.t6g(sch_1):page65_i343@pure_quanta.q_cap_diffbus(chips)',
 PATH='I343',
 DRAWING='@T6G_MB_LIB.T6G(SCH_1):PAGE353',
 PIN_NAMES_ROTATE='TRUE',
 TOLERANCE='20%',
 MATERIAL='X6S',
 PHYS_PAGE='65',
 XY='(3575,1150)',
 ROT='2',
 VER='2',
 PACK_TYPE='C0201',
 LOCATION='C827',
 CDS_LIB='pure_quanta',
 CDS_PART_NAME='Q_CAP_DIFFBUS_C0201-DIFF BUS_0.22UF,6.3V,20%,X6S,SA',
 VOLTAGE='6.3V',
 PART_NUMBER='SP_CH4221MEE01',
 VALUE='DIFF BUS_0.22UF',
 PRIM_FILE='./archive_libs/logical/q_cap_diffbus/chips/chips.prt';

PART_NAME
 C828 'Q_CAP_DIFFBUS_C0201-DIFF BUS_0.22UF,6.3V,20%,X6S,SA':;

SECTION_NUMBER 1
 '@T6G_MB_LIB.T6G(SCH_1):PAGE353_I340@PURE_QUANTA.Q_CAP_DIFFBUS(CHIPS)':
 C_PATH='@t6g_mb_lib.t6g(sch_1):page353_i340@pure_quanta.q_cap_diffbus(chips)',
 P_PATH='@t6g_mb_lib.t6g(sch_1):page65_i340@pure_quanta.q_cap_diffbus(chips)',
 PATH='I340',
 DRAWING='@T6G_MB_LIB.T6G(SCH_1):PAGE353',
 PIN_NAMES_ROTATE='TRUE',
 TOLERANCE='20%',
 MATERIAL='X6S',
 PHYS_PAGE='65',
 XY='(3575,1000)',
 ROT='2',
 VER='2',
 PACK_TYPE='C0201',
 LOCATION='C828',
 CDS_LIB='pure_quanta',
 CDS_PART_NAME='Q_CAP_DIFFBUS_C0201-DIFF BUS_0.22UF,6.3V,20%,X6S,SA',
 VOLTAGE='6.3V',
 PART_NUMBER='SP_CH4221MEE01',
 VALUE='DIFF BUS_0.22UF',
 PRIM_FILE='./archive_libs/logical/q_cap_diffbus/chips/chips.prt';

PART_NAME
 C829 'Q_CAP_DIFFBUS_C0201-DIFF BUS_0.22UF,6.3V,20%,X6S,SA':;

SECTION_NUMBER 1
 '@T6G_MB_LIB.T6G(SCH_1):PAGE353_I342@PURE_QUANTA.Q_CAP_DIFFBUS(CHIPS)':
 C_PATH='@t6g_mb_lib.t6g(sch_1):page353_i342@pure_quanta.q_cap_diffbus(chips)',
 P_PATH='@t6g_mb_lib.t6g(sch_1):page65_i342@pure_quanta.q_cap_diffbus(chips)',
 PATH='I342',
 DRAWING='@T6G_MB_LIB.T6G(SCH_1):PAGE353',
 PIN_NAMES_ROTATE='TRUE',
 TOLERANCE='20%',
 MATERIAL='X6S',
 PHYS_PAGE='65',
 XY='(3575,950)',
 ROT='2',
 VER='2',
 PACK_TYPE='C0201',
 LOCATION='C829',
 CDS_LIB='pure_quanta',
 CDS_PART_NAME='Q_CAP_DIFFBUS_C0201-DIFF BUS_0.22UF,6.3V,20%,X6S,SA',
 VOLTAGE='6.3V',
 PART_NUMBER='SP_CH4221MEE01',
 VALUE='DIFF BUS_0.22UF',
 PRIM_FILE='./archive_libs/logical/q_cap_diffbus/chips/chips.prt';

PART_NAME
 C830 'Q_CAP_DIFFBUS_C0201-DIFF BUS_0.22UF,6.3V,20%,X6S,SA':;

SECTION_NUMBER 1
 '@T6G_MB_LIB.T6G(SCH_1):PAGE353_I341@PURE_QUANTA.Q_CAP_DIFFBUS(CHIPS)':
 C_PATH='@t6g_mb_lib.t6g(sch_1):page353_i341@pure_quanta.q_cap_diffbus(chips)',
 P_PATH='@t6g_mb_lib.t6g(sch_1):page65_i341@pure_quanta.q_cap_diffbus(chips)',
 PATH='I341',
 DRAWING='@T6G_MB_LIB.T6G(SCH_1):PAGE353',
 PIN_NAMES_ROTATE='TRUE',
 TOLERANCE='20%',
 MATERIAL='X6S',
 PHYS_PAGE='65',
 XY='(3575,800)',
 ROT='2',
 VER='2',
 PACK_TYPE='C0201',
 LOCATION='C830',
 CDS_LIB='pure_quanta',
 CDS_PART_NAME='Q_CAP_DIFFBUS_C0201-DIFF BUS_0.22UF,6.3V,20%,X6S,SA',
 VOLTAGE='6.3V',
 PART_NUMBER='SP_CH4221MEE01',
 VALUE='DIFF BUS_0.22UF',
 PRIM_FILE='./archive_libs/logical/q_cap_diffbus/chips/chips.prt';

PART_NAME
 C831 'Q_CAP_DIFFBUS_C0201-DIFF BUS_0.22UF,6.3V,20%,X6S,SA':;

SECTION_NUMBER 1
 '@T6G_MB_LIB.T6G(SCH_1):PAGE353_I337@PURE_QUANTA.Q_CAP_DIFFBUS(CHIPS)':
 C_PATH='@t6g_mb_lib.t6g(sch_1):page353_i337@pure_quanta.q_cap_diffbus(chips)',
 P_PATH='@t6g_mb_lib.t6g(sch_1):page65_i337@pure_quanta.q_cap_diffbus(chips)',
 PATH='I337',
 DRAWING='@T6G_MB_LIB.T6G(SCH_1):PAGE353',
 PIN_NAMES_ROTATE='TRUE',
 TOLERANCE='20%',
 MATERIAL='X6S',
 PHYS_PAGE='65',
 XY='(3575,750)',
 ROT='2',
 VER='2',
 PACK_TYPE='C0201',
 LOCATION='C831',
 CDS_LIB='pure_quanta',
 CDS_PART_NAME='Q_CAP_DIFFBUS_C0201-DIFF BUS_0.22UF,6.3V,20%,X6S,SA',
 VOLTAGE='6.3V',
 PART_NUMBER='SP_CH4221MEE01',
 VALUE='DIFF BUS_0.22UF',
 PRIM_FILE='./archive_libs/logical/q_cap_diffbus/chips/chips.prt';

PART_NAME
 C832 'Q_CAP_DIFFBUS_C0201-DIFF BUS_0.22UF,6.3V,20%,X6S,SA':;

SECTION_NUMBER 1
 '@T6G_MB_LIB.T6G(SCH_1):PAGE353_I338@PURE_QUANTA.Q_CAP_DIFFBUS(CHIPS)':
 C_PATH='@t6g_mb_lib.t6g(sch_1):page353_i338@pure_quanta.q_cap_diffbus(chips)',
 P_PATH='@t6g_mb_lib.t6g(sch_1):page65_i338@pure_quanta.q_cap_diffbus(chips)',
 PATH='I338',
 DRAWING='@T6G_MB_LIB.T6G(SCH_1):PAGE353',
 PIN_NAMES_ROTATE='TRUE',
 TOLERANCE='20%',
 MATERIAL='X6S',
 PHYS_PAGE='65',
 XY='(3575,600)',
 ROT='2',
 VER='2',
 PACK_TYPE='C0201',
 LOCATION='C832',
 CDS_LIB='pure_quanta',
 CDS_PART_NAME='Q_CAP_DIFFBUS_C0201-DIFF BUS_0.22UF,6.3V,20%,X6S,SA',
 VOLTAGE='6.3V',
 PART_NUMBER='SP_CH4221MEE01',
 VALUE='DIFF BUS_0.22UF',
 PRIM_FILE='./archive_libs/logical/q_cap_diffbus/chips/chips.prt';

PART_NAME
 C833 'Q_CAP_DIFFBUS_C0201-DIFF BUS_0.22UF,6.3V,20%,X6S,SA':;

SECTION_NUMBER 1
 '@T6G_MB_LIB.T6G(SCH_1):PAGE353_I339@PURE_QUANTA.Q_CAP_DIFFBUS(CHIPS)':
 C_PATH='@t6g_mb_lib.t6g(sch_1):page353_i339@pure_quanta.q_cap_diffbus(chips)',
 P_PATH='@t6g_mb_lib.t6g(sch_1):page65_i339@pure_quanta.q_cap_diffbus(chips)',
 PATH='I339',
 DRAWING='@T6G_MB_LIB.T6G(SCH_1):PAGE353',
 PIN_NAMES_ROTATE='TRUE',
 TOLERANCE='20%',
 MATERIAL='X6S',
 PHYS_PAGE='65',
 XY='(3575,550)',
 ROT='2',
 VER='2',
 PACK_TYPE='C0201',
 LOCATION='C833',
 CDS_LIB='pure_quanta',
 CDS_PART_NAME='Q_CAP_DIFFBUS_C0201-DIFF BUS_0.22UF,6.3V,20%,X6S,SA',
 VOLTAGE='6.3V',
 PART_NUMBER='SP_CH4221MEE01',
 VALUE='DIFF BUS_0.22UF',
 PRIM_FILE='./archive_libs/logical/q_cap_diffbus/chips/chips.prt';

PART_NAME
 C834 'Q_CAP_DIFFBUS_C0201-DIFF BUS_0.22UF,6.3V,20%,X6S,SA':;

SECTION_NUMBER 1
 '@T6G_MB_LIB.T6G(SCH_1):PAGE353_I335@PURE_QUANTA.Q_CAP_DIFFBUS(CHIPS)':
 C_PATH='@t6g_mb_lib.t6g(sch_1):page353_i335@pure_quanta.q_cap_diffbus(chips)',
 P_PATH='@t6g_mb_lib.t6g(sch_1):page65_i335@pure_quanta.q_cap_diffbus(chips)',
 PATH='I335',
 DRAWING='@T6G_MB_LIB.T6G(SCH_1):PAGE353',
 PIN_NAMES_ROTATE='TRUE',
 TOLERANCE='20%',
 MATERIAL='X6S',
 PHYS_PAGE='65',
 XY='(3575,400)',
 ROT='2',
 VER='2',
 PACK_TYPE='C0201',
 LOCATION='C834',
 CDS_LIB='pure_quanta',
 CDS_PART_NAME='Q_CAP_DIFFBUS_C0201-DIFF BUS_0.22UF,6.3V,20%,X6S,SA',
 VOLTAGE='6.3V',
 PART_NUMBER='SP_CH4221MEE01',
 VALUE='DIFF BUS_0.22UF',
 PRIM_FILE='./archive_libs/logical/q_cap_diffbus/chips/chips.prt';

PART_NAME
 C835 'Q_CAP_DIFFBUS_C0201-DIFF BUS_0.22UF,6.3V,20%,X6S,SA':;

SECTION_NUMBER 1
 '@T6G_MB_LIB.T6G(SCH_1):PAGE353_I336@PURE_QUANTA.Q_CAP_DIFFBUS(CHIPS)':
 C_PATH='@t6g_mb_lib.t6g(sch_1):page353_i336@pure_quanta.q_cap_diffbus(chips)',
 P_PATH='@t6g_mb_lib.t6g(sch_1):page65_i336@pure_quanta.q_cap_diffbus(chips)',
 PATH='I336',
 DRAWING='@T6G_MB_LIB.T6G(SCH_1):PAGE353',
 PIN_NAMES_ROTATE='TRUE',
 TOLERANCE='20%',
 MATERIAL='X6S',
 PHYS_PAGE='65',
 XY='(3575,350)',
 ROT='2',
 VER='2',
 PACK_TYPE='C0201',
 LOCATION='C835',
 CDS_LIB='pure_quanta',
 CDS_PART_NAME='Q_CAP_DIFFBUS_C0201-DIFF BUS_0.22UF,6.3V,20%,X6S,SA',
 VOLTAGE='6.3V',
 PART_NUMBER='SP_CH4221MEE01',
 VALUE='DIFF BUS_0.22UF',
 PRIM_FILE='./archive_libs/logical/q_cap_diffbus/chips/chips.prt';

PART_NAME
 C836 'Q_CAP_DIFFBUS_C0201-DIFF BUS_0.22UF,6.3V,20%,X6S,SA':;

SECTION_NUMBER 1
 '@T6G_MB_LIB.T6G(SCH_1):PAGE353_I333@PURE_QUANTA.Q_CAP_DIFFBUS(CHIPS)':
 C_PATH='@t6g_mb_lib.t6g(sch_1):page353_i333@pure_quanta.q_cap_diffbus(chips)',
 P_PATH='@t6g_mb_lib.t6g(sch_1):page65_i333@pure_quanta.q_cap_diffbus(chips)',
 PATH='I333',
 DRAWING='@T6G_MB_LIB.T6G(SCH_1):PAGE353',
 PIN_NAMES_ROTATE='TRUE',
 TOLERANCE='20%',
 MATERIAL='X6S',
 PHYS_PAGE='65',
 XY='(3575,200)',
 ROT='2',
 VER='2',
 PACK_TYPE='C0201',
 LOCATION='C836',
 CDS_LIB='pure_quanta',
 CDS_PART_NAME='Q_CAP_DIFFBUS_C0201-DIFF BUS_0.22UF,6.3V,20%,X6S,SA',
 VOLTAGE='6.3V',
 PART_NUMBER='SP_CH4221MEE01',
 VALUE='DIFF BUS_0.22UF',
 PRIM_FILE='./archive_libs/logical/q_cap_diffbus/chips/chips.prt';

PART_NAME
 C837 'Q_CAP_DIFFBUS_C0201-DIFF BUS_0.22UF,6.3V,20%,X6S,SA':;

SECTION_NUMBER 1
 '@T6G_MB_LIB.T6G(SCH_1):PAGE353_I334@PURE_QUANTA.Q_CAP_DIFFBUS(CHIPS)':
 C_PATH='@t6g_mb_lib.t6g(sch_1):page353_i334@pure_quanta.q_cap_diffbus(chips)',
 P_PATH='@t6g_mb_lib.t6g(sch_1):page65_i334@pure_quanta.q_cap_diffbus(chips)',
 PATH='I334',
 DRAWING='@T6G_MB_LIB.T6G(SCH_1):PAGE353',
 PIN_NAMES_ROTATE='TRUE',
 TOLERANCE='20%',
 MATERIAL='X6S',
 PHYS_PAGE='65',
 XY='(3575,150)',
 ROT='2',
 VER='2',
 PACK_TYPE='C0201',
 LOCATION='C837',
 CDS_LIB='pure_quanta',
 CDS_PART_NAME='Q_CAP_DIFFBUS_C0201-DIFF BUS_0.22UF,6.3V,20%,X6S,SA',
 VOLTAGE='6.3V',
 PART_NUMBER='SP_CH4221MEE01',
 VALUE='DIFF BUS_0.22UF',
 PRIM_FILE='./archive_libs/logical/q_cap_diffbus/chips/chips.prt';

PART_NAME
 C838 'Q_CAP_DIFFBUS_C0201-DIFF BUS_0.22UF,6.3V,20%,X6S,SA':;

SECTION_NUMBER 1
 '@T6G_MB_LIB.T6G(SCH_1):PAGE352_I80@PURE_QUANTA.Q_CAP_DIFFBUS(CHIPS)':
 C_PATH='@t6g_mb_lib.t6g(sch_1):page352_i80@pure_quanta.q_cap_diffbus(chips)',
 P_PATH='@t6g_mb_lib.t6g(sch_1):page64_i80@pure_quanta.q_cap_diffbus(chips)',
 PATH='I80',
 DRAWING='@T6G_MB_LIB.T6G(SCH_1):PAGE352',
 PIN_NAMES_ROTATE='TRUE',
 TOLERANCE='20%',
 MATERIAL='X6S',
 PHYS_PAGE='64',
 XY='(-650,3550)',
 ROT='2',
 VER='2',
 PACK_TYPE='C0201',
 LOCATION='C838',
 CDS_LIB='pure_quanta',
 CDS_PART_NAME='Q_CAP_DIFFBUS_C0201-DIFF BUS_0.22UF,6.3V,20%,X6S,SA',
 VOLTAGE='6.3V',
 PART_NUMBER='SP_CH4221MEE01',
 VALUE='DIFF BUS_0.22UF',
 PRIM_FILE='./archive_libs/logical/q_cap_diffbus/chips/chips.prt';

PART_NAME
 C839 'Q_CAP_DIFFBUS_C0201-DIFF BUS_0.22UF,6.3V,20%,X6S,SA':;

SECTION_NUMBER 1
 '@T6G_MB_LIB.T6G(SCH_1):PAGE352_I81@PURE_QUANTA.Q_CAP_DIFFBUS(CHIPS)':
 C_PATH='@t6g_mb_lib.t6g(sch_1):page352_i81@pure_quanta.q_cap_diffbus(chips)',
 P_PATH='@t6g_mb_lib.t6g(sch_1):page64_i81@pure_quanta.q_cap_diffbus(chips)',
 PATH='I81',
 DRAWING='@T6G_MB_LIB.T6G(SCH_1):PAGE352',
 PIN_NAMES_ROTATE='TRUE',
 TOLERANCE='20%',
 MATERIAL='X6S',
 PHYS_PAGE='64',
 XY='(-650,3500)',
 ROT='2',
 VER='2',
 PACK_TYPE='C0201',
 LOCATION='C839',
 CDS_LIB='pure_quanta',
 CDS_PART_NAME='Q_CAP_DIFFBUS_C0201-DIFF BUS_0.22UF,6.3V,20%,X6S,SA',
 VOLTAGE='6.3V',
 PART_NUMBER='SP_CH4221MEE01',
 VALUE='DIFF BUS_0.22UF',
 PRIM_FILE='./archive_libs/logical/q_cap_diffbus/chips/chips.prt';

PART_NAME
 C840 'Q_CAP_DIFFBUS_C0201-DIFF BUS_0.22UF,6.3V,20%,X6S,SA':;

SECTION_NUMBER 1
 '@T6G_MB_LIB.T6G(SCH_1):PAGE352_I79@PURE_QUANTA.Q_CAP_DIFFBUS(CHIPS)':
 C_PATH='@t6g_mb_lib.t6g(sch_1):page352_i79@pure_quanta.q_cap_diffbus(chips)',
 P_PATH='@t6g_mb_lib.t6g(sch_1):page64_i79@pure_quanta.q_cap_diffbus(chips)',
 PATH='I79',
 DRAWING='@T6G_MB_LIB.T6G(SCH_1):PAGE352',
 PIN_NAMES_ROTATE='TRUE',
 TOLERANCE='20%',
 MATERIAL='X6S',
 PHYS_PAGE='64',
 XY='(-650,3350)',
 ROT='2',
 VER='2',
 PACK_TYPE='C0201',
 LOCATION='C840',
 CDS_LIB='pure_quanta',
 CDS_PART_NAME='Q_CAP_DIFFBUS_C0201-DIFF BUS_0.22UF,6.3V,20%,X6S,SA',
 VOLTAGE='6.3V',
 PART_NUMBER='SP_CH4221MEE01',
 VALUE='DIFF BUS_0.22UF',
 PRIM_FILE='./archive_libs/logical/q_cap_diffbus/chips/chips.prt';

PART_NAME
 C841 'Q_CAP_DIFFBUS_C0201-DIFF BUS_0.22UF,6.3V,20%,X6S,SA':;

SECTION_NUMBER 1
 '@T6G_MB_LIB.T6G(SCH_1):PAGE352_I78@PURE_QUANTA.Q_CAP_DIFFBUS(CHIPS)':
 C_PATH='@t6g_mb_lib.t6g(sch_1):page352_i78@pure_quanta.q_cap_diffbus(chips)',
 P_PATH='@t6g_mb_lib.t6g(sch_1):page64_i78@pure_quanta.q_cap_diffbus(chips)',
 PATH='I78',
 DRAWING='@T6G_MB_LIB.T6G(SCH_1):PAGE352',
 PIN_NAMES_ROTATE='TRUE',
 TOLERANCE='20%',
 MATERIAL='X6S',
 PHYS_PAGE='64',
 XY='(-650,3300)',
 ROT='2',
 VER='2',
 PACK_TYPE='C0201',
 LOCATION='C841',
 CDS_LIB='pure_quanta',
 CDS_PART_NAME='Q_CAP_DIFFBUS_C0201-DIFF BUS_0.22UF,6.3V,20%,X6S,SA',
 VOLTAGE='6.3V',
 PART_NUMBER='SP_CH4221MEE01',
 VALUE='DIFF BUS_0.22UF',
 PRIM_FILE='./archive_libs/logical/q_cap_diffbus/chips/chips.prt';

PART_NAME
 C842 'Q_CAP_DIFFBUS_C0201-DIFF BUS_0.22UF,6.3V,20%,X6S,SA':;

SECTION_NUMBER 1
 '@T6G_MB_LIB.T6G(SCH_1):PAGE352_I76@PURE_QUANTA.Q_CAP_DIFFBUS(CHIPS)':
 C_PATH='@t6g_mb_lib.t6g(sch_1):page352_i76@pure_quanta.q_cap_diffbus(chips)',
 P_PATH='@t6g_mb_lib.t6g(sch_1):page64_i76@pure_quanta.q_cap_diffbus(chips)',
 PATH='I76',
 DRAWING='@T6G_MB_LIB.T6G(SCH_1):PAGE352',
 PIN_NAMES_ROTATE='TRUE',
 TOLERANCE='20%',
 MATERIAL='X6S',
 PHYS_PAGE='64',
 XY='(-650,3150)',
 ROT='2',
 VER='2',
 PACK_TYPE='C0201',
 LOCATION='C842',
 CDS_LIB='pure_quanta',
 CDS_PART_NAME='Q_CAP_DIFFBUS_C0201-DIFF BUS_0.22UF,6.3V,20%,X6S,SA',
 VOLTAGE='6.3V',
 PART_NUMBER='SP_CH4221MEE01',
 VALUE='DIFF BUS_0.22UF',
 PRIM_FILE='./archive_libs/logical/q_cap_diffbus/chips/chips.prt';

PART_NAME
 C843 'Q_CAP_DIFFBUS_C0201-DIFF BUS_0.22UF,6.3V,20%,X6S,SA':;

SECTION_NUMBER 1
 '@T6G_MB_LIB.T6G(SCH_1):PAGE352_I77@PURE_QUANTA.Q_CAP_DIFFBUS(CHIPS)':
 C_PATH='@t6g_mb_lib.t6g(sch_1):page352_i77@pure_quanta.q_cap_diffbus(chips)',
 P_PATH='@t6g_mb_lib.t6g(sch_1):page64_i77@pure_quanta.q_cap_diffbus(chips)',
 PATH='I77',
 DRAWING='@T6G_MB_LIB.T6G(SCH_1):PAGE352',
 PIN_NAMES_ROTATE='TRUE',
 TOLERANCE='20%',
 MATERIAL='X6S',
 PHYS_PAGE='64',
 XY='(-650,3100)',
 ROT='2',
 VER='2',
 PACK_TYPE='C0201',
 LOCATION='C843',
 CDS_LIB='pure_quanta',
 CDS_PART_NAME='Q_CAP_DIFFBUS_C0201-DIFF BUS_0.22UF,6.3V,20%,X6S,SA',
 VOLTAGE='6.3V',
 PART_NUMBER='SP_CH4221MEE01',
 VALUE='DIFF BUS_0.22UF',
 PRIM_FILE='./archive_libs/logical/q_cap_diffbus/chips/chips.prt';

PART_NAME
 C844 'Q_CAP_DIFFBUS_C0201-DIFF BUS_0.22UF,6.3V,20%,X6S,SA':;

SECTION_NUMBER 1
 '@T6G_MB_LIB.T6G(SCH_1):PAGE352_I70@PURE_QUANTA.Q_CAP_DIFFBUS(CHIPS)':
 C_PATH='@t6g_mb_lib.t6g(sch_1):page352_i70@pure_quanta.q_cap_diffbus(chips)',
 P_PATH='@t6g_mb_lib.t6g(sch_1):page64_i70@pure_quanta.q_cap_diffbus(chips)',
 PATH='I70',
 DRAWING='@T6G_MB_LIB.T6G(SCH_1):PAGE352',
 PIN_NAMES_ROTATE='TRUE',
 TOLERANCE='20%',
 MATERIAL='X6S',
 PHYS_PAGE='64',
 XY='(-650,2950)',
 ROT='2',
 VER='2',
 PACK_TYPE='C0201',
 LOCATION='C844',
 CDS_LIB='pure_quanta',
 CDS_PART_NAME='Q_CAP_DIFFBUS_C0201-DIFF BUS_0.22UF,6.3V,20%,X6S,SA',
 VOLTAGE='6.3V',
 PART_NUMBER='SP_CH4221MEE01',
 VALUE='DIFF BUS_0.22UF',
 PRIM_FILE='./archive_libs/logical/q_cap_diffbus/chips/chips.prt';

PART_NAME
 C845 'Q_CAP_DIFFBUS_C0201-DIFF BUS_0.22UF,6.3V,20%,X6S,SA':;

SECTION_NUMBER 1
 '@T6G_MB_LIB.T6G(SCH_1):PAGE352_I69@PURE_QUANTA.Q_CAP_DIFFBUS(CHIPS)':
 C_PATH='@t6g_mb_lib.t6g(sch_1):page352_i69@pure_quanta.q_cap_diffbus(chips)',
 P_PATH='@t6g_mb_lib.t6g(sch_1):page64_i69@pure_quanta.q_cap_diffbus(chips)',
 PATH='I69',
 DRAWING='@T6G_MB_LIB.T6G(SCH_1):PAGE352',
 PIN_NAMES_ROTATE='TRUE',
 TOLERANCE='20%',
 MATERIAL='X6S',
 PHYS_PAGE='64',
 XY='(-650,2900)',
 ROT='2',
 VER='2',
 PACK_TYPE='C0201',
 LOCATION='C845',
 CDS_LIB='pure_quanta',
 CDS_PART_NAME='Q_CAP_DIFFBUS_C0201-DIFF BUS_0.22UF,6.3V,20%,X6S,SA',
 VOLTAGE='6.3V',
 PART_NUMBER='SP_CH4221MEE01',
 VALUE='DIFF BUS_0.22UF',
 PRIM_FILE='./archive_libs/logical/q_cap_diffbus/chips/chips.prt';

PART_NAME
 C846 'Q_CAP_DIFFBUS_C0201-DIFF BUS_0.22UF,6.3V,20%,X6S,SA':;

SECTION_NUMBER 1
 '@T6G_MB_LIB.T6G(SCH_1):PAGE352_I68@PURE_QUANTA.Q_CAP_DIFFBUS(CHIPS)':
 C_PATH='@t6g_mb_lib.t6g(sch_1):page352_i68@pure_quanta.q_cap_diffbus(chips)',
 P_PATH='@t6g_mb_lib.t6g(sch_1):page64_i68@pure_quanta.q_cap_diffbus(chips)',
 PATH='I68',
 DRAWING='@T6G_MB_LIB.T6G(SCH_1):PAGE352',
 PIN_NAMES_ROTATE='TRUE',
 TOLERANCE='20%',
 MATERIAL='X6S',
 PHYS_PAGE='64',
 XY='(-650,2750)',
 ROT='2',
 VER='2',
 PACK_TYPE='C0201',
 LOCATION='C846',
 CDS_LIB='pure_quanta',
 CDS_PART_NAME='Q_CAP_DIFFBUS_C0201-DIFF BUS_0.22UF,6.3V,20%,X6S,SA',
 VOLTAGE='6.3V',
 PART_NUMBER='SP_CH4221MEE01',
 VALUE='DIFF BUS_0.22UF',
 PRIM_FILE='./archive_libs/logical/q_cap_diffbus/chips/chips.prt';

PART_NAME
 C847 'Q_CAP_DIFFBUS_C0201-DIFF BUS_0.22UF,6.3V,20%,X6S,SA':;

SECTION_NUMBER 1
 '@T6G_MB_LIB.T6G(SCH_1):PAGE352_I67@PURE_QUANTA.Q_CAP_DIFFBUS(CHIPS)':
 C_PATH='@t6g_mb_lib.t6g(sch_1):page352_i67@pure_quanta.q_cap_diffbus(chips)',
 P_PATH='@t6g_mb_lib.t6g(sch_1):page64_i67@pure_quanta.q_cap_diffbus(chips)',
 PATH='I67',
 DRAWING='@T6G_MB_LIB.T6G(SCH_1):PAGE352',
 PIN_NAMES_ROTATE='TRUE',
 TOLERANCE='20%',
 MATERIAL='X6S',
 PHYS_PAGE='64',
 XY='(-650,2700)',
 ROT='2',
 VER='2',
 PACK_TYPE='C0201',
 LOCATION='C847',
 CDS_LIB='pure_quanta',
 CDS_PART_NAME='Q_CAP_DIFFBUS_C0201-DIFF BUS_0.22UF,6.3V,20%,X6S,SA',
 VOLTAGE='6.3V',
 PART_NUMBER='SP_CH4221MEE01',
 VALUE='DIFF BUS_0.22UF',
 PRIM_FILE='./archive_libs/logical/q_cap_diffbus/chips/chips.prt';

PART_NAME
 C848 'Q_CAP_DIFFBUS_C0201-DIFF BUS_0.22UF,6.3V,20%,X6S,SA':;

SECTION_NUMBER 1
 '@T6G_MB_LIB.T6G(SCH_1):PAGE352_I66@PURE_QUANTA.Q_CAP_DIFFBUS(CHIPS)':
 C_PATH='@t6g_mb_lib.t6g(sch_1):page352_i66@pure_quanta.q_cap_diffbus(chips)',
 P_PATH='@t6g_mb_lib.t6g(sch_1):page64_i66@pure_quanta.q_cap_diffbus(chips)',
 PATH='I66',
 DRAWING='@T6G_MB_LIB.T6G(SCH_1):PAGE352',
 PIN_NAMES_ROTATE='TRUE',
 TOLERANCE='20%',
 MATERIAL='X6S',
 PHYS_PAGE='64',
 XY='(-650,2550)',
 ROT='2',
 VER='2',
 PACK_TYPE='C0201',
 LOCATION='C848',
 CDS_LIB='pure_quanta',
 CDS_PART_NAME='Q_CAP_DIFFBUS_C0201-DIFF BUS_0.22UF,6.3V,20%,X6S,SA',
 VOLTAGE='6.3V',
 PART_NUMBER='SP_CH4221MEE01',
 VALUE='DIFF BUS_0.22UF',
 PRIM_FILE='./archive_libs/logical/q_cap_diffbus/chips/chips.prt';

PART_NAME
 C849 'Q_CAP_DIFFBUS_C0201-DIFF BUS_0.22UF,6.3V,20%,X6S,SA':;

SECTION_NUMBER 1
 '@T6G_MB_LIB.T6G(SCH_1):PAGE352_I65@PURE_QUANTA.Q_CAP_DIFFBUS(CHIPS)':
 C_PATH='@t6g_mb_lib.t6g(sch_1):page352_i65@pure_quanta.q_cap_diffbus(chips)',
 P_PATH='@t6g_mb_lib.t6g(sch_1):page64_i65@pure_quanta.q_cap_diffbus(chips)',
 PATH='I65',
 DRAWING='@T6G_MB_LIB.T6G(SCH_1):PAGE352',
 PIN_NAMES_ROTATE='TRUE',
 TOLERANCE='20%',
 MATERIAL='X6S',
 PHYS_PAGE='64',
 XY='(-650,2500)',
 ROT='2',
 VER='2',
 PACK_TYPE='C0201',
 LOCATION='C849',
 CDS_LIB='pure_quanta',
 CDS_PART_NAME='Q_CAP_DIFFBUS_C0201-DIFF BUS_0.22UF,6.3V,20%,X6S,SA',
 VOLTAGE='6.3V',
 PART_NUMBER='SP_CH4221MEE01',
 VALUE='DIFF BUS_0.22UF',
 PRIM_FILE='./archive_libs/logical/q_cap_diffbus/chips/chips.prt';

PART_NAME
 C850 'Q_CAP_DIFFBUS_C0201-DIFF BUS_0.22UF,6.3V,20%,X6S,SA':;

SECTION_NUMBER 1
 '@T6G_MB_LIB.T6G(SCH_1):PAGE352_I64@PURE_QUANTA.Q_CAP_DIFFBUS(CHIPS)':
 C_PATH='@t6g_mb_lib.t6g(sch_1):page352_i64@pure_quanta.q_cap_diffbus(chips)',
 P_PATH='@t6g_mb_lib.t6g(sch_1):page64_i64@pure_quanta.q_cap_diffbus(chips)',
 PATH='I64',
 DRAWING='@T6G_MB_LIB.T6G(SCH_1):PAGE352',
 PIN_NAMES_ROTATE='TRUE',
 TOLERANCE='20%',
 MATERIAL='X6S',
 PHYS_PAGE='64',
 XY='(-650,2350)',
 ROT='2',
 VER='2',
 PACK_TYPE='C0201',
 LOCATION='C850',
 CDS_LIB='pure_quanta',
 CDS_PART_NAME='Q_CAP_DIFFBUS_C0201-DIFF BUS_0.22UF,6.3V,20%,X6S,SA',
 VOLTAGE='6.3V',
 PART_NUMBER='SP_CH4221MEE01',
 VALUE='DIFF BUS_0.22UF',
 PRIM_FILE='./archive_libs/logical/q_cap_diffbus/chips/chips.prt';

PART_NAME
 C851 'Q_CAP_DIFFBUS_C0201-DIFF BUS_0.22UF,6.3V,20%,X6S,SA':;

SECTION_NUMBER 1
 '@T6G_MB_LIB.T6G(SCH_1):PAGE352_I63@PURE_QUANTA.Q_CAP_DIFFBUS(CHIPS)':
 C_PATH='@t6g_mb_lib.t6g(sch_1):page352_i63@pure_quanta.q_cap_diffbus(chips)',
 P_PATH='@t6g_mb_lib.t6g(sch_1):page64_i63@pure_quanta.q_cap_diffbus(chips)',
 PATH='I63',
 DRAWING='@T6G_MB_LIB.T6G(SCH_1):PAGE352',
 PIN_NAMES_ROTATE='TRUE',
 TOLERANCE='20%',
 MATERIAL='X6S',
 PHYS_PAGE='64',
 XY='(-650,2300)',
 ROT='2',
 VER='2',
 PACK_TYPE='C0201',
 LOCATION='C851',
 CDS_LIB='pure_quanta',
 CDS_PART_NAME='Q_CAP_DIFFBUS_C0201-DIFF BUS_0.22UF,6.3V,20%,X6S,SA',
 VOLTAGE='6.3V',
 PART_NUMBER='SP_CH4221MEE01',
 VALUE='DIFF BUS_0.22UF',
 PRIM_FILE='./archive_libs/logical/q_cap_diffbus/chips/chips.prt';

PART_NAME
 C852 'Q_CAP_DIFFBUS_C0201-DIFF BUS_0.22UF,6.3V,20%,X6S,SA':;

SECTION_NUMBER 1
 '@T6G_MB_LIB.T6G(SCH_1):PAGE352_I61@PURE_QUANTA.Q_CAP_DIFFBUS(CHIPS)':
 C_PATH='@t6g_mb_lib.t6g(sch_1):page352_i61@pure_quanta.q_cap_diffbus(chips)',
 P_PATH='@t6g_mb_lib.t6g(sch_1):page64_i61@pure_quanta.q_cap_diffbus(chips)',
 PATH='I61',
 DRAWING='@T6G_MB_LIB.T6G(SCH_1):PAGE352',
 PIN_NAMES_ROTATE='TRUE',
 TOLERANCE='20%',
 MATERIAL='X6S',
 PHYS_PAGE='64',
 XY='(-650,2150)',
 ROT='2',
 VER='2',
 PACK_TYPE='C0201',
 LOCATION='C852',
 CDS_LIB='pure_quanta',
 CDS_PART_NAME='Q_CAP_DIFFBUS_C0201-DIFF BUS_0.22UF,6.3V,20%,X6S,SA',
 VOLTAGE='6.3V',
 PART_NUMBER='SP_CH4221MEE01',
 VALUE='DIFF BUS_0.22UF',
 PRIM_FILE='./archive_libs/logical/q_cap_diffbus/chips/chips.prt';

PART_NAME
 C853 'Q_CAP_DIFFBUS_C0201-DIFF BUS_0.22UF,6.3V,20%,X6S,SA':;

SECTION_NUMBER 1
 '@T6G_MB_LIB.T6G(SCH_1):PAGE352_I62@PURE_QUANTA.Q_CAP_DIFFBUS(CHIPS)':
 C_PATH='@t6g_mb_lib.t6g(sch_1):page352_i62@pure_quanta.q_cap_diffbus(chips)',
 P_PATH='@t6g_mb_lib.t6g(sch_1):page64_i62@pure_quanta.q_cap_diffbus(chips)',
 PATH='I62',
 DRAWING='@T6G_MB_LIB.T6G(SCH_1):PAGE352',
 PIN_NAMES_ROTATE='TRUE',
 TOLERANCE='20%',
 MATERIAL='X6S',
 PHYS_PAGE='64',
 XY='(-650,2100)',
 ROT='2',
 VER='2',
 PACK_TYPE='C0201',
 LOCATION='C853',
 CDS_LIB='pure_quanta',
 CDS_PART_NAME='Q_CAP_DIFFBUS_C0201-DIFF BUS_0.22UF,6.3V,20%,X6S,SA',
 VOLTAGE='6.3V',
 PART_NUMBER='SP_CH4221MEE01',
 VALUE='DIFF BUS_0.22UF',
 PRIM_FILE='./archive_libs/logical/q_cap_diffbus/chips/chips.prt';

PART_NAME
 C854 'Q_CAP_DIFFBUS_C0201-DIFF BUS_0.22UF,6.3V,20%,X6S,SA':;

SECTION_NUMBER 1
 '@T6G_MB_LIB.T6G(SCH_1):PAGE352_I41@PURE_QUANTA.Q_CAP_DIFFBUS(CHIPS)':
 C_PATH='@t6g_mb_lib.t6g(sch_1):page352_i41@pure_quanta.q_cap_diffbus(chips)',
 P_PATH='@t6g_mb_lib.t6g(sch_1):page64_i41@pure_quanta.q_cap_diffbus(chips)',
 PATH='I41',
 DRAWING='@T6G_MB_LIB.T6G(SCH_1):PAGE352',
 PIN_NAMES_ROTATE='TRUE',
 TOLERANCE='20%',
 MATERIAL='X6S',
 PHYS_PAGE='64',
 XY='(-650,1575)',
 ROT='2',
 VER='2',
 PACK_TYPE='C0201',
 LOCATION='C854',
 CDS_LIB='pure_quanta',
 CDS_PART_NAME='Q_CAP_DIFFBUS_C0201-DIFF BUS_0.22UF,6.3V,20%,X6S,SA',
 VOLTAGE='6.3V',
 PART_NUMBER='SP_CH4221MEE01',
 VALUE='DIFF BUS_0.22UF',
 PRIM_FILE='./archive_libs/logical/q_cap_diffbus/chips/chips.prt';

PART_NAME
 C855 'Q_CAP_DIFFBUS_C0201-DIFF BUS_0.22UF,6.3V,20%,X6S,SA':;

SECTION_NUMBER 1
 '@T6G_MB_LIB.T6G(SCH_1):PAGE352_I40@PURE_QUANTA.Q_CAP_DIFFBUS(CHIPS)':
 C_PATH='@t6g_mb_lib.t6g(sch_1):page352_i40@pure_quanta.q_cap_diffbus(chips)',
 P_PATH='@t6g_mb_lib.t6g(sch_1):page64_i40@pure_quanta.q_cap_diffbus(chips)',
 PATH='I40',
 DRAWING='@T6G_MB_LIB.T6G(SCH_1):PAGE352',
 PIN_NAMES_ROTATE='TRUE',
 TOLERANCE='20%',
 MATERIAL='X6S',
 PHYS_PAGE='64',
 XY='(-650,1525)',
 ROT='2',
 VER='2',
 PACK_TYPE='C0201',
 LOCATION='C855',
 CDS_LIB='pure_quanta',
 CDS_PART_NAME='Q_CAP_DIFFBUS_C0201-DIFF BUS_0.22UF,6.3V,20%,X6S,SA',
 VOLTAGE='6.3V',
 PART_NUMBER='SP_CH4221MEE01',
 VALUE='DIFF BUS_0.22UF',
 PRIM_FILE='./archive_libs/logical/q_cap_diffbus/chips/chips.prt';

PART_NAME
 C856 'Q_CAP_DIFFBUS_C0201-DIFF BUS_0.22UF,6.3V,20%,X6S,SA':;

SECTION_NUMBER 1
 '@T6G_MB_LIB.T6G(SCH_1):PAGE352_I39@PURE_QUANTA.Q_CAP_DIFFBUS(CHIPS)':
 C_PATH='@t6g_mb_lib.t6g(sch_1):page352_i39@pure_quanta.q_cap_diffbus(chips)',
 P_PATH='@t6g_mb_lib.t6g(sch_1):page64_i39@pure_quanta.q_cap_diffbus(chips)',
 PATH='I39',
 DRAWING='@T6G_MB_LIB.T6G(SCH_1):PAGE352',
 PIN_NAMES_ROTATE='TRUE',
 TOLERANCE='20%',
 MATERIAL='X6S',
 PHYS_PAGE='64',
 XY='(-650,1375)',
 ROT='2',
 VER='2',
 PACK_TYPE='C0201',
 LOCATION='C856',
 CDS_LIB='pure_quanta',
 CDS_PART_NAME='Q_CAP_DIFFBUS_C0201-DIFF BUS_0.22UF,6.3V,20%,X6S,SA',
 VOLTAGE='6.3V',
 PART_NUMBER='SP_CH4221MEE01',
 VALUE='DIFF BUS_0.22UF',
 PRIM_FILE='./archive_libs/logical/q_cap_diffbus/chips/chips.prt';

PART_NAME
 C857 'Q_CAP_DIFFBUS_C0201-DIFF BUS_0.22UF,6.3V,20%,X6S,SA':;

SECTION_NUMBER 1
 '@T6G_MB_LIB.T6G(SCH_1):PAGE352_I38@PURE_QUANTA.Q_CAP_DIFFBUS(CHIPS)':
 C_PATH='@t6g_mb_lib.t6g(sch_1):page352_i38@pure_quanta.q_cap_diffbus(chips)',
 P_PATH='@t6g_mb_lib.t6g(sch_1):page64_i38@pure_quanta.q_cap_diffbus(chips)',
 PATH='I38',
 DRAWING='@T6G_MB_LIB.T6G(SCH_1):PAGE352',
 PIN_NAMES_ROTATE='TRUE',
 TOLERANCE='20%',
 MATERIAL='X6S',
 PHYS_PAGE='64',
 XY='(-650,1325)',
 ROT='2',
 VER='2',
 PACK_TYPE='C0201',
 LOCATION='C857',
 CDS_LIB='pure_quanta',
 CDS_PART_NAME='Q_CAP_DIFFBUS_C0201-DIFF BUS_0.22UF,6.3V,20%,X6S,SA',
 VOLTAGE='6.3V',
 PART_NUMBER='SP_CH4221MEE01',
 VALUE='DIFF BUS_0.22UF',
 PRIM_FILE='./archive_libs/logical/q_cap_diffbus/chips/chips.prt';

PART_NAME
 C858 'Q_CAP_DIFFBUS_C0201-DIFF BUS_0.22UF,6.3V,20%,X6S,SA':;

SECTION_NUMBER 1
 '@T6G_MB_LIB.T6G(SCH_1):PAGE352_I37@PURE_QUANTA.Q_CAP_DIFFBUS(CHIPS)':
 C_PATH='@t6g_mb_lib.t6g(sch_1):page352_i37@pure_quanta.q_cap_diffbus(chips)',
 P_PATH='@t6g_mb_lib.t6g(sch_1):page64_i37@pure_quanta.q_cap_diffbus(chips)',
 PATH='I37',
 DRAWING='@T6G_MB_LIB.T6G(SCH_1):PAGE352',
 PIN_NAMES_ROTATE='TRUE',
 TOLERANCE='20%',
 MATERIAL='X6S',
 PHYS_PAGE='64',
 XY='(-650,1175)',
 ROT='2',
 VER='2',
 PACK_TYPE='C0201',
 LOCATION='C858',
 CDS_LIB='pure_quanta',
 CDS_PART_NAME='Q_CAP_DIFFBUS_C0201-DIFF BUS_0.22UF,6.3V,20%,X6S,SA',
 VOLTAGE='6.3V',
 PART_NUMBER='SP_CH4221MEE01',
 VALUE='DIFF BUS_0.22UF',
 PRIM_FILE='./archive_libs/logical/q_cap_diffbus/chips/chips.prt';

PART_NAME
 C859 'Q_CAP_DIFFBUS_C0201-DIFF BUS_0.22UF,6.3V,20%,X6S,SA':;

SECTION_NUMBER 1
 '@T6G_MB_LIB.T6G(SCH_1):PAGE352_I36@PURE_QUANTA.Q_CAP_DIFFBUS(CHIPS)':
 C_PATH='@t6g_mb_lib.t6g(sch_1):page352_i36@pure_quanta.q_cap_diffbus(chips)',
 P_PATH='@t6g_mb_lib.t6g(sch_1):page64_i36@pure_quanta.q_cap_diffbus(chips)',
 PATH='I36',
 DRAWING='@T6G_MB_LIB.T6G(SCH_1):PAGE352',
 PIN_NAMES_ROTATE='TRUE',
 TOLERANCE='20%',
 MATERIAL='X6S',
 PHYS_PAGE='64',
 XY='(-650,1125)',
 ROT='2',
 VER='2',
 PACK_TYPE='C0201',
 LOCATION='C859',
 CDS_LIB='pure_quanta',
 CDS_PART_NAME='Q_CAP_DIFFBUS_C0201-DIFF BUS_0.22UF,6.3V,20%,X6S,SA',
 VOLTAGE='6.3V',
 PART_NUMBER='SP_CH4221MEE01',
 VALUE='DIFF BUS_0.22UF',
 PRIM_FILE='./archive_libs/logical/q_cap_diffbus/chips/chips.prt';

PART_NAME
 C860 'Q_CAP_DIFFBUS_C0201-DIFF BUS_0.22UF,6.3V,20%,X6S,SA':;

SECTION_NUMBER 1
 '@T6G_MB_LIB.T6G(SCH_1):PAGE352_I30@PURE_QUANTA.Q_CAP_DIFFBUS(CHIPS)':
 C_PATH='@t6g_mb_lib.t6g(sch_1):page352_i30@pure_quanta.q_cap_diffbus(chips)',
 P_PATH='@t6g_mb_lib.t6g(sch_1):page64_i30@pure_quanta.q_cap_diffbus(chips)',
 PATH='I30',
 DRAWING='@T6G_MB_LIB.T6G(SCH_1):PAGE352',
 PIN_NAMES_ROTATE='TRUE',
 TOLERANCE='20%',
 MATERIAL='X6S',
 PHYS_PAGE='64',
 XY='(-650,975)',
 ROT='2',
 VER='2',
 PACK_TYPE='C0201',
 LOCATION='C860',
 CDS_LIB='pure_quanta',
 CDS_PART_NAME='Q_CAP_DIFFBUS_C0201-DIFF BUS_0.22UF,6.3V,20%,X6S,SA',
 VOLTAGE='6.3V',
 PART_NUMBER='SP_CH4221MEE01',
 VALUE='DIFF BUS_0.22UF',
 PRIM_FILE='./archive_libs/logical/q_cap_diffbus/chips/chips.prt';

PART_NAME
 C861 'Q_CAP_DIFFBUS_C0201-DIFF BUS_0.22UF,6.3V,20%,X6S,SA':;

SECTION_NUMBER 1
 '@T6G_MB_LIB.T6G(SCH_1):PAGE352_I29@PURE_QUANTA.Q_CAP_DIFFBUS(CHIPS)':
 C_PATH='@t6g_mb_lib.t6g(sch_1):page352_i29@pure_quanta.q_cap_diffbus(chips)',
 P_PATH='@t6g_mb_lib.t6g(sch_1):page64_i29@pure_quanta.q_cap_diffbus(chips)',
 PATH='I29',
 DRAWING='@T6G_MB_LIB.T6G(SCH_1):PAGE352',
 PIN_NAMES_ROTATE='TRUE',
 TOLERANCE='20%',
 MATERIAL='X6S',
 PHYS_PAGE='64',
 XY='(-650,925)',
 ROT='2',
 VER='2',
 PACK_TYPE='C0201',
 LOCATION='C861',
 CDS_LIB='pure_quanta',
 CDS_PART_NAME='Q_CAP_DIFFBUS_C0201-DIFF BUS_0.22UF,6.3V,20%,X6S,SA',
 VOLTAGE='6.3V',
 PART_NUMBER='SP_CH4221MEE01',
 VALUE='DIFF BUS_0.22UF',
 PRIM_FILE='./archive_libs/logical/q_cap_diffbus/chips/chips.prt';

PART_NAME
 C862 'Q_CAP_DIFFBUS_C0201-DIFF BUS_0.22UF,6.3V,20%,X6S,SA':;

SECTION_NUMBER 1
 '@T6G_MB_LIB.T6G(SCH_1):PAGE352_I28@PURE_QUANTA.Q_CAP_DIFFBUS(CHIPS)':
 C_PATH='@t6g_mb_lib.t6g(sch_1):page352_i28@pure_quanta.q_cap_diffbus(chips)',
 P_PATH='@t6g_mb_lib.t6g(sch_1):page64_i28@pure_quanta.q_cap_diffbus(chips)',
 PATH='I28',
 DRAWING='@T6G_MB_LIB.T6G(SCH_1):PAGE352',
 PIN_NAMES_ROTATE='TRUE',
 TOLERANCE='20%',
 MATERIAL='X6S',
 PHYS_PAGE='64',
 XY='(-650,775)',
 ROT='2',
 VER='2',
 PACK_TYPE='C0201',
 LOCATION='C862',
 CDS_LIB='pure_quanta',
 CDS_PART_NAME='Q_CAP_DIFFBUS_C0201-DIFF BUS_0.22UF,6.3V,20%,X6S,SA',
 VOLTAGE='6.3V',
 PART_NUMBER='SP_CH4221MEE01',
 VALUE='DIFF BUS_0.22UF',
 PRIM_FILE='./archive_libs/logical/q_cap_diffbus/chips/chips.prt';

PART_NAME
 C863 'Q_CAP_DIFFBUS_C0201-DIFF BUS_0.22UF,6.3V,20%,X6S,SA':;

SECTION_NUMBER 1
 '@T6G_MB_LIB.T6G(SCH_1):PAGE352_I27@PURE_QUANTA.Q_CAP_DIFFBUS(CHIPS)':
 C_PATH='@t6g_mb_lib.t6g(sch_1):page352_i27@pure_quanta.q_cap_diffbus(chips)',
 P_PATH='@t6g_mb_lib.t6g(sch_1):page64_i27@pure_quanta.q_cap_diffbus(chips)',
 PATH='I27',
 DRAWING='@T6G_MB_LIB.T6G(SCH_1):PAGE352',
 PIN_NAMES_ROTATE='TRUE',
 TOLERANCE='20%',
 MATERIAL='X6S',
 PHYS_PAGE='64',
 XY='(-650,725)',
 ROT='2',
 VER='2',
 PACK_TYPE='C0201',
 LOCATION='C863',
 CDS_LIB='pure_quanta',
 CDS_PART_NAME='Q_CAP_DIFFBUS_C0201-DIFF BUS_0.22UF,6.3V,20%,X6S,SA',
 VOLTAGE='6.3V',
 PART_NUMBER='SP_CH4221MEE01',
 VALUE='DIFF BUS_0.22UF',
 PRIM_FILE='./archive_libs/logical/q_cap_diffbus/chips/chips.prt';

PART_NAME
 C864 'Q_CAP_DIFFBUS_C0201-DIFF BUS_0.22UF,6.3V,20%,X6S,SA':;

SECTION_NUMBER 1
 '@T6G_MB_LIB.T6G(SCH_1):PAGE352_I25@PURE_QUANTA.Q_CAP_DIFFBUS(CHIPS)':
 C_PATH='@t6g_mb_lib.t6g(sch_1):page352_i25@pure_quanta.q_cap_diffbus(chips)',
 P_PATH='@t6g_mb_lib.t6g(sch_1):page64_i25@pure_quanta.q_cap_diffbus(chips)',
 PATH='I25',
 DRAWING='@T6G_MB_LIB.T6G(SCH_1):PAGE352',
 PIN_NAMES_ROTATE='TRUE',
 TOLERANCE='20%',
 MATERIAL='X6S',
 PHYS_PAGE='64',
 XY='(-650,575)',
 ROT='2',
 VER='2',
 PACK_TYPE='C0201',
 LOCATION='C864',
 CDS_LIB='pure_quanta',
 CDS_PART_NAME='Q_CAP_DIFFBUS_C0201-DIFF BUS_0.22UF,6.3V,20%,X6S,SA',
 VOLTAGE='6.3V',
 PART_NUMBER='SP_CH4221MEE01',
 VALUE='DIFF BUS_0.22UF',
 PRIM_FILE='./archive_libs/logical/q_cap_diffbus/chips/chips.prt';

PART_NAME
 C865 'Q_CAP_DIFFBUS_C0201-DIFF BUS_0.22UF,6.3V,20%,X6S,SA':;

SECTION_NUMBER 1
 '@T6G_MB_LIB.T6G(SCH_1):PAGE352_I26@PURE_QUANTA.Q_CAP_DIFFBUS(CHIPS)':
 C_PATH='@t6g_mb_lib.t6g(sch_1):page352_i26@pure_quanta.q_cap_diffbus(chips)',
 P_PATH='@t6g_mb_lib.t6g(sch_1):page64_i26@pure_quanta.q_cap_diffbus(chips)',
 PATH='I26',
 DRAWING='@T6G_MB_LIB.T6G(SCH_1):PAGE352',
 PIN_NAMES_ROTATE='TRUE',
 TOLERANCE='20%',
 MATERIAL='X6S',
 PHYS_PAGE='64',
 XY='(-650,525)',
 ROT='2',
 VER='2',
 PACK_TYPE='C0201',
 LOCATION='C865',
 CDS_LIB='pure_quanta',
 CDS_PART_NAME='Q_CAP_DIFFBUS_C0201-DIFF BUS_0.22UF,6.3V,20%,X6S,SA',
 VOLTAGE='6.3V',
 PART_NUMBER='SP_CH4221MEE01',
 VALUE='DIFF BUS_0.22UF',
 PRIM_FILE='./archive_libs/logical/q_cap_diffbus/chips/chips.prt';

PART_NAME
 C866 'Q_CAP_DIFFBUS_C0201-DIFF BUS_0.22UF,6.3V,20%,X6S,SA':;

SECTION_NUMBER 1
 '@T6G_MB_LIB.T6G(SCH_1):PAGE352_I24@PURE_QUANTA.Q_CAP_DIFFBUS(CHIPS)':
 C_PATH='@t6g_mb_lib.t6g(sch_1):page352_i24@pure_quanta.q_cap_diffbus(chips)',
 P_PATH='@t6g_mb_lib.t6g(sch_1):page64_i24@pure_quanta.q_cap_diffbus(chips)',
 PATH='I24',
 DRAWING='@T6G_MB_LIB.T6G(SCH_1):PAGE352',
 PIN_NAMES_ROTATE='TRUE',
 TOLERANCE='20%',
 MATERIAL='X6S',
 PHYS_PAGE='64',
 XY='(-650,375)',
 ROT='2',
 VER='2',
 PACK_TYPE='C0201',
 LOCATION='C866',
 CDS_LIB='pure_quanta',
 CDS_PART_NAME='Q_CAP_DIFFBUS_C0201-DIFF BUS_0.22UF,6.3V,20%,X6S,SA',
 VOLTAGE='6.3V',
 PART_NUMBER='SP_CH4221MEE01',
 VALUE='DIFF BUS_0.22UF',
 PRIM_FILE='./archive_libs/logical/q_cap_diffbus/chips/chips.prt';

PART_NAME
 C867 'Q_CAP_DIFFBUS_C0201-DIFF BUS_0.22UF,6.3V,20%,X6S,SA':;

SECTION_NUMBER 1
 '@T6G_MB_LIB.T6G(SCH_1):PAGE352_I23@PURE_QUANTA.Q_CAP_DIFFBUS(CHIPS)':
 C_PATH='@t6g_mb_lib.t6g(sch_1):page352_i23@pure_quanta.q_cap_diffbus(chips)',
 P_PATH='@t6g_mb_lib.t6g(sch_1):page64_i23@pure_quanta.q_cap_diffbus(chips)',
 PATH='I23',
 DRAWING='@T6G_MB_LIB.T6G(SCH_1):PAGE352',
 PIN_NAMES_ROTATE='TRUE',
 TOLERANCE='20%',
 MATERIAL='X6S',
 PHYS_PAGE='64',
 XY='(-650,325)',
 ROT='2',
 VER='2',
 PACK_TYPE='C0201',
 LOCATION='C867',
 CDS_LIB='pure_quanta',
 CDS_PART_NAME='Q_CAP_DIFFBUS_C0201-DIFF BUS_0.22UF,6.3V,20%,X6S,SA',
 VOLTAGE='6.3V',
 PART_NUMBER='SP_CH4221MEE01',
 VALUE='DIFF BUS_0.22UF',
 PRIM_FILE='./archive_libs/logical/q_cap_diffbus/chips/chips.prt';

PART_NAME
 C868 'Q_CAP_DIFFBUS_C0201-DIFF BUS_0.22UF,6.3V,20%,X6S,SA':;

SECTION_NUMBER 1
 '@T6G_MB_LIB.T6G(SCH_1):PAGE352_I22@PURE_QUANTA.Q_CAP_DIFFBUS(CHIPS)':
 C_PATH='@t6g_mb_lib.t6g(sch_1):page352_i22@pure_quanta.q_cap_diffbus(chips)',
 P_PATH='@t6g_mb_lib.t6g(sch_1):page64_i22@pure_quanta.q_cap_diffbus(chips)',
 PATH='I22',
 DRAWING='@T6G_MB_LIB.T6G(SCH_1):PAGE352',
 PIN_NAMES_ROTATE='TRUE',
 TOLERANCE='20%',
 MATERIAL='X6S',
 PHYS_PAGE='64',
 XY='(-650,175)',
 ROT='2',
 VER='2',
 PACK_TYPE='C0201',
 LOCATION='C868',
 CDS_LIB='pure_quanta',
 CDS_PART_NAME='Q_CAP_DIFFBUS_C0201-DIFF BUS_0.22UF,6.3V,20%,X6S,SA',
 VOLTAGE='6.3V',
 PART_NUMBER='SP_CH4221MEE01',
 VALUE='DIFF BUS_0.22UF',
 PRIM_FILE='./archive_libs/logical/q_cap_diffbus/chips/chips.prt';

PART_NAME
 C869 'Q_CAP_DIFFBUS_C0201-DIFF BUS_0.22UF,6.3V,20%,X6S,SA':;

SECTION_NUMBER 1
 '@T6G_MB_LIB.T6G(SCH_1):PAGE352_I21@PURE_QUANTA.Q_CAP_DIFFBUS(CHIPS)':
 C_PATH='@t6g_mb_lib.t6g(sch_1):page352_i21@pure_quanta.q_cap_diffbus(chips)',
 P_PATH='@t6g_mb_lib.t6g(sch_1):page64_i21@pure_quanta.q_cap_diffbus(chips)',
 PATH='I21',
 DRAWING='@T6G_MB_LIB.T6G(SCH_1):PAGE352',
 PIN_NAMES_ROTATE='TRUE',
 TOLERANCE='20%',
 MATERIAL='X6S',
 PHYS_PAGE='64',
 XY='(-650,125)',
 ROT='2',
 VER='2',
 PACK_TYPE='C0201',
 LOCATION='C869',
 CDS_LIB='pure_quanta',
 CDS_PART_NAME='Q_CAP_DIFFBUS_C0201-DIFF BUS_0.22UF,6.3V,20%,X6S,SA',
 VOLTAGE='6.3V',
 PART_NUMBER='SP_CH4221MEE01',
 VALUE='DIFF BUS_0.22UF',
 PRIM_FILE='./archive_libs/logical/q_cap_diffbus/chips/chips.prt';

PART_NAME
 C870 'Q_CAP_DIFFBUS_C0201-DIFF BUS_0.22UF,6.3V,20%,X6S,SA':;

SECTION_NUMBER 1
 '@T6G_MB_LIB.T6G(SCH_1):PAGE352_I169@PURE_QUANTA.Q_CAP_DIFFBUS(CHIPS)':
 C_PATH='@t6g_mb_lib.t6g(sch_1):page352_i169@pure_quanta.q_cap_diffbus(chips)',
 P_PATH='@t6g_mb_lib.t6g(sch_1):page64_i169@pure_quanta.q_cap_diffbus(chips)',
 PATH='I169',
 DRAWING='@T6G_MB_LIB.T6G(SCH_1):PAGE352',
 PIN_NAMES_ROTATE='TRUE',
 TOLERANCE='20%',
 MATERIAL='X6S',
 PHYS_PAGE='64',
 XY='(3825,3550)',
 ROT='2',
 VER='2',
 PACK_TYPE='C0201',
 LOCATION='C870',
 CDS_LIB='pure_quanta',
 CDS_PART_NAME='Q_CAP_DIFFBUS_C0201-DIFF BUS_0.22UF,6.3V,20%,X6S,SA',
 VOLTAGE='6.3V',
 PART_NUMBER='SP_CH4221MEE01',
 VALUE='DIFF BUS_0.22UF',
 PRIM_FILE='./archive_libs/logical/q_cap_diffbus/chips/chips.prt';

PART_NAME
 C871 'Q_CAP_DIFFBUS_C0201-DIFF BUS_0.22UF,6.3V,20%,X6S,SA':;

SECTION_NUMBER 1
 '@T6G_MB_LIB.T6G(SCH_1):PAGE352_I168@PURE_QUANTA.Q_CAP_DIFFBUS(CHIPS)':
 C_PATH='@t6g_mb_lib.t6g(sch_1):page352_i168@pure_quanta.q_cap_diffbus(chips)',
 P_PATH='@t6g_mb_lib.t6g(sch_1):page64_i168@pure_quanta.q_cap_diffbus(chips)',
 PATH='I168',
 DRAWING='@T6G_MB_LIB.T6G(SCH_1):PAGE352',
 PIN_NAMES_ROTATE='TRUE',
 TOLERANCE='20%',
 MATERIAL='X6S',
 PHYS_PAGE='64',
 XY='(3825,3500)',
 ROT='2',
 VER='2',
 PACK_TYPE='C0201',
 LOCATION='C871',
 CDS_LIB='pure_quanta',
 CDS_PART_NAME='Q_CAP_DIFFBUS_C0201-DIFF BUS_0.22UF,6.3V,20%,X6S,SA',
 VOLTAGE='6.3V',
 PART_NUMBER='SP_CH4221MEE01',
 VALUE='DIFF BUS_0.22UF',
 PRIM_FILE='./archive_libs/logical/q_cap_diffbus/chips/chips.prt';

PART_NAME
 C872 'Q_CAP_DIFFBUS_C0201-DIFF BUS_0.22UF,6.3V,20%,X6S,SA':;

SECTION_NUMBER 1
 '@T6G_MB_LIB.T6G(SCH_1):PAGE352_I167@PURE_QUANTA.Q_CAP_DIFFBUS(CHIPS)':
 C_PATH='@t6g_mb_lib.t6g(sch_1):page352_i167@pure_quanta.q_cap_diffbus(chips)',
 P_PATH='@t6g_mb_lib.t6g(sch_1):page64_i167@pure_quanta.q_cap_diffbus(chips)',
 PATH='I167',
 DRAWING='@T6G_MB_LIB.T6G(SCH_1):PAGE352',
 PIN_NAMES_ROTATE='TRUE',
 TOLERANCE='20%',
 MATERIAL='X6S',
 PHYS_PAGE='64',
 XY='(3825,3350)',
 ROT='2',
 VER='2',
 PACK_TYPE='C0201',
 LOCATION='C872',
 CDS_LIB='pure_quanta',
 CDS_PART_NAME='Q_CAP_DIFFBUS_C0201-DIFF BUS_0.22UF,6.3V,20%,X6S,SA',
 VOLTAGE='6.3V',
 PART_NUMBER='SP_CH4221MEE01',
 VALUE='DIFF BUS_0.22UF',
 PRIM_FILE='./archive_libs/logical/q_cap_diffbus/chips/chips.prt';

PART_NAME
 C873 'Q_CAP_DIFFBUS_C0201-DIFF BUS_0.22UF,6.3V,20%,X6S,SA':;

SECTION_NUMBER 1
 '@T6G_MB_LIB.T6G(SCH_1):PAGE352_I166@PURE_QUANTA.Q_CAP_DIFFBUS(CHIPS)':
 C_PATH='@t6g_mb_lib.t6g(sch_1):page352_i166@pure_quanta.q_cap_diffbus(chips)',
 P_PATH='@t6g_mb_lib.t6g(sch_1):page64_i166@pure_quanta.q_cap_diffbus(chips)',
 PATH='I166',
 DRAWING='@T6G_MB_LIB.T6G(SCH_1):PAGE352',
 PIN_NAMES_ROTATE='TRUE',
 TOLERANCE='20%',
 MATERIAL='X6S',
 PHYS_PAGE='64',
 XY='(3825,3300)',
 ROT='2',
 VER='2',
 PACK_TYPE='C0201',
 LOCATION='C873',
 CDS_LIB='pure_quanta',
 CDS_PART_NAME='Q_CAP_DIFFBUS_C0201-DIFF BUS_0.22UF,6.3V,20%,X6S,SA',
 VOLTAGE='6.3V',
 PART_NUMBER='SP_CH4221MEE01',
 VALUE='DIFF BUS_0.22UF',
 PRIM_FILE='./archive_libs/logical/q_cap_diffbus/chips/chips.prt';

PART_NAME
 C874 'Q_CAP_DIFFBUS_C0201-DIFF BUS_0.22UF,6.3V,20%,X6S,SA':;

SECTION_NUMBER 1
 '@T6G_MB_LIB.T6G(SCH_1):PAGE352_I165@PURE_QUANTA.Q_CAP_DIFFBUS(CHIPS)':
 C_PATH='@t6g_mb_lib.t6g(sch_1):page352_i165@pure_quanta.q_cap_diffbus(chips)',
 P_PATH='@t6g_mb_lib.t6g(sch_1):page64_i165@pure_quanta.q_cap_diffbus(chips)',
 PATH='I165',
 DRAWING='@T6G_MB_LIB.T6G(SCH_1):PAGE352',
 PIN_NAMES_ROTATE='TRUE',
 TOLERANCE='20%',
 MATERIAL='X6S',
 PHYS_PAGE='64',
 XY='(3825,3150)',
 ROT='2',
 VER='2',
 PACK_TYPE='C0201',
 LOCATION='C874',
 CDS_LIB='pure_quanta',
 CDS_PART_NAME='Q_CAP_DIFFBUS_C0201-DIFF BUS_0.22UF,6.3V,20%,X6S,SA',
 VOLTAGE='6.3V',
 PART_NUMBER='SP_CH4221MEE01',
 VALUE='DIFF BUS_0.22UF',
 PRIM_FILE='./archive_libs/logical/q_cap_diffbus/chips/chips.prt';

PART_NAME
 C875 'Q_CAP_DIFFBUS_C0201-DIFF BUS_0.22UF,6.3V,20%,X6S,SA':;

SECTION_NUMBER 1
 '@T6G_MB_LIB.T6G(SCH_1):PAGE352_I164@PURE_QUANTA.Q_CAP_DIFFBUS(CHIPS)':
 C_PATH='@t6g_mb_lib.t6g(sch_1):page352_i164@pure_quanta.q_cap_diffbus(chips)',
 P_PATH='@t6g_mb_lib.t6g(sch_1):page64_i164@pure_quanta.q_cap_diffbus(chips)',
 PATH='I164',
 DRAWING='@T6G_MB_LIB.T6G(SCH_1):PAGE352',
 PIN_NAMES_ROTATE='TRUE',
 TOLERANCE='20%',
 MATERIAL='X6S',
 PHYS_PAGE='64',
 XY='(3825,3100)',
 ROT='2',
 VER='2',
 PACK_TYPE='C0201',
 LOCATION='C875',
 CDS_LIB='pure_quanta',
 CDS_PART_NAME='Q_CAP_DIFFBUS_C0201-DIFF BUS_0.22UF,6.3V,20%,X6S,SA',
 VOLTAGE='6.3V',
 PART_NUMBER='SP_CH4221MEE01',
 VALUE='DIFF BUS_0.22UF',
 PRIM_FILE='./archive_libs/logical/q_cap_diffbus/chips/chips.prt';

PART_NAME
 C876 'Q_CAP_DIFFBUS_C0201-DIFF BUS_0.22UF,6.3V,20%,X6S,SA':;

SECTION_NUMBER 1
 '@T6G_MB_LIB.T6G(SCH_1):PAGE352_I160@PURE_QUANTA.Q_CAP_DIFFBUS(CHIPS)':
 C_PATH='@t6g_mb_lib.t6g(sch_1):page352_i160@pure_quanta.q_cap_diffbus(chips)',
 P_PATH='@t6g_mb_lib.t6g(sch_1):page64_i160@pure_quanta.q_cap_diffbus(chips)',
 PATH='I160',
 DRAWING='@T6G_MB_LIB.T6G(SCH_1):PAGE352',
 PIN_NAMES_ROTATE='TRUE',
 TOLERANCE='20%',
 MATERIAL='X6S',
 PHYS_PAGE='64',
 XY='(3825,2950)',
 ROT='2',
 VER='2',
 PACK_TYPE='C0201',
 LOCATION='C876',
 CDS_LIB='pure_quanta',
 CDS_PART_NAME='Q_CAP_DIFFBUS_C0201-DIFF BUS_0.22UF,6.3V,20%,X6S,SA',
 VOLTAGE='6.3V',
 PART_NUMBER='SP_CH4221MEE01',
 VALUE='DIFF BUS_0.22UF',
 PRIM_FILE='./archive_libs/logical/q_cap_diffbus/chips/chips.prt';

PART_NAME
 C877 'Q_CAP_DIFFBUS_C0201-DIFF BUS_0.22UF,6.3V,20%,X6S,SA':;

SECTION_NUMBER 1
 '@T6G_MB_LIB.T6G(SCH_1):PAGE352_I159@PURE_QUANTA.Q_CAP_DIFFBUS(CHIPS)':
 C_PATH='@t6g_mb_lib.t6g(sch_1):page352_i159@pure_quanta.q_cap_diffbus(chips)',
 P_PATH='@t6g_mb_lib.t6g(sch_1):page64_i159@pure_quanta.q_cap_diffbus(chips)',
 PATH='I159',
 DRAWING='@T6G_MB_LIB.T6G(SCH_1):PAGE352',
 PIN_NAMES_ROTATE='TRUE',
 TOLERANCE='20%',
 MATERIAL='X6S',
 PHYS_PAGE='64',
 XY='(3825,2900)',
 ROT='2',
 VER='2',
 PACK_TYPE='C0201',
 LOCATION='C877',
 CDS_LIB='pure_quanta',
 CDS_PART_NAME='Q_CAP_DIFFBUS_C0201-DIFF BUS_0.22UF,6.3V,20%,X6S,SA',
 VOLTAGE='6.3V',
 PART_NUMBER='SP_CH4221MEE01',
 VALUE='DIFF BUS_0.22UF',
 PRIM_FILE='./archive_libs/logical/q_cap_diffbus/chips/chips.prt';

PART_NAME
 C878 'Q_CAP_DIFFBUS_C0201-DIFF BUS_0.22UF,6.3V,20%,X6S,SA':;

SECTION_NUMBER 1
 '@T6G_MB_LIB.T6G(SCH_1):PAGE352_I157@PURE_QUANTA.Q_CAP_DIFFBUS(CHIPS)':
 C_PATH='@t6g_mb_lib.t6g(sch_1):page352_i157@pure_quanta.q_cap_diffbus(chips)',
 P_PATH='@t6g_mb_lib.t6g(sch_1):page64_i157@pure_quanta.q_cap_diffbus(chips)',
 PATH='I157',
 DRAWING='@T6G_MB_LIB.T6G(SCH_1):PAGE352',
 PIN_NAMES_ROTATE='TRUE',
 TOLERANCE='20%',
 MATERIAL='X6S',
 PHYS_PAGE='64',
 XY='(3825,2750)',
 ROT='2',
 VER='2',
 PACK_TYPE='C0201',
 LOCATION='C878',
 CDS_LIB='pure_quanta',
 CDS_PART_NAME='Q_CAP_DIFFBUS_C0201-DIFF BUS_0.22UF,6.3V,20%,X6S,SA',
 VOLTAGE='6.3V',
 PART_NUMBER='SP_CH4221MEE01',
 VALUE='DIFF BUS_0.22UF',
 PRIM_FILE='./archive_libs/logical/q_cap_diffbus/chips/chips.prt';

PART_NAME
 C879 'Q_CAP_DIFFBUS_C0201-DIFF BUS_0.22UF,6.3V,20%,X6S,SA':;

SECTION_NUMBER 1
 '@T6G_MB_LIB.T6G(SCH_1):PAGE352_I158@PURE_QUANTA.Q_CAP_DIFFBUS(CHIPS)':
 C_PATH='@t6g_mb_lib.t6g(sch_1):page352_i158@pure_quanta.q_cap_diffbus(chips)',
 P_PATH='@t6g_mb_lib.t6g(sch_1):page64_i158@pure_quanta.q_cap_diffbus(chips)',
 PATH='I158',
 DRAWING='@T6G_MB_LIB.T6G(SCH_1):PAGE352',
 PIN_NAMES_ROTATE='TRUE',
 TOLERANCE='20%',
 MATERIAL='X6S',
 PHYS_PAGE='64',
 XY='(3825,2700)',
 ROT='2',
 VER='2',
 PACK_TYPE='C0201',
 LOCATION='C879',
 CDS_LIB='pure_quanta',
 CDS_PART_NAME='Q_CAP_DIFFBUS_C0201-DIFF BUS_0.22UF,6.3V,20%,X6S,SA',
 VOLTAGE='6.3V',
 PART_NUMBER='SP_CH4221MEE01',
 VALUE='DIFF BUS_0.22UF',
 PRIM_FILE='./archive_libs/logical/q_cap_diffbus/chips/chips.prt';

PART_NAME
 C880 'Q_CAP_DIFFBUS_C0201-DIFF BUS_0.22UF,6.3V,20%,X6S,SA':;

SECTION_NUMBER 1
 '@T6G_MB_LIB.T6G(SCH_1):PAGE352_I156@PURE_QUANTA.Q_CAP_DIFFBUS(CHIPS)':
 C_PATH='@t6g_mb_lib.t6g(sch_1):page352_i156@pure_quanta.q_cap_diffbus(chips)',
 P_PATH='@t6g_mb_lib.t6g(sch_1):page64_i156@pure_quanta.q_cap_diffbus(chips)',
 PATH='I156',
 DRAWING='@T6G_MB_LIB.T6G(SCH_1):PAGE352',
 PIN_NAMES_ROTATE='TRUE',
 TOLERANCE='20%',
 MATERIAL='X6S',
 PHYS_PAGE='64',
 XY='(3825,2550)',
 ROT='2',
 VER='2',
 PACK_TYPE='C0201',
 LOCATION='C880',
 CDS_LIB='pure_quanta',
 CDS_PART_NAME='Q_CAP_DIFFBUS_C0201-DIFF BUS_0.22UF,6.3V,20%,X6S,SA',
 VOLTAGE='6.3V',
 PART_NUMBER='SP_CH4221MEE01',
 VALUE='DIFF BUS_0.22UF',
 PRIM_FILE='./archive_libs/logical/q_cap_diffbus/chips/chips.prt';

PART_NAME
 C881 'Q_CAP_DIFFBUS_C0201-DIFF BUS_0.22UF,6.3V,20%,X6S,SA':;

SECTION_NUMBER 1
 '@T6G_MB_LIB.T6G(SCH_1):PAGE352_I155@PURE_QUANTA.Q_CAP_DIFFBUS(CHIPS)':
 C_PATH='@t6g_mb_lib.t6g(sch_1):page352_i155@pure_quanta.q_cap_diffbus(chips)',
 P_PATH='@t6g_mb_lib.t6g(sch_1):page64_i155@pure_quanta.q_cap_diffbus(chips)',
 PATH='I155',
 DRAWING='@T6G_MB_LIB.T6G(SCH_1):PAGE352',
 PIN_NAMES_ROTATE='TRUE',
 TOLERANCE='20%',
 MATERIAL='X6S',
 PHYS_PAGE='64',
 XY='(3825,2500)',
 ROT='2',
 VER='2',
 PACK_TYPE='C0201',
 LOCATION='C881',
 CDS_LIB='pure_quanta',
 CDS_PART_NAME='Q_CAP_DIFFBUS_C0201-DIFF BUS_0.22UF,6.3V,20%,X6S,SA',
 VOLTAGE='6.3V',
 PART_NUMBER='SP_CH4221MEE01',
 VALUE='DIFF BUS_0.22UF',
 PRIM_FILE='./archive_libs/logical/q_cap_diffbus/chips/chips.prt';

PART_NAME
 C882 'Q_CAP_DIFFBUS_C0201-DIFF BUS_0.22UF,6.3V,20%,X6S,SA':;

SECTION_NUMBER 1
 '@T6G_MB_LIB.T6G(SCH_1):PAGE352_I154@PURE_QUANTA.Q_CAP_DIFFBUS(CHIPS)':
 C_PATH='@t6g_mb_lib.t6g(sch_1):page352_i154@pure_quanta.q_cap_diffbus(chips)',
 P_PATH='@t6g_mb_lib.t6g(sch_1):page64_i154@pure_quanta.q_cap_diffbus(chips)',
 PATH='I154',
 DRAWING='@T6G_MB_LIB.T6G(SCH_1):PAGE352',
 PIN_NAMES_ROTATE='TRUE',
 TOLERANCE='20%',
 MATERIAL='X6S',
 PHYS_PAGE='64',
 XY='(3825,2350)',
 ROT='2',
 VER='2',
 PACK_TYPE='C0201',
 LOCATION='C882',
 CDS_LIB='pure_quanta',
 CDS_PART_NAME='Q_CAP_DIFFBUS_C0201-DIFF BUS_0.22UF,6.3V,20%,X6S,SA',
 VOLTAGE='6.3V',
 PART_NUMBER='SP_CH4221MEE01',
 VALUE='DIFF BUS_0.22UF',
 PRIM_FILE='./archive_libs/logical/q_cap_diffbus/chips/chips.prt';

PART_NAME
 C883 'Q_CAP_DIFFBUS_C0201-DIFF BUS_0.22UF,6.3V,20%,X6S,SA':;

SECTION_NUMBER 1
 '@T6G_MB_LIB.T6G(SCH_1):PAGE352_I153@PURE_QUANTA.Q_CAP_DIFFBUS(CHIPS)':
 C_PATH='@t6g_mb_lib.t6g(sch_1):page352_i153@pure_quanta.q_cap_diffbus(chips)',
 P_PATH='@t6g_mb_lib.t6g(sch_1):page64_i153@pure_quanta.q_cap_diffbus(chips)',
 PATH='I153',
 DRAWING='@T6G_MB_LIB.T6G(SCH_1):PAGE352',
 PIN_NAMES_ROTATE='TRUE',
 TOLERANCE='20%',
 MATERIAL='X6S',
 PHYS_PAGE='64',
 XY='(3825,2300)',
 ROT='2',
 VER='2',
 PACK_TYPE='C0201',
 LOCATION='C883',
 CDS_LIB='pure_quanta',
 CDS_PART_NAME='Q_CAP_DIFFBUS_C0201-DIFF BUS_0.22UF,6.3V,20%,X6S,SA',
 VOLTAGE='6.3V',
 PART_NUMBER='SP_CH4221MEE01',
 VALUE='DIFF BUS_0.22UF',
 PRIM_FILE='./archive_libs/logical/q_cap_diffbus/chips/chips.prt';

PART_NAME
 C884 'Q_CAP_DIFFBUS_C0201-DIFF BUS_0.22UF,6.3V,20%,X6S,SA':;

SECTION_NUMBER 1
 '@T6G_MB_LIB.T6G(SCH_1):PAGE352_I151@PURE_QUANTA.Q_CAP_DIFFBUS(CHIPS)':
 C_PATH='@t6g_mb_lib.t6g(sch_1):page352_i151@pure_quanta.q_cap_diffbus(chips)',
 P_PATH='@t6g_mb_lib.t6g(sch_1):page64_i151@pure_quanta.q_cap_diffbus(chips)',
 PATH='I151',
 DRAWING='@T6G_MB_LIB.T6G(SCH_1):PAGE352',
 PIN_NAMES_ROTATE='TRUE',
 TOLERANCE='20%',
 MATERIAL='X6S',
 PHYS_PAGE='64',
 XY='(3825,2150)',
 ROT='2',
 VER='2',
 PACK_TYPE='C0201',
 LOCATION='C884',
 CDS_LIB='pure_quanta',
 CDS_PART_NAME='Q_CAP_DIFFBUS_C0201-DIFF BUS_0.22UF,6.3V,20%,X6S,SA',
 VOLTAGE='6.3V',
 PART_NUMBER='SP_CH4221MEE01',
 VALUE='DIFF BUS_0.22UF',
 PRIM_FILE='./archive_libs/logical/q_cap_diffbus/chips/chips.prt';

PART_NAME
 C885 'Q_CAP_DIFFBUS_C0201-DIFF BUS_0.22UF,6.3V,20%,X6S,SA':;

SECTION_NUMBER 1
 '@T6G_MB_LIB.T6G(SCH_1):PAGE352_I152@PURE_QUANTA.Q_CAP_DIFFBUS(CHIPS)':
 C_PATH='@t6g_mb_lib.t6g(sch_1):page352_i152@pure_quanta.q_cap_diffbus(chips)',
 P_PATH='@t6g_mb_lib.t6g(sch_1):page64_i152@pure_quanta.q_cap_diffbus(chips)',
 PATH='I152',
 DRAWING='@T6G_MB_LIB.T6G(SCH_1):PAGE352',
 PIN_NAMES_ROTATE='TRUE',
 TOLERANCE='20%',
 MATERIAL='X6S',
 PHYS_PAGE='64',
 XY='(3825,2100)',
 ROT='2',
 VER='2',
 PACK_TYPE='C0201',
 LOCATION='C885',
 CDS_LIB='pure_quanta',
 CDS_PART_NAME='Q_CAP_DIFFBUS_C0201-DIFF BUS_0.22UF,6.3V,20%,X6S,SA',
 VOLTAGE='6.3V',
 PART_NUMBER='SP_CH4221MEE01',
 VALUE='DIFF BUS_0.22UF',
 PRIM_FILE='./archive_libs/logical/q_cap_diffbus/chips/chips.prt';

PART_NAME
 C886 'Q_CAP_DIFFBUS_C0201-DIFF BUS_0.22UF,6.3V,20%,X6S,SA':;

SECTION_NUMBER 1
 '@T6G_MB_LIB.T6G(SCH_1):PAGE352_I137@PURE_QUANTA.Q_CAP_DIFFBUS(CHIPS)':
 C_PATH='@t6g_mb_lib.t6g(sch_1):page352_i137@pure_quanta.q_cap_diffbus(chips)',
 P_PATH='@t6g_mb_lib.t6g(sch_1):page64_i137@pure_quanta.q_cap_diffbus(chips)',
 PATH='I137',
 DRAWING='@T6G_MB_LIB.T6G(SCH_1):PAGE352',
 PIN_NAMES_ROTATE='TRUE',
 TOLERANCE='20%',
 MATERIAL='X6S',
 PHYS_PAGE='64',
 XY='(3825,1575)',
 ROT='2',
 VER='2',
 PACK_TYPE='C0201',
 LOCATION='C886',
 CDS_LIB='pure_quanta',
 CDS_PART_NAME='Q_CAP_DIFFBUS_C0201-DIFF BUS_0.22UF,6.3V,20%,X6S,SA',
 VOLTAGE='6.3V',
 PART_NUMBER='SP_CH4221MEE01',
 VALUE='DIFF BUS_0.22UF',
 PRIM_FILE='./archive_libs/logical/q_cap_diffbus/chips/chips.prt';

PART_NAME
 C887 'Q_CAP_DIFFBUS_C0201-DIFF BUS_0.22UF,6.3V,20%,X6S,SA':;

SECTION_NUMBER 1
 '@T6G_MB_LIB.T6G(SCH_1):PAGE352_I136@PURE_QUANTA.Q_CAP_DIFFBUS(CHIPS)':
 C_PATH='@t6g_mb_lib.t6g(sch_1):page352_i136@pure_quanta.q_cap_diffbus(chips)',
 P_PATH='@t6g_mb_lib.t6g(sch_1):page64_i136@pure_quanta.q_cap_diffbus(chips)',
 PATH='I136',
 DRAWING='@T6G_MB_LIB.T6G(SCH_1):PAGE352',
 PIN_NAMES_ROTATE='TRUE',
 TOLERANCE='20%',
 MATERIAL='X6S',
 PHYS_PAGE='64',
 XY='(3825,1525)',
 ROT='2',
 VER='2',
 PACK_TYPE='C0201',
 LOCATION='C887',
 CDS_LIB='pure_quanta',
 CDS_PART_NAME='Q_CAP_DIFFBUS_C0201-DIFF BUS_0.22UF,6.3V,20%,X6S,SA',
 VOLTAGE='6.3V',
 PART_NUMBER='SP_CH4221MEE01',
 VALUE='DIFF BUS_0.22UF',
 PRIM_FILE='./archive_libs/logical/q_cap_diffbus/chips/chips.prt';

PART_NAME
 C888 'Q_CAP_DIFFBUS_C0201-DIFF BUS_0.22UF,6.3V,20%,X6S,SA':;

SECTION_NUMBER 1
 '@T6G_MB_LIB.T6G(SCH_1):PAGE352_I135@PURE_QUANTA.Q_CAP_DIFFBUS(CHIPS)':
 C_PATH='@t6g_mb_lib.t6g(sch_1):page352_i135@pure_quanta.q_cap_diffbus(chips)',
 P_PATH='@t6g_mb_lib.t6g(sch_1):page64_i135@pure_quanta.q_cap_diffbus(chips)',
 PATH='I135',
 DRAWING='@T6G_MB_LIB.T6G(SCH_1):PAGE352',
 PIN_NAMES_ROTATE='TRUE',
 TOLERANCE='20%',
 MATERIAL='X6S',
 PHYS_PAGE='64',
 XY='(3825,1375)',
 ROT='2',
 VER='2',
 PACK_TYPE='C0201',
 LOCATION='C888',
 CDS_LIB='pure_quanta',
 CDS_PART_NAME='Q_CAP_DIFFBUS_C0201-DIFF BUS_0.22UF,6.3V,20%,X6S,SA',
 VOLTAGE='6.3V',
 PART_NUMBER='SP_CH4221MEE01',
 VALUE='DIFF BUS_0.22UF',
 PRIM_FILE='./archive_libs/logical/q_cap_diffbus/chips/chips.prt';

PART_NAME
 C889 'Q_CAP_DIFFBUS_C0201-DIFF BUS_0.22UF,6.3V,20%,X6S,SA':;

SECTION_NUMBER 1
 '@T6G_MB_LIB.T6G(SCH_1):PAGE352_I134@PURE_QUANTA.Q_CAP_DIFFBUS(CHIPS)':
 C_PATH='@t6g_mb_lib.t6g(sch_1):page352_i134@pure_quanta.q_cap_diffbus(chips)',
 P_PATH='@t6g_mb_lib.t6g(sch_1):page64_i134@pure_quanta.q_cap_diffbus(chips)',
 PATH='I134',
 DRAWING='@T6G_MB_LIB.T6G(SCH_1):PAGE352',
 PIN_NAMES_ROTATE='TRUE',
 TOLERANCE='20%',
 MATERIAL='X6S',
 PHYS_PAGE='64',
 XY='(3825,1325)',
 ROT='2',
 VER='2',
 PACK_TYPE='C0201',
 LOCATION='C889',
 CDS_LIB='pure_quanta',
 CDS_PART_NAME='Q_CAP_DIFFBUS_C0201-DIFF BUS_0.22UF,6.3V,20%,X6S,SA',
 VOLTAGE='6.3V',
 PART_NUMBER='SP_CH4221MEE01',
 VALUE='DIFF BUS_0.22UF',
 PRIM_FILE='./archive_libs/logical/q_cap_diffbus/chips/chips.prt';

PART_NAME
 C890 'Q_CAP_DIFFBUS_C0201-DIFF BUS_0.22UF,6.3V,20%,X6S,SA':;

SECTION_NUMBER 1
 '@T6G_MB_LIB.T6G(SCH_1):PAGE352_I133@PURE_QUANTA.Q_CAP_DIFFBUS(CHIPS)':
 C_PATH='@t6g_mb_lib.t6g(sch_1):page352_i133@pure_quanta.q_cap_diffbus(chips)',
 P_PATH='@t6g_mb_lib.t6g(sch_1):page64_i133@pure_quanta.q_cap_diffbus(chips)',
 PATH='I133',
 DRAWING='@T6G_MB_LIB.T6G(SCH_1):PAGE352',
 PIN_NAMES_ROTATE='TRUE',
 TOLERANCE='20%',
 MATERIAL='X6S',
 PHYS_PAGE='64',
 XY='(3825,1175)',
 ROT='2',
 VER='2',
 PACK_TYPE='C0201',
 LOCATION='C890',
 CDS_LIB='pure_quanta',
 CDS_PART_NAME='Q_CAP_DIFFBUS_C0201-DIFF BUS_0.22UF,6.3V,20%,X6S,SA',
 VOLTAGE='6.3V',
 PART_NUMBER='SP_CH4221MEE01',
 VALUE='DIFF BUS_0.22UF',
 PRIM_FILE='./archive_libs/logical/q_cap_diffbus/chips/chips.prt';

PART_NAME
 C891 'Q_CAP_DIFFBUS_C0201-DIFF BUS_0.22UF,6.3V,20%,X6S,SA':;

SECTION_NUMBER 1
 '@T6G_MB_LIB.T6G(SCH_1):PAGE352_I132@PURE_QUANTA.Q_CAP_DIFFBUS(CHIPS)':
 C_PATH='@t6g_mb_lib.t6g(sch_1):page352_i132@pure_quanta.q_cap_diffbus(chips)',
 P_PATH='@t6g_mb_lib.t6g(sch_1):page64_i132@pure_quanta.q_cap_diffbus(chips)',
 PATH='I132',
 DRAWING='@T6G_MB_LIB.T6G(SCH_1):PAGE352',
 PIN_NAMES_ROTATE='TRUE',
 TOLERANCE='20%',
 MATERIAL='X6S',
 PHYS_PAGE='64',
 XY='(3825,1125)',
 ROT='2',
 VER='2',
 PACK_TYPE='C0201',
 LOCATION='C891',
 CDS_LIB='pure_quanta',
 CDS_PART_NAME='Q_CAP_DIFFBUS_C0201-DIFF BUS_0.22UF,6.3V,20%,X6S,SA',
 VOLTAGE='6.3V',
 PART_NUMBER='SP_CH4221MEE01',
 VALUE='DIFF BUS_0.22UF',
 PRIM_FILE='./archive_libs/logical/q_cap_diffbus/chips/chips.prt';

PART_NAME
 C892 'Q_CAP_DIFFBUS_C0201-DIFF BUS_0.22UF,6.3V,20%,X6S,SA':;

SECTION_NUMBER 1
 '@T6G_MB_LIB.T6G(SCH_1):PAGE352_I127@PURE_QUANTA.Q_CAP_DIFFBUS(CHIPS)':
 C_PATH='@t6g_mb_lib.t6g(sch_1):page352_i127@pure_quanta.q_cap_diffbus(chips)',
 P_PATH='@t6g_mb_lib.t6g(sch_1):page64_i127@pure_quanta.q_cap_diffbus(chips)',
 PATH='I127',
 DRAWING='@T6G_MB_LIB.T6G(SCH_1):PAGE352',
 PIN_NAMES_ROTATE='TRUE',
 TOLERANCE='20%',
 MATERIAL='X6S',
 PHYS_PAGE='64',
 XY='(3825,975)',
 ROT='2',
 VER='2',
 PACK_TYPE='C0201',
 LOCATION='C892',
 CDS_LIB='pure_quanta',
 CDS_PART_NAME='Q_CAP_DIFFBUS_C0201-DIFF BUS_0.22UF,6.3V,20%,X6S,SA',
 VOLTAGE='6.3V',
 PART_NUMBER='SP_CH4221MEE01',
 VALUE='DIFF BUS_0.22UF',
 PRIM_FILE='./archive_libs/logical/q_cap_diffbus/chips/chips.prt';

PART_NAME
 C893 'Q_CAP_DIFFBUS_C0201-DIFF BUS_0.22UF,6.3V,20%,X6S,SA':;

SECTION_NUMBER 1
 '@T6G_MB_LIB.T6G(SCH_1):PAGE352_I128@PURE_QUANTA.Q_CAP_DIFFBUS(CHIPS)':
 C_PATH='@t6g_mb_lib.t6g(sch_1):page352_i128@pure_quanta.q_cap_diffbus(chips)',
 P_PATH='@t6g_mb_lib.t6g(sch_1):page64_i128@pure_quanta.q_cap_diffbus(chips)',
 PATH='I128',
 DRAWING='@T6G_MB_LIB.T6G(SCH_1):PAGE352',
 PIN_NAMES_ROTATE='TRUE',
 TOLERANCE='20%',
 MATERIAL='X6S',
 PHYS_PAGE='64',
 XY='(3825,925)',
 ROT='2',
 VER='2',
 PACK_TYPE='C0201',
 LOCATION='C893',
 CDS_LIB='pure_quanta',
 CDS_PART_NAME='Q_CAP_DIFFBUS_C0201-DIFF BUS_0.22UF,6.3V,20%,X6S,SA',
 VOLTAGE='6.3V',
 PART_NUMBER='SP_CH4221MEE01',
 VALUE='DIFF BUS_0.22UF',
 PRIM_FILE='./archive_libs/logical/q_cap_diffbus/chips/chips.prt';

PART_NAME
 C894 'Q_CAP_DIFFBUS_C0201-DIFF BUS_0.22UF,6.3V,20%,X6S,SA':;

SECTION_NUMBER 1
 '@T6G_MB_LIB.T6G(SCH_1):PAGE352_I126@PURE_QUANTA.Q_CAP_DIFFBUS(CHIPS)':
 C_PATH='@t6g_mb_lib.t6g(sch_1):page352_i126@pure_quanta.q_cap_diffbus(chips)',
 P_PATH='@t6g_mb_lib.t6g(sch_1):page64_i126@pure_quanta.q_cap_diffbus(chips)',
 PATH='I126',
 DRAWING='@T6G_MB_LIB.T6G(SCH_1):PAGE352',
 PIN_NAMES_ROTATE='TRUE',
 TOLERANCE='20%',
 MATERIAL='X6S',
 PHYS_PAGE='64',
 XY='(3825,775)',
 ROT='2',
 VER='2',
 PACK_TYPE='C0201',
 LOCATION='C894',
 CDS_LIB='pure_quanta',
 CDS_PART_NAME='Q_CAP_DIFFBUS_C0201-DIFF BUS_0.22UF,6.3V,20%,X6S,SA',
 VOLTAGE='6.3V',
 PART_NUMBER='SP_CH4221MEE01',
 VALUE='DIFF BUS_0.22UF',
 PRIM_FILE='./archive_libs/logical/q_cap_diffbus/chips/chips.prt';

PART_NAME
 C895 'Q_CAP_DIFFBUS_C0201-DIFF BUS_0.22UF,6.3V,20%,X6S,SA':;

SECTION_NUMBER 1
 '@T6G_MB_LIB.T6G(SCH_1):PAGE352_I125@PURE_QUANTA.Q_CAP_DIFFBUS(CHIPS)':
 C_PATH='@t6g_mb_lib.t6g(sch_1):page352_i125@pure_quanta.q_cap_diffbus(chips)',
 P_PATH='@t6g_mb_lib.t6g(sch_1):page64_i125@pure_quanta.q_cap_diffbus(chips)',
 PATH='I125',
 DRAWING='@T6G_MB_LIB.T6G(SCH_1):PAGE352',
 PIN_NAMES_ROTATE='TRUE',
 TOLERANCE='20%',
 MATERIAL='X6S',
 PHYS_PAGE='64',
 XY='(3825,725)',
 ROT='2',
 VER='2',
 PACK_TYPE='C0201',
 LOCATION='C895',
 CDS_LIB='pure_quanta',
 CDS_PART_NAME='Q_CAP_DIFFBUS_C0201-DIFF BUS_0.22UF,6.3V,20%,X6S,SA',
 VOLTAGE='6.3V',
 PART_NUMBER='SP_CH4221MEE01',
 VALUE='DIFF BUS_0.22UF',
 PRIM_FILE='./archive_libs/logical/q_cap_diffbus/chips/chips.prt';

PART_NAME
 C896 'Q_CAP_DIFFBUS_C0201-DIFF BUS_0.22UF,6.3V,20%,X6S,SA':;

SECTION_NUMBER 1
 '@T6G_MB_LIB.T6G(SCH_1):PAGE352_I124@PURE_QUANTA.Q_CAP_DIFFBUS(CHIPS)':
 C_PATH='@t6g_mb_lib.t6g(sch_1):page352_i124@pure_quanta.q_cap_diffbus(chips)',
 P_PATH='@t6g_mb_lib.t6g(sch_1):page64_i124@pure_quanta.q_cap_diffbus(chips)',
 PATH='I124',
 DRAWING='@T6G_MB_LIB.T6G(SCH_1):PAGE352',
 PIN_NAMES_ROTATE='TRUE',
 TOLERANCE='20%',
 MATERIAL='X6S',
 PHYS_PAGE='64',
 XY='(3825,575)',
 ROT='2',
 VER='2',
 PACK_TYPE='C0201',
 LOCATION='C896',
 CDS_LIB='pure_quanta',
 CDS_PART_NAME='Q_CAP_DIFFBUS_C0201-DIFF BUS_0.22UF,6.3V,20%,X6S,SA',
 VOLTAGE='6.3V',
 PART_NUMBER='SP_CH4221MEE01',
 VALUE='DIFF BUS_0.22UF',
 PRIM_FILE='./archive_libs/logical/q_cap_diffbus/chips/chips.prt';

PART_NAME
 C897 'Q_CAP_DIFFBUS_C0201-DIFF BUS_0.22UF,6.3V,20%,X6S,SA':;

SECTION_NUMBER 1
 '@T6G_MB_LIB.T6G(SCH_1):PAGE352_I123@PURE_QUANTA.Q_CAP_DIFFBUS(CHIPS)':
 C_PATH='@t6g_mb_lib.t6g(sch_1):page352_i123@pure_quanta.q_cap_diffbus(chips)',
 P_PATH='@t6g_mb_lib.t6g(sch_1):page64_i123@pure_quanta.q_cap_diffbus(chips)',
 PATH='I123',
 DRAWING='@T6G_MB_LIB.T6G(SCH_1):PAGE352',
 PIN_NAMES_ROTATE='TRUE',
 TOLERANCE='20%',
 MATERIAL='X6S',
 PHYS_PAGE='64',
 XY='(3825,525)',
 ROT='2',
 VER='2',
 PACK_TYPE='C0201',
 LOCATION='C897',
 CDS_LIB='pure_quanta',
 CDS_PART_NAME='Q_CAP_DIFFBUS_C0201-DIFF BUS_0.22UF,6.3V,20%,X6S,SA',
 VOLTAGE='6.3V',
 PART_NUMBER='SP_CH4221MEE01',
 VALUE='DIFF BUS_0.22UF',
 PRIM_FILE='./archive_libs/logical/q_cap_diffbus/chips/chips.prt';

PART_NAME
 C898 'Q_CAP_DIFFBUS_C0201-DIFF BUS_0.22UF,6.3V,20%,X6S,SA':;

SECTION_NUMBER 1
 '@T6G_MB_LIB.T6G(SCH_1):PAGE352_I206@PURE_QUANTA.Q_CAP_DIFFBUS(CHIPS)':
 C_PATH='@t6g_mb_lib.t6g(sch_1):page352_i206@pure_quanta.q_cap_diffbus(chips)',
 P_PATH='@t6g_mb_lib.t6g(sch_1):page64_i206@pure_quanta.q_cap_diffbus(chips)',
 PATH='I206',
 DRAWING='@T6G_MB_LIB.T6G(SCH_1):PAGE352',
 PIN_NAMES_ROTATE='TRUE',
 TOLERANCE='20%',
 MATERIAL='X6S',
 PHYS_PAGE='64',
 XY='(3825,375)',
 ROT='2',
 VER='2',
 PACK_TYPE='C0201',
 LOCATION='C898',
 CDS_LIB='pure_quanta',
 CDS_PART_NAME='Q_CAP_DIFFBUS_C0201-DIFF BUS_0.22UF,6.3V,20%,X6S,SA',
 VOLTAGE='6.3V',
 PART_NUMBER='SP_CH4221MEE01',
 VALUE='DIFF BUS_0.22UF',
 PRIM_FILE='./archive_libs/logical/q_cap_diffbus/chips/chips.prt';

PART_NAME
 C899 'Q_CAP_DIFFBUS_C0201-DIFF BUS_0.22UF,6.3V,20%,X6S,SA':;

SECTION_NUMBER 1
 '@T6G_MB_LIB.T6G(SCH_1):PAGE352_I122@PURE_QUANTA.Q_CAP_DIFFBUS(CHIPS)':
 C_PATH='@t6g_mb_lib.t6g(sch_1):page352_i122@pure_quanta.q_cap_diffbus(chips)',
 P_PATH='@t6g_mb_lib.t6g(sch_1):page64_i122@pure_quanta.q_cap_diffbus(chips)',
 PATH='I122',
 DRAWING='@T6G_MB_LIB.T6G(SCH_1):PAGE352',
 PIN_NAMES_ROTATE='TRUE',
 TOLERANCE='20%',
 MATERIAL='X6S',
 PHYS_PAGE='64',
 XY='(3825,325)',
 ROT='2',
 VER='2',
 PACK_TYPE='C0201',
 LOCATION='C899',
 CDS_LIB='pure_quanta',
 CDS_PART_NAME='Q_CAP_DIFFBUS_C0201-DIFF BUS_0.22UF,6.3V,20%,X6S,SA',
 VOLTAGE='6.3V',
 PART_NUMBER='SP_CH4221MEE01',
 VALUE='DIFF BUS_0.22UF',
 PRIM_FILE='./archive_libs/logical/q_cap_diffbus/chips/chips.prt';

PART_NAME
 C900 'Q_CAP_DIFFBUS_C0201-DIFF BUS_0.22UF,6.3V,20%,X6S,SA':;

SECTION_NUMBER 1
 '@T6G_MB_LIB.T6G(SCH_1):PAGE352_I121@PURE_QUANTA.Q_CAP_DIFFBUS(CHIPS)':
 C_PATH='@t6g_mb_lib.t6g(sch_1):page352_i121@pure_quanta.q_cap_diffbus(chips)',
 P_PATH='@t6g_mb_lib.t6g(sch_1):page64_i121@pure_quanta.q_cap_diffbus(chips)',
 PATH='I121',
 DRAWING='@T6G_MB_LIB.T6G(SCH_1):PAGE352',
 PIN_NAMES_ROTATE='TRUE',
 TOLERANCE='20%',
 MATERIAL='X6S',
 PHYS_PAGE='64',
 XY='(3825,175)',
 ROT='2',
 VER='2',
 PACK_TYPE='C0201',
 LOCATION='C900',
 CDS_LIB='pure_quanta',
 CDS_PART_NAME='Q_CAP_DIFFBUS_C0201-DIFF BUS_0.22UF,6.3V,20%,X6S,SA',
 VOLTAGE='6.3V',
 PART_NUMBER='SP_CH4221MEE01',
 VALUE='DIFF BUS_0.22UF',
 PRIM_FILE='./archive_libs/logical/q_cap_diffbus/chips/chips.prt';

PART_NAME
 C901 'Q_CAP_DIFFBUS_C0201-DIFF BUS_0.22UF,6.3V,20%,X6S,SA':;

SECTION_NUMBER 1
 '@T6G_MB_LIB.T6G(SCH_1):PAGE352_I120@PURE_QUANTA.Q_CAP_DIFFBUS(CHIPS)':
 C_PATH='@t6g_mb_lib.t6g(sch_1):page352_i120@pure_quanta.q_cap_diffbus(chips)',
 P_PATH='@t6g_mb_lib.t6g(sch_1):page64_i120@pure_quanta.q_cap_diffbus(chips)',
 PATH='I120',
 DRAWING='@T6G_MB_LIB.T6G(SCH_1):PAGE352',
 PIN_NAMES_ROTATE='TRUE',
 TOLERANCE='20%',
 MATERIAL='X6S',
 PHYS_PAGE='64',
 XY='(3825,125)',
 ROT='2',
 VER='2',
 PACK_TYPE='C0201',
 LOCATION='C901',
 CDS_LIB='pure_quanta',
 CDS_PART_NAME='Q_CAP_DIFFBUS_C0201-DIFF BUS_0.22UF,6.3V,20%,X6S,SA',
 VOLTAGE='6.3V',
 PART_NUMBER='SP_CH4221MEE01',
 VALUE='DIFF BUS_0.22UF',
 PRIM_FILE='./archive_libs/logical/q_cap_diffbus/chips/chips.prt';

PART_NAME
 C902 'Q_CAP_DIFFBUS_C0201-DIFF BUS_0.22UF,6.3V,20%,X6S,SA':;

SECTION_NUMBER 1
 '@T6G_MB_LIB.T6G(SCH_1):PAGE351_I68@PURE_QUANTA.Q_CAP_DIFFBUS(CHIPS)':
 C_PATH='@t6g_mb_lib.t6g(sch_1):page351_i68@pure_quanta.q_cap_diffbus(chips)',
 P_PATH='@t6g_mb_lib.t6g(sch_1):page63_i68@pure_quanta.q_cap_diffbus(chips)',
 PATH='I68',
 DRAWING='@T6G_MB_LIB.T6G(SCH_1):PAGE351',
 PIN_NAMES_ROTATE='TRUE',
 TOLERANCE='20%',
 MATERIAL='X6S',
 PHYS_PAGE='63',
 XY='(-575,3750)',
 ROT='2',
 VER='2',
 PACK_TYPE='C0201',
 LOCATION='C902',
 CDS_LIB='pure_quanta',
 CDS_PART_NAME='Q_CAP_DIFFBUS_C0201-DIFF BUS_0.22UF,6.3V,20%,X6S,SA',
 VOLTAGE='6.3V',
 PART_NUMBER='SP_CH4221MEE01',
 VALUE='DIFF BUS_0.22UF',
 PRIM_FILE='./archive_libs/logical/q_cap_diffbus/chips/chips.prt';

PART_NAME
 C903 'Q_CAP_DIFFBUS_C0201-DIFF BUS_0.22UF,6.3V,20%,X6S,SA':;

SECTION_NUMBER 1
 '@T6G_MB_LIB.T6G(SCH_1):PAGE351_I67@PURE_QUANTA.Q_CAP_DIFFBUS(CHIPS)':
 C_PATH='@t6g_mb_lib.t6g(sch_1):page351_i67@pure_quanta.q_cap_diffbus(chips)',
 P_PATH='@t6g_mb_lib.t6g(sch_1):page63_i67@pure_quanta.q_cap_diffbus(chips)',
 PATH='I67',
 DRAWING='@T6G_MB_LIB.T6G(SCH_1):PAGE351',
 PIN_NAMES_ROTATE='TRUE',
 TOLERANCE='20%',
 MATERIAL='X6S',
 PHYS_PAGE='63',
 XY='(-575,3700)',
 ROT='2',
 VER='2',
 PACK_TYPE='C0201',
 LOCATION='C903',
 CDS_LIB='pure_quanta',
 CDS_PART_NAME='Q_CAP_DIFFBUS_C0201-DIFF BUS_0.22UF,6.3V,20%,X6S,SA',
 VOLTAGE='6.3V',
 PART_NUMBER='SP_CH4221MEE01',
 VALUE='DIFF BUS_0.22UF',
 PRIM_FILE='./archive_libs/logical/q_cap_diffbus/chips/chips.prt';

PART_NAME
 C904 'Q_CAP_DIFFBUS_C0201-DIFF BUS_0.22UF,6.3V,20%,X6S,SA':;

SECTION_NUMBER 1
 '@T6G_MB_LIB.T6G(SCH_1):PAGE351_I66@PURE_QUANTA.Q_CAP_DIFFBUS(CHIPS)':
 C_PATH='@t6g_mb_lib.t6g(sch_1):page351_i66@pure_quanta.q_cap_diffbus(chips)',
 P_PATH='@t6g_mb_lib.t6g(sch_1):page63_i66@pure_quanta.q_cap_diffbus(chips)',
 PATH='I66',
 DRAWING='@T6G_MB_LIB.T6G(SCH_1):PAGE351',
 PIN_NAMES_ROTATE='TRUE',
 TOLERANCE='20%',
 MATERIAL='X6S',
 PHYS_PAGE='63',
 XY='(-575,3550)',
 ROT='2',
 VER='2',
 PACK_TYPE='C0201',
 LOCATION='C904',
 CDS_LIB='pure_quanta',
 CDS_PART_NAME='Q_CAP_DIFFBUS_C0201-DIFF BUS_0.22UF,6.3V,20%,X6S,SA',
 VOLTAGE='6.3V',
 PART_NUMBER='SP_CH4221MEE01',
 VALUE='DIFF BUS_0.22UF',
 PRIM_FILE='./archive_libs/logical/q_cap_diffbus/chips/chips.prt';

PART_NAME
 C905 'Q_CAP_DIFFBUS_C0201-DIFF BUS_0.22UF,6.3V,20%,X6S,SA':;

SECTION_NUMBER 1
 '@T6G_MB_LIB.T6G(SCH_1):PAGE351_I65@PURE_QUANTA.Q_CAP_DIFFBUS(CHIPS)':
 C_PATH='@t6g_mb_lib.t6g(sch_1):page351_i65@pure_quanta.q_cap_diffbus(chips)',
 P_PATH='@t6g_mb_lib.t6g(sch_1):page63_i65@pure_quanta.q_cap_diffbus(chips)',
 PATH='I65',
 DRAWING='@T6G_MB_LIB.T6G(SCH_1):PAGE351',
 PIN_NAMES_ROTATE='TRUE',
 TOLERANCE='20%',
 MATERIAL='X6S',
 PHYS_PAGE='63',
 XY='(-575,3500)',
 ROT='2',
 VER='2',
 PACK_TYPE='C0201',
 LOCATION='C905',
 CDS_LIB='pure_quanta',
 CDS_PART_NAME='Q_CAP_DIFFBUS_C0201-DIFF BUS_0.22UF,6.3V,20%,X6S,SA',
 VOLTAGE='6.3V',
 PART_NUMBER='SP_CH4221MEE01',
 VALUE='DIFF BUS_0.22UF',
 PRIM_FILE='./archive_libs/logical/q_cap_diffbus/chips/chips.prt';

PART_NAME
 C906 'Q_CAP_DIFFBUS_C0201-DIFF BUS_0.22UF,6.3V,20%,X6S,SA':;

SECTION_NUMBER 1
 '@T6G_MB_LIB.T6G(SCH_1):PAGE351_I63@PURE_QUANTA.Q_CAP_DIFFBUS(CHIPS)':
 C_PATH='@t6g_mb_lib.t6g(sch_1):page351_i63@pure_quanta.q_cap_diffbus(chips)',
 P_PATH='@t6g_mb_lib.t6g(sch_1):page63_i63@pure_quanta.q_cap_diffbus(chips)',
 PATH='I63',
 DRAWING='@T6G_MB_LIB.T6G(SCH_1):PAGE351',
 PIN_NAMES_ROTATE='TRUE',
 TOLERANCE='20%',
 MATERIAL='X6S',
 PHYS_PAGE='63',
 XY='(-575,3350)',
 ROT='2',
 VER='2',
 PACK_TYPE='C0201',
 LOCATION='C906',
 CDS_LIB='pure_quanta',
 CDS_PART_NAME='Q_CAP_DIFFBUS_C0201-DIFF BUS_0.22UF,6.3V,20%,X6S,SA',
 VOLTAGE='6.3V',
 PART_NUMBER='SP_CH4221MEE01',
 VALUE='DIFF BUS_0.22UF',
 PRIM_FILE='./archive_libs/logical/q_cap_diffbus/chips/chips.prt';

PART_NAME
 C907 'Q_CAP_DIFFBUS_C0201-DIFF BUS_0.22UF,6.3V,20%,X6S,SA':;

SECTION_NUMBER 1
 '@T6G_MB_LIB.T6G(SCH_1):PAGE351_I64@PURE_QUANTA.Q_CAP_DIFFBUS(CHIPS)':
 C_PATH='@t6g_mb_lib.t6g(sch_1):page351_i64@pure_quanta.q_cap_diffbus(chips)',
 P_PATH='@t6g_mb_lib.t6g(sch_1):page63_i64@pure_quanta.q_cap_diffbus(chips)',
 PATH='I64',
 DRAWING='@T6G_MB_LIB.T6G(SCH_1):PAGE351',
 PIN_NAMES_ROTATE='TRUE',
 TOLERANCE='20%',
 MATERIAL='X6S',
 PHYS_PAGE='63',
 XY='(-575,3300)',
 ROT='2',
 VER='2',
 PACK_TYPE='C0201',
 LOCATION='C907',
 CDS_LIB='pure_quanta',
 CDS_PART_NAME='Q_CAP_DIFFBUS_C0201-DIFF BUS_0.22UF,6.3V,20%,X6S,SA',
 VOLTAGE='6.3V',
 PART_NUMBER='SP_CH4221MEE01',
 VALUE='DIFF BUS_0.22UF',
 PRIM_FILE='./archive_libs/logical/q_cap_diffbus/chips/chips.prt';

PART_NAME
 C908 'Q_CAP_DIFFBUS_C0201-DIFF BUS_0.22UF,6.3V,20%,X6S,SA':;

SECTION_NUMBER 1
 '@T6G_MB_LIB.T6G(SCH_1):PAGE351_I62@PURE_QUANTA.Q_CAP_DIFFBUS(CHIPS)':
 C_PATH='@t6g_mb_lib.t6g(sch_1):page351_i62@pure_quanta.q_cap_diffbus(chips)',
 P_PATH='@t6g_mb_lib.t6g(sch_1):page63_i62@pure_quanta.q_cap_diffbus(chips)',
 PATH='I62',
 DRAWING='@T6G_MB_LIB.T6G(SCH_1):PAGE351',
 PIN_NAMES_ROTATE='TRUE',
 TOLERANCE='20%',
 MATERIAL='X6S',
 PHYS_PAGE='63',
 XY='(-575,3150)',
 ROT='2',
 VER='2',
 PACK_TYPE='C0201',
 LOCATION='C908',
 CDS_LIB='pure_quanta',
 CDS_PART_NAME='Q_CAP_DIFFBUS_C0201-DIFF BUS_0.22UF,6.3V,20%,X6S,SA',
 VOLTAGE='6.3V',
 PART_NUMBER='SP_CH4221MEE01',
 VALUE='DIFF BUS_0.22UF',
 PRIM_FILE='./archive_libs/logical/q_cap_diffbus/chips/chips.prt';

PART_NAME
 C909 'Q_CAP_DIFFBUS_C0201-DIFF BUS_0.22UF,6.3V,20%,X6S,SA':;

SECTION_NUMBER 1
 '@T6G_MB_LIB.T6G(SCH_1):PAGE351_I61@PURE_QUANTA.Q_CAP_DIFFBUS(CHIPS)':
 C_PATH='@t6g_mb_lib.t6g(sch_1):page351_i61@pure_quanta.q_cap_diffbus(chips)',
 P_PATH='@t6g_mb_lib.t6g(sch_1):page63_i61@pure_quanta.q_cap_diffbus(chips)',
 PATH='I61',
 DRAWING='@T6G_MB_LIB.T6G(SCH_1):PAGE351',
 PIN_NAMES_ROTATE='TRUE',
 TOLERANCE='20%',
 MATERIAL='X6S',
 PHYS_PAGE='63',
 XY='(-575,3100)',
 ROT='2',
 VER='2',
 PACK_TYPE='C0201',
 LOCATION='C909',
 CDS_LIB='pure_quanta',
 CDS_PART_NAME='Q_CAP_DIFFBUS_C0201-DIFF BUS_0.22UF,6.3V,20%,X6S,SA',
 VOLTAGE='6.3V',
 PART_NUMBER='SP_CH4221MEE01',
 VALUE='DIFF BUS_0.22UF',
 PRIM_FILE='./archive_libs/logical/q_cap_diffbus/chips/chips.prt';

PART_NAME
 C910 'Q_CAP_DIFFBUS_C0201-DIFF BUS_0.22UF,6.3V,20%,X6S,SA':;

SECTION_NUMBER 1
 '@T6G_MB_LIB.T6G(SCH_1):PAGE351_I60@PURE_QUANTA.Q_CAP_DIFFBUS(CHIPS)':
 C_PATH='@t6g_mb_lib.t6g(sch_1):page351_i60@pure_quanta.q_cap_diffbus(chips)',
 P_PATH='@t6g_mb_lib.t6g(sch_1):page63_i60@pure_quanta.q_cap_diffbus(chips)',
 PATH='I60',
 DRAWING='@T6G_MB_LIB.T6G(SCH_1):PAGE351',
 PIN_NAMES_ROTATE='TRUE',
 TOLERANCE='20%',
 MATERIAL='X6S',
 PHYS_PAGE='63',
 XY='(-575,2950)',
 ROT='2',
 VER='2',
 PACK_TYPE='C0201',
 LOCATION='C910',
 CDS_LIB='pure_quanta',
 CDS_PART_NAME='Q_CAP_DIFFBUS_C0201-DIFF BUS_0.22UF,6.3V,20%,X6S,SA',
 VOLTAGE='6.3V',
 PART_NUMBER='SP_CH4221MEE01',
 VALUE='DIFF BUS_0.22UF',
 PRIM_FILE='./archive_libs/logical/q_cap_diffbus/chips/chips.prt';

PART_NAME
 C911 'Q_CAP_DIFFBUS_C0201-DIFF BUS_0.22UF,6.3V,20%,X6S,SA':;

SECTION_NUMBER 1
 '@T6G_MB_LIB.T6G(SCH_1):PAGE351_I59@PURE_QUANTA.Q_CAP_DIFFBUS(CHIPS)':
 C_PATH='@t6g_mb_lib.t6g(sch_1):page351_i59@pure_quanta.q_cap_diffbus(chips)',
 P_PATH='@t6g_mb_lib.t6g(sch_1):page63_i59@pure_quanta.q_cap_diffbus(chips)',
 PATH='I59',
 DRAWING='@T6G_MB_LIB.T6G(SCH_1):PAGE351',
 PIN_NAMES_ROTATE='TRUE',
 TOLERANCE='20%',
 MATERIAL='X6S',
 PHYS_PAGE='63',
 XY='(-575,2900)',
 ROT='2',
 VER='2',
 PACK_TYPE='C0201',
 LOCATION='C911',
 CDS_LIB='pure_quanta',
 CDS_PART_NAME='Q_CAP_DIFFBUS_C0201-DIFF BUS_0.22UF,6.3V,20%,X6S,SA',
 VOLTAGE='6.3V',
 PART_NUMBER='SP_CH4221MEE01',
 VALUE='DIFF BUS_0.22UF',
 PRIM_FILE='./archive_libs/logical/q_cap_diffbus/chips/chips.prt';

PART_NAME
 C912 'Q_CAP_DIFFBUS_C0201-DIFF BUS_0.22UF,6.3V,20%,X6S,SA':;

SECTION_NUMBER 1
 '@T6G_MB_LIB.T6G(SCH_1):PAGE351_I58@PURE_QUANTA.Q_CAP_DIFFBUS(CHIPS)':
 C_PATH='@t6g_mb_lib.t6g(sch_1):page351_i58@pure_quanta.q_cap_diffbus(chips)',
 P_PATH='@t6g_mb_lib.t6g(sch_1):page63_i58@pure_quanta.q_cap_diffbus(chips)',
 PATH='I58',
 DRAWING='@T6G_MB_LIB.T6G(SCH_1):PAGE351',
 PIN_NAMES_ROTATE='TRUE',
 TOLERANCE='20%',
 MATERIAL='X6S',
 PHYS_PAGE='63',
 XY='(-575,2750)',
 ROT='2',
 VER='2',
 PACK_TYPE='C0201',
 LOCATION='C912',
 CDS_LIB='pure_quanta',
 CDS_PART_NAME='Q_CAP_DIFFBUS_C0201-DIFF BUS_0.22UF,6.3V,20%,X6S,SA',
 VOLTAGE='6.3V',
 PART_NUMBER='SP_CH4221MEE01',
 VALUE='DIFF BUS_0.22UF',
 PRIM_FILE='./archive_libs/logical/q_cap_diffbus/chips/chips.prt';

PART_NAME
 C913 'Q_CAP_DIFFBUS_C0201-DIFF BUS_0.22UF,6.3V,20%,X6S,SA':;

SECTION_NUMBER 1
 '@T6G_MB_LIB.T6G(SCH_1):PAGE351_I57@PURE_QUANTA.Q_CAP_DIFFBUS(CHIPS)':
 C_PATH='@t6g_mb_lib.t6g(sch_1):page351_i57@pure_quanta.q_cap_diffbus(chips)',
 P_PATH='@t6g_mb_lib.t6g(sch_1):page63_i57@pure_quanta.q_cap_diffbus(chips)',
 PATH='I57',
 DRAWING='@T6G_MB_LIB.T6G(SCH_1):PAGE351',
 PIN_NAMES_ROTATE='TRUE',
 TOLERANCE='20%',
 MATERIAL='X6S',
 PHYS_PAGE='63',
 XY='(-575,2700)',
 ROT='2',
 VER='2',
 PACK_TYPE='C0201',
 LOCATION='C913',
 CDS_LIB='pure_quanta',
 CDS_PART_NAME='Q_CAP_DIFFBUS_C0201-DIFF BUS_0.22UF,6.3V,20%,X6S,SA',
 VOLTAGE='6.3V',
 PART_NUMBER='SP_CH4221MEE01',
 VALUE='DIFF BUS_0.22UF',
 PRIM_FILE='./archive_libs/logical/q_cap_diffbus/chips/chips.prt';

PART_NAME
 C914 'Q_CAP_DIFFBUS_C0201-DIFF BUS_0.22UF,6.3V,20%,X6S,SA':;

SECTION_NUMBER 1
 '@T6G_MB_LIB.T6G(SCH_1):PAGE351_I56@PURE_QUANTA.Q_CAP_DIFFBUS(CHIPS)':
 C_PATH='@t6g_mb_lib.t6g(sch_1):page351_i56@pure_quanta.q_cap_diffbus(chips)',
 P_PATH='@t6g_mb_lib.t6g(sch_1):page63_i56@pure_quanta.q_cap_diffbus(chips)',
 PATH='I56',
 DRAWING='@T6G_MB_LIB.T6G(SCH_1):PAGE351',
 PIN_NAMES_ROTATE='TRUE',
 TOLERANCE='20%',
 MATERIAL='X6S',
 PHYS_PAGE='63',
 XY='(-575,2550)',
 ROT='2',
 VER='2',
 PACK_TYPE='C0201',
 LOCATION='C914',
 CDS_LIB='pure_quanta',
 CDS_PART_NAME='Q_CAP_DIFFBUS_C0201-DIFF BUS_0.22UF,6.3V,20%,X6S,SA',
 VOLTAGE='6.3V',
 PART_NUMBER='SP_CH4221MEE01',
 VALUE='DIFF BUS_0.22UF',
 PRIM_FILE='./archive_libs/logical/q_cap_diffbus/chips/chips.prt';

PART_NAME
 C915 'Q_CAP_DIFFBUS_C0201-DIFF BUS_0.22UF,6.3V,20%,X6S,SA':;

SECTION_NUMBER 1
 '@T6G_MB_LIB.T6G(SCH_1):PAGE351_I55@PURE_QUANTA.Q_CAP_DIFFBUS(CHIPS)':
 C_PATH='@t6g_mb_lib.t6g(sch_1):page351_i55@pure_quanta.q_cap_diffbus(chips)',
 P_PATH='@t6g_mb_lib.t6g(sch_1):page63_i55@pure_quanta.q_cap_diffbus(chips)',
 PATH='I55',
 DRAWING='@T6G_MB_LIB.T6G(SCH_1):PAGE351',
 PIN_NAMES_ROTATE='TRUE',
 TOLERANCE='20%',
 MATERIAL='X6S',
 PHYS_PAGE='63',
 XY='(-575,2500)',
 ROT='2',
 VER='2',
 PACK_TYPE='C0201',
 LOCATION='C915',
 CDS_LIB='pure_quanta',
 CDS_PART_NAME='Q_CAP_DIFFBUS_C0201-DIFF BUS_0.22UF,6.3V,20%,X6S,SA',
 VOLTAGE='6.3V',
 PART_NUMBER='SP_CH4221MEE01',
 VALUE='DIFF BUS_0.22UF',
 PRIM_FILE='./archive_libs/logical/q_cap_diffbus/chips/chips.prt';

PART_NAME
 C916 'Q_CAP_DIFFBUS_C0201-DIFF BUS_0.22UF,6.3V,20%,X6S,SA':;

SECTION_NUMBER 1
 '@T6G_MB_LIB.T6G(SCH_1):PAGE351_I53@PURE_QUANTA.Q_CAP_DIFFBUS(CHIPS)':
 C_PATH='@t6g_mb_lib.t6g(sch_1):page351_i53@pure_quanta.q_cap_diffbus(chips)',
 P_PATH='@t6g_mb_lib.t6g(sch_1):page63_i53@pure_quanta.q_cap_diffbus(chips)',
 PATH='I53',
 DRAWING='@T6G_MB_LIB.T6G(SCH_1):PAGE351',
 PIN_NAMES_ROTATE='TRUE',
 TOLERANCE='20%',
 MATERIAL='X6S',
 PHYS_PAGE='63',
 XY='(-575,2350)',
 ROT='2',
 VER='2',
 PACK_TYPE='C0201',
 LOCATION='C916',
 CDS_LIB='pure_quanta',
 CDS_PART_NAME='Q_CAP_DIFFBUS_C0201-DIFF BUS_0.22UF,6.3V,20%,X6S,SA',
 VOLTAGE='6.3V',
 PART_NUMBER='SP_CH4221MEE01',
 VALUE='DIFF BUS_0.22UF',
 PRIM_FILE='./archive_libs/logical/q_cap_diffbus/chips/chips.prt';

PART_NAME
 C917 'Q_CAP_DIFFBUS_C0201-DIFF BUS_0.22UF,6.3V,20%,X6S,SA':;

SECTION_NUMBER 1
 '@T6G_MB_LIB.T6G(SCH_1):PAGE351_I54@PURE_QUANTA.Q_CAP_DIFFBUS(CHIPS)':
 C_PATH='@t6g_mb_lib.t6g(sch_1):page351_i54@pure_quanta.q_cap_diffbus(chips)',
 P_PATH='@t6g_mb_lib.t6g(sch_1):page63_i54@pure_quanta.q_cap_diffbus(chips)',
 PATH='I54',
 DRAWING='@T6G_MB_LIB.T6G(SCH_1):PAGE351',
 PIN_NAMES_ROTATE='TRUE',
 TOLERANCE='20%',
 MATERIAL='X6S',
 PHYS_PAGE='63',
 XY='(-575,2300)',
 ROT='2',
 VER='2',
 PACK_TYPE='C0201',
 LOCATION='C917',
 CDS_LIB='pure_quanta',
 CDS_PART_NAME='Q_CAP_DIFFBUS_C0201-DIFF BUS_0.22UF,6.3V,20%,X6S,SA',
 VOLTAGE='6.3V',
 PART_NUMBER='SP_CH4221MEE01',
 VALUE='DIFF BUS_0.22UF',
 PRIM_FILE='./archive_libs/logical/q_cap_diffbus/chips/chips.prt';

PART_NAME
 C918 'Q_CAP_DIFFBUS_C0201-DIFF BUS_0.22UF,6.3V,20%,X6S,SA':;

SECTION_NUMBER 1
 '@T6G_MB_LIB.T6G(SCH_1):PAGE351_I35@PURE_QUANTA.Q_CAP_DIFFBUS(CHIPS)':
 C_PATH='@t6g_mb_lib.t6g(sch_1):page351_i35@pure_quanta.q_cap_diffbus(chips)',
 P_PATH='@t6g_mb_lib.t6g(sch_1):page63_i35@pure_quanta.q_cap_diffbus(chips)',
 PATH='I35',
 DRAWING='@T6G_MB_LIB.T6G(SCH_1):PAGE351',
 PIN_NAMES_ROTATE='TRUE',
 TOLERANCE='20%',
 MATERIAL='X6S',
 PHYS_PAGE='63',
 XY='(-575,1775)',
 ROT='2',
 VER='2',
 PACK_TYPE='C0201',
 LOCATION='C918',
 CDS_LIB='pure_quanta',
 CDS_PART_NAME='Q_CAP_DIFFBUS_C0201-DIFF BUS_0.22UF,6.3V,20%,X6S,SA',
 VOLTAGE='6.3V',
 PART_NUMBER='SP_CH4221MEE01',
 VALUE='DIFF BUS_0.22UF',
 PRIM_FILE='./archive_libs/logical/q_cap_diffbus/chips/chips.prt';

PART_NAME
 C919 'Q_CAP_DIFFBUS_C0201-DIFF BUS_0.22UF,6.3V,20%,X6S,SA':;

SECTION_NUMBER 1
 '@T6G_MB_LIB.T6G(SCH_1):PAGE351_I36@PURE_QUANTA.Q_CAP_DIFFBUS(CHIPS)':
 C_PATH='@t6g_mb_lib.t6g(sch_1):page351_i36@pure_quanta.q_cap_diffbus(chips)',
 P_PATH='@t6g_mb_lib.t6g(sch_1):page63_i36@pure_quanta.q_cap_diffbus(chips)',
 PATH='I36',
 DRAWING='@T6G_MB_LIB.T6G(SCH_1):PAGE351',
 PIN_NAMES_ROTATE='TRUE',
 TOLERANCE='20%',
 MATERIAL='X6S',
 PHYS_PAGE='63',
 XY='(-575,1725)',
 ROT='2',
 VER='2',
 PACK_TYPE='C0201',
 LOCATION='C919',
 CDS_LIB='pure_quanta',
 CDS_PART_NAME='Q_CAP_DIFFBUS_C0201-DIFF BUS_0.22UF,6.3V,20%,X6S,SA',
 VOLTAGE='6.3V',
 PART_NUMBER='SP_CH4221MEE01',
 VALUE='DIFF BUS_0.22UF',
 PRIM_FILE='./archive_libs/logical/q_cap_diffbus/chips/chips.prt';

PART_NAME
 C920 'Q_CAP_DIFFBUS_C0201-DIFF BUS_0.22UF,6.3V,20%,X6S,SA':;

SECTION_NUMBER 1
 '@T6G_MB_LIB.T6G(SCH_1):PAGE351_I34@PURE_QUANTA.Q_CAP_DIFFBUS(CHIPS)':
 C_PATH='@t6g_mb_lib.t6g(sch_1):page351_i34@pure_quanta.q_cap_diffbus(chips)',
 P_PATH='@t6g_mb_lib.t6g(sch_1):page63_i34@pure_quanta.q_cap_diffbus(chips)',
 PATH='I34',
 DRAWING='@T6G_MB_LIB.T6G(SCH_1):PAGE351',
 PIN_NAMES_ROTATE='TRUE',
 TOLERANCE='20%',
 MATERIAL='X6S',
 PHYS_PAGE='63',
 XY='(-575,1575)',
 ROT='2',
 VER='2',
 PACK_TYPE='C0201',
 LOCATION='C920',
 CDS_LIB='pure_quanta',
 CDS_PART_NAME='Q_CAP_DIFFBUS_C0201-DIFF BUS_0.22UF,6.3V,20%,X6S,SA',
 VOLTAGE='6.3V',
 PART_NUMBER='SP_CH4221MEE01',
 VALUE='DIFF BUS_0.22UF',
 PRIM_FILE='./archive_libs/logical/q_cap_diffbus/chips/chips.prt';

PART_NAME
 C921 'Q_CAP_DIFFBUS_C0201-DIFF BUS_0.22UF,6.3V,20%,X6S,SA':;

SECTION_NUMBER 1
 '@T6G_MB_LIB.T6G(SCH_1):PAGE351_I33@PURE_QUANTA.Q_CAP_DIFFBUS(CHIPS)':
 C_PATH='@t6g_mb_lib.t6g(sch_1):page351_i33@pure_quanta.q_cap_diffbus(chips)',
 P_PATH='@t6g_mb_lib.t6g(sch_1):page63_i33@pure_quanta.q_cap_diffbus(chips)',
 PATH='I33',
 DRAWING='@T6G_MB_LIB.T6G(SCH_1):PAGE351',
 PIN_NAMES_ROTATE='TRUE',
 TOLERANCE='20%',
 MATERIAL='X6S',
 PHYS_PAGE='63',
 XY='(-575,1525)',
 ROT='2',
 VER='2',
 PACK_TYPE='C0201',
 LOCATION='C921',
 CDS_LIB='pure_quanta',
 CDS_PART_NAME='Q_CAP_DIFFBUS_C0201-DIFF BUS_0.22UF,6.3V,20%,X6S,SA',
 VOLTAGE='6.3V',
 PART_NUMBER='SP_CH4221MEE01',
 VALUE='DIFF BUS_0.22UF',
 PRIM_FILE='./archive_libs/logical/q_cap_diffbus/chips/chips.prt';

PART_NAME
 C922 'Q_CAP_DIFFBUS_C0201-DIFF BUS_0.22UF,6.3V,20%,X6S,SA':;

SECTION_NUMBER 1
 '@T6G_MB_LIB.T6G(SCH_1):PAGE351_I32@PURE_QUANTA.Q_CAP_DIFFBUS(CHIPS)':
 C_PATH='@t6g_mb_lib.t6g(sch_1):page351_i32@pure_quanta.q_cap_diffbus(chips)',
 P_PATH='@t6g_mb_lib.t6g(sch_1):page63_i32@pure_quanta.q_cap_diffbus(chips)',
 PATH='I32',
 DRAWING='@T6G_MB_LIB.T6G(SCH_1):PAGE351',
 PIN_NAMES_ROTATE='TRUE',
 TOLERANCE='20%',
 MATERIAL='X6S',
 PHYS_PAGE='63',
 XY='(-575,1375)',
 ROT='2',
 VER='2',
 PACK_TYPE='C0201',
 LOCATION='C922',
 CDS_LIB='pure_quanta',
 CDS_PART_NAME='Q_CAP_DIFFBUS_C0201-DIFF BUS_0.22UF,6.3V,20%,X6S,SA',
 VOLTAGE='6.3V',
 PART_NUMBER='SP_CH4221MEE01',
 VALUE='DIFF BUS_0.22UF',
 PRIM_FILE='./archive_libs/logical/q_cap_diffbus/chips/chips.prt';

PART_NAME
 C923 'Q_CAP_DIFFBUS_C0201-DIFF BUS_0.22UF,6.3V,20%,X6S,SA':;

SECTION_NUMBER 1
 '@T6G_MB_LIB.T6G(SCH_1):PAGE351_I31@PURE_QUANTA.Q_CAP_DIFFBUS(CHIPS)':
 C_PATH='@t6g_mb_lib.t6g(sch_1):page351_i31@pure_quanta.q_cap_diffbus(chips)',
 P_PATH='@t6g_mb_lib.t6g(sch_1):page63_i31@pure_quanta.q_cap_diffbus(chips)',
 PATH='I31',
 DRAWING='@T6G_MB_LIB.T6G(SCH_1):PAGE351',
 PIN_NAMES_ROTATE='TRUE',
 TOLERANCE='20%',
 MATERIAL='X6S',
 PHYS_PAGE='63',
 XY='(-575,1325)',
 ROT='2',
 VER='2',
 PACK_TYPE='C0201',
 LOCATION='C923',
 CDS_LIB='pure_quanta',
 CDS_PART_NAME='Q_CAP_DIFFBUS_C0201-DIFF BUS_0.22UF,6.3V,20%,X6S,SA',
 VOLTAGE='6.3V',
 PART_NUMBER='SP_CH4221MEE01',
 VALUE='DIFF BUS_0.22UF',
 PRIM_FILE='./archive_libs/logical/q_cap_diffbus/chips/chips.prt';

PART_NAME
 C924 'Q_CAP_DIFFBUS_C0201-DIFF BUS_0.22UF,6.3V,20%,X6S,SA':;

SECTION_NUMBER 1
 '@T6G_MB_LIB.T6G(SCH_1):PAGE351_I30@PURE_QUANTA.Q_CAP_DIFFBUS(CHIPS)':
 C_PATH='@t6g_mb_lib.t6g(sch_1):page351_i30@pure_quanta.q_cap_diffbus(chips)',
 P_PATH='@t6g_mb_lib.t6g(sch_1):page63_i30@pure_quanta.q_cap_diffbus(chips)',
 PATH='I30',
 DRAWING='@T6G_MB_LIB.T6G(SCH_1):PAGE351',
 PIN_NAMES_ROTATE='TRUE',
 TOLERANCE='20%',
 MATERIAL='X6S',
 PHYS_PAGE='63',
 XY='(-575,1175)',
 ROT='2',
 VER='2',
 PACK_TYPE='C0201',
 LOCATION='C924',
 CDS_LIB='pure_quanta',
 CDS_PART_NAME='Q_CAP_DIFFBUS_C0201-DIFF BUS_0.22UF,6.3V,20%,X6S,SA',
 VOLTAGE='6.3V',
 PART_NUMBER='SP_CH4221MEE01',
 VALUE='DIFF BUS_0.22UF',
 PRIM_FILE='./archive_libs/logical/q_cap_diffbus/chips/chips.prt';

PART_NAME
 C925 'Q_CAP_DIFFBUS_C0201-DIFF BUS_0.22UF,6.3V,20%,X6S,SA':;

SECTION_NUMBER 1
 '@T6G_MB_LIB.T6G(SCH_1):PAGE351_I29@PURE_QUANTA.Q_CAP_DIFFBUS(CHIPS)':
 C_PATH='@t6g_mb_lib.t6g(sch_1):page351_i29@pure_quanta.q_cap_diffbus(chips)',
 P_PATH='@t6g_mb_lib.t6g(sch_1):page63_i29@pure_quanta.q_cap_diffbus(chips)',
 PATH='I29',
 DRAWING='@T6G_MB_LIB.T6G(SCH_1):PAGE351',
 PIN_NAMES_ROTATE='TRUE',
 TOLERANCE='20%',
 MATERIAL='X6S',
 PHYS_PAGE='63',
 XY='(-575,1125)',
 ROT='2',
 VER='2',
 PACK_TYPE='C0201',
 LOCATION='C925',
 CDS_LIB='pure_quanta',
 CDS_PART_NAME='Q_CAP_DIFFBUS_C0201-DIFF BUS_0.22UF,6.3V,20%,X6S,SA',
 VOLTAGE='6.3V',
 PART_NUMBER='SP_CH4221MEE01',
 VALUE='DIFF BUS_0.22UF',
 PRIM_FILE='./archive_libs/logical/q_cap_diffbus/chips/chips.prt';

PART_NAME
 C926 'Q_CAP_DIFFBUS_C0201-DIFF BUS_0.22UF,6.3V,20%,X6S,SA':;

SECTION_NUMBER 1
 '@T6G_MB_LIB.T6G(SCH_1):PAGE351_I28@PURE_QUANTA.Q_CAP_DIFFBUS(CHIPS)':
 C_PATH='@t6g_mb_lib.t6g(sch_1):page351_i28@pure_quanta.q_cap_diffbus(chips)',
 P_PATH='@t6g_mb_lib.t6g(sch_1):page63_i28@pure_quanta.q_cap_diffbus(chips)',
 PATH='I28',
 DRAWING='@T6G_MB_LIB.T6G(SCH_1):PAGE351',
 PIN_NAMES_ROTATE='TRUE',
 TOLERANCE='20%',
 MATERIAL='X6S',
 PHYS_PAGE='63',
 XY='(-575,975)',
 ROT='2',
 VER='2',
 PACK_TYPE='C0201',
 LOCATION='C926',
 CDS_LIB='pure_quanta',
 CDS_PART_NAME='Q_CAP_DIFFBUS_C0201-DIFF BUS_0.22UF,6.3V,20%,X6S,SA',
 VOLTAGE='6.3V',
 PART_NUMBER='SP_CH4221MEE01',
 VALUE='DIFF BUS_0.22UF',
 PRIM_FILE='./archive_libs/logical/q_cap_diffbus/chips/chips.prt';

PART_NAME
 C927 'Q_CAP_DIFFBUS_C0201-DIFF BUS_0.22UF,6.3V,20%,X6S,SA':;

SECTION_NUMBER 1
 '@T6G_MB_LIB.T6G(SCH_1):PAGE351_I27@PURE_QUANTA.Q_CAP_DIFFBUS(CHIPS)':
 C_PATH='@t6g_mb_lib.t6g(sch_1):page351_i27@pure_quanta.q_cap_diffbus(chips)',
 P_PATH='@t6g_mb_lib.t6g(sch_1):page63_i27@pure_quanta.q_cap_diffbus(chips)',
 PATH='I27',
 DRAWING='@T6G_MB_LIB.T6G(SCH_1):PAGE351',
 PIN_NAMES_ROTATE='TRUE',
 TOLERANCE='20%',
 MATERIAL='X6S',
 PHYS_PAGE='63',
 XY='(-575,925)',
 ROT='2',
 VER='2',
 PACK_TYPE='C0201',
 LOCATION='C927',
 CDS_LIB='pure_quanta',
 CDS_PART_NAME='Q_CAP_DIFFBUS_C0201-DIFF BUS_0.22UF,6.3V,20%,X6S,SA',
 VOLTAGE='6.3V',
 PART_NUMBER='SP_CH4221MEE01',
 VALUE='DIFF BUS_0.22UF',
 PRIM_FILE='./archive_libs/logical/q_cap_diffbus/chips/chips.prt';

PART_NAME
 C928 'Q_CAP_DIFFBUS_C0201-DIFF BUS_0.22UF,6.3V,20%,X6S,SA':;

SECTION_NUMBER 1
 '@T6G_MB_LIB.T6G(SCH_1):PAGE351_I25@PURE_QUANTA.Q_CAP_DIFFBUS(CHIPS)':
 C_PATH='@t6g_mb_lib.t6g(sch_1):page351_i25@pure_quanta.q_cap_diffbus(chips)',
 P_PATH='@t6g_mb_lib.t6g(sch_1):page63_i25@pure_quanta.q_cap_diffbus(chips)',
 PATH='I25',
 DRAWING='@T6G_MB_LIB.T6G(SCH_1):PAGE351',
 PIN_NAMES_ROTATE='TRUE',
 TOLERANCE='20%',
 MATERIAL='X6S',
 PHYS_PAGE='63',
 XY='(-575,775)',
 ROT='2',
 VER='2',
 PACK_TYPE='C0201',
 LOCATION='C928',
 CDS_LIB='pure_quanta',
 CDS_PART_NAME='Q_CAP_DIFFBUS_C0201-DIFF BUS_0.22UF,6.3V,20%,X6S,SA',
 VOLTAGE='6.3V',
 PART_NUMBER='SP_CH4221MEE01',
 VALUE='DIFF BUS_0.22UF',
 PRIM_FILE='./archive_libs/logical/q_cap_diffbus/chips/chips.prt';

PART_NAME
 C929 'Q_CAP_DIFFBUS_C0201-DIFF BUS_0.22UF,6.3V,20%,X6S,SA':;

SECTION_NUMBER 1
 '@T6G_MB_LIB.T6G(SCH_1):PAGE351_I26@PURE_QUANTA.Q_CAP_DIFFBUS(CHIPS)':
 C_PATH='@t6g_mb_lib.t6g(sch_1):page351_i26@pure_quanta.q_cap_diffbus(chips)',
 P_PATH='@t6g_mb_lib.t6g(sch_1):page63_i26@pure_quanta.q_cap_diffbus(chips)',
 PATH='I26',
 DRAWING='@T6G_MB_LIB.T6G(SCH_1):PAGE351',
 PIN_NAMES_ROTATE='TRUE',
 TOLERANCE='20%',
 MATERIAL='X6S',
 PHYS_PAGE='63',
 XY='(-575,725)',
 ROT='2',
 VER='2',
 PACK_TYPE='C0201',
 LOCATION='C929',
 CDS_LIB='pure_quanta',
 CDS_PART_NAME='Q_CAP_DIFFBUS_C0201-DIFF BUS_0.22UF,6.3V,20%,X6S,SA',
 VOLTAGE='6.3V',
 PART_NUMBER='SP_CH4221MEE01',
 VALUE='DIFF BUS_0.22UF',
 PRIM_FILE='./archive_libs/logical/q_cap_diffbus/chips/chips.prt';

PART_NAME
 C930 'Q_CAP_DIFFBUS_C0201-DIFF BUS_0.22UF,6.3V,20%,X6S,SA':;

SECTION_NUMBER 1
 '@T6G_MB_LIB.T6G(SCH_1):PAGE351_I24@PURE_QUANTA.Q_CAP_DIFFBUS(CHIPS)':
 C_PATH='@t6g_mb_lib.t6g(sch_1):page351_i24@pure_quanta.q_cap_diffbus(chips)',
 P_PATH='@t6g_mb_lib.t6g(sch_1):page63_i24@pure_quanta.q_cap_diffbus(chips)',
 PATH='I24',
 DRAWING='@T6G_MB_LIB.T6G(SCH_1):PAGE351',
 PIN_NAMES_ROTATE='TRUE',
 TOLERANCE='20%',
 MATERIAL='X6S',
 PHYS_PAGE='63',
 XY='(-575,575)',
 ROT='2',
 VER='2',
 PACK_TYPE='C0201',
 LOCATION='C930',
 CDS_LIB='pure_quanta',
 CDS_PART_NAME='Q_CAP_DIFFBUS_C0201-DIFF BUS_0.22UF,6.3V,20%,X6S,SA',
 VOLTAGE='6.3V',
 PART_NUMBER='SP_CH4221MEE01',
 VALUE='DIFF BUS_0.22UF',
 PRIM_FILE='./archive_libs/logical/q_cap_diffbus/chips/chips.prt';

PART_NAME
 C931 'Q_CAP_DIFFBUS_C0201-DIFF BUS_0.22UF,6.3V,20%,X6S,SA':;

SECTION_NUMBER 1
 '@T6G_MB_LIB.T6G(SCH_1):PAGE351_I23@PURE_QUANTA.Q_CAP_DIFFBUS(CHIPS)':
 C_PATH='@t6g_mb_lib.t6g(sch_1):page351_i23@pure_quanta.q_cap_diffbus(chips)',
 P_PATH='@t6g_mb_lib.t6g(sch_1):page63_i23@pure_quanta.q_cap_diffbus(chips)',
 PATH='I23',
 DRAWING='@T6G_MB_LIB.T6G(SCH_1):PAGE351',
 PIN_NAMES_ROTATE='TRUE',
 TOLERANCE='20%',
 MATERIAL='X6S',
 PHYS_PAGE='63',
 XY='(-575,525)',
 ROT='2',
 VER='2',
 PACK_TYPE='C0201',
 LOCATION='C931',
 CDS_LIB='pure_quanta',
 CDS_PART_NAME='Q_CAP_DIFFBUS_C0201-DIFF BUS_0.22UF,6.3V,20%,X6S,SA',
 VOLTAGE='6.3V',
 PART_NUMBER='SP_CH4221MEE01',
 VALUE='DIFF BUS_0.22UF',
 PRIM_FILE='./archive_libs/logical/q_cap_diffbus/chips/chips.prt';

PART_NAME
 C932 'Q_CAP_DIFFBUS_C0201-DIFF BUS_0.22UF,6.3V,20%,X6S,SA':;

SECTION_NUMBER 1
 '@T6G_MB_LIB.T6G(SCH_1):PAGE351_I21@PURE_QUANTA.Q_CAP_DIFFBUS(CHIPS)':
 C_PATH='@t6g_mb_lib.t6g(sch_1):page351_i21@pure_quanta.q_cap_diffbus(chips)',
 P_PATH='@t6g_mb_lib.t6g(sch_1):page63_i21@pure_quanta.q_cap_diffbus(chips)',
 PATH='I21',
 DRAWING='@T6G_MB_LIB.T6G(SCH_1):PAGE351',
 PIN_NAMES_ROTATE='TRUE',
 TOLERANCE='20%',
 MATERIAL='X6S',
 PHYS_PAGE='63',
 XY='(-575,375)',
 ROT='2',
 VER='2',
 PACK_TYPE='C0201',
 LOCATION='C932',
 CDS_LIB='pure_quanta',
 CDS_PART_NAME='Q_CAP_DIFFBUS_C0201-DIFF BUS_0.22UF,6.3V,20%,X6S,SA',
 VOLTAGE='6.3V',
 PART_NUMBER='SP_CH4221MEE01',
 VALUE='DIFF BUS_0.22UF',
 PRIM_FILE='./archive_libs/logical/q_cap_diffbus/chips/chips.prt';

PART_NAME
 C933 'Q_CAP_DIFFBUS_C0201-DIFF BUS_0.22UF,6.3V,20%,X6S,SA':;

SECTION_NUMBER 1
 '@T6G_MB_LIB.T6G(SCH_1):PAGE351_I22@PURE_QUANTA.Q_CAP_DIFFBUS(CHIPS)':
 C_PATH='@t6g_mb_lib.t6g(sch_1):page351_i22@pure_quanta.q_cap_diffbus(chips)',
 P_PATH='@t6g_mb_lib.t6g(sch_1):page63_i22@pure_quanta.q_cap_diffbus(chips)',
 PATH='I22',
 DRAWING='@T6G_MB_LIB.T6G(SCH_1):PAGE351',
 PIN_NAMES_ROTATE='TRUE',
 TOLERANCE='20%',
 MATERIAL='X6S',
 PHYS_PAGE='63',
 XY='(-575,325)',
 ROT='2',
 VER='2',
 PACK_TYPE='C0201',
 LOCATION='C933',
 CDS_LIB='pure_quanta',
 CDS_PART_NAME='Q_CAP_DIFFBUS_C0201-DIFF BUS_0.22UF,6.3V,20%,X6S,SA',
 VOLTAGE='6.3V',
 PART_NUMBER='SP_CH4221MEE01',
 VALUE='DIFF BUS_0.22UF',
 PRIM_FILE='./archive_libs/logical/q_cap_diffbus/chips/chips.prt';

PART_NAME
 C934 'Q_CAP_DIFFBUS_C0201-DIFF BUS_0.22UF,6.3V,20%,X6S,SA':;

SECTION_NUMBER 1
 '@T6G_MB_LIB.T6G(SCH_1):PAGE351_I169@PURE_QUANTA.Q_CAP_DIFFBUS(CHIPS)':
 C_PATH='@t6g_mb_lib.t6g(sch_1):page351_i169@pure_quanta.q_cap_diffbus(chips)',
 P_PATH='@t6g_mb_lib.t6g(sch_1):page63_i169@pure_quanta.q_cap_diffbus(chips)',
 PATH='I169',
 DRAWING='@T6G_MB_LIB.T6G(SCH_1):PAGE351',
 PIN_NAMES_ROTATE='TRUE',
 TOLERANCE='20%',
 MATERIAL='X6S',
 PHYS_PAGE='63',
 XY='(3975,3750)',
 ROT='2',
 VER='2',
 PACK_TYPE='C0201',
 LOCATION='C934',
 CDS_LIB='pure_quanta',
 CDS_PART_NAME='Q_CAP_DIFFBUS_C0201-DIFF BUS_0.22UF,6.3V,20%,X6S,SA',
 VOLTAGE='6.3V',
 PART_NUMBER='SP_CH4221MEE01',
 VALUE='DIFF BUS_0.22UF',
 PRIM_FILE='./archive_libs/logical/q_cap_diffbus/chips/chips.prt';

PART_NAME
 C935 'Q_CAP_DIFFBUS_C0201-DIFF BUS_0.22UF,6.3V,20%,X6S,SA':;

SECTION_NUMBER 1
 '@T6G_MB_LIB.T6G(SCH_1):PAGE351_I168@PURE_QUANTA.Q_CAP_DIFFBUS(CHIPS)':
 C_PATH='@t6g_mb_lib.t6g(sch_1):page351_i168@pure_quanta.q_cap_diffbus(chips)',
 P_PATH='@t6g_mb_lib.t6g(sch_1):page63_i168@pure_quanta.q_cap_diffbus(chips)',
 PATH='I168',
 DRAWING='@T6G_MB_LIB.T6G(SCH_1):PAGE351',
 PIN_NAMES_ROTATE='TRUE',
 TOLERANCE='20%',
 MATERIAL='X6S',
 PHYS_PAGE='63',
 XY='(3975,3700)',
 ROT='2',
 VER='2',
 PACK_TYPE='C0201',
 LOCATION='C935',
 CDS_LIB='pure_quanta',
 CDS_PART_NAME='Q_CAP_DIFFBUS_C0201-DIFF BUS_0.22UF,6.3V,20%,X6S,SA',
 VOLTAGE='6.3V',
 PART_NUMBER='SP_CH4221MEE01',
 VALUE='DIFF BUS_0.22UF',
 PRIM_FILE='./archive_libs/logical/q_cap_diffbus/chips/chips.prt';

PART_NAME
 C936 'Q_CAP_DIFFBUS_C0201-DIFF BUS_0.22UF,6.3V,20%,X6S,SA':;

SECTION_NUMBER 1
 '@T6G_MB_LIB.T6G(SCH_1):PAGE351_I167@PURE_QUANTA.Q_CAP_DIFFBUS(CHIPS)':
 C_PATH='@t6g_mb_lib.t6g(sch_1):page351_i167@pure_quanta.q_cap_diffbus(chips)',
 P_PATH='@t6g_mb_lib.t6g(sch_1):page63_i167@pure_quanta.q_cap_diffbus(chips)',
 PATH='I167',
 DRAWING='@T6G_MB_LIB.T6G(SCH_1):PAGE351',
 PIN_NAMES_ROTATE='TRUE',
 TOLERANCE='20%',
 MATERIAL='X6S',
 PHYS_PAGE='63',
 XY='(3975,3550)',
 ROT='2',
 VER='2',
 PACK_TYPE='C0201',
 LOCATION='C936',
 CDS_LIB='pure_quanta',
 CDS_PART_NAME='Q_CAP_DIFFBUS_C0201-DIFF BUS_0.22UF,6.3V,20%,X6S,SA',
 VOLTAGE='6.3V',
 PART_NUMBER='SP_CH4221MEE01',
 VALUE='DIFF BUS_0.22UF',
 PRIM_FILE='./archive_libs/logical/q_cap_diffbus/chips/chips.prt';

PART_NAME
 C937 'Q_CAP_DIFFBUS_C0201-DIFF BUS_0.22UF,6.3V,20%,X6S,SA':;

SECTION_NUMBER 1
 '@T6G_MB_LIB.T6G(SCH_1):PAGE351_I166@PURE_QUANTA.Q_CAP_DIFFBUS(CHIPS)':
 C_PATH='@t6g_mb_lib.t6g(sch_1):page351_i166@pure_quanta.q_cap_diffbus(chips)',
 P_PATH='@t6g_mb_lib.t6g(sch_1):page63_i166@pure_quanta.q_cap_diffbus(chips)',
 PATH='I166',
 DRAWING='@T6G_MB_LIB.T6G(SCH_1):PAGE351',
 PIN_NAMES_ROTATE='TRUE',
 TOLERANCE='20%',
 MATERIAL='X6S',
 PHYS_PAGE='63',
 XY='(3975,3500)',
 ROT='2',
 VER='2',
 PACK_TYPE='C0201',
 LOCATION='C937',
 CDS_LIB='pure_quanta',
 CDS_PART_NAME='Q_CAP_DIFFBUS_C0201-DIFF BUS_0.22UF,6.3V,20%,X6S,SA',
 VOLTAGE='6.3V',
 PART_NUMBER='SP_CH4221MEE01',
 VALUE='DIFF BUS_0.22UF',
 PRIM_FILE='./archive_libs/logical/q_cap_diffbus/chips/chips.prt';

PART_NAME
 C938 'Q_CAP_DIFFBUS_C0201-DIFF BUS_0.22UF,6.3V,20%,X6S,SA':;

SECTION_NUMBER 1
 '@T6G_MB_LIB.T6G(SCH_1):PAGE351_I165@PURE_QUANTA.Q_CAP_DIFFBUS(CHIPS)':
 C_PATH='@t6g_mb_lib.t6g(sch_1):page351_i165@pure_quanta.q_cap_diffbus(chips)',
 P_PATH='@t6g_mb_lib.t6g(sch_1):page63_i165@pure_quanta.q_cap_diffbus(chips)',
 PATH='I165',
 DRAWING='@T6G_MB_LIB.T6G(SCH_1):PAGE351',
 PIN_NAMES_ROTATE='TRUE',
 TOLERANCE='20%',
 MATERIAL='X6S',
 PHYS_PAGE='63',
 XY='(3975,3350)',
 ROT='2',
 VER='2',
 PACK_TYPE='C0201',
 LOCATION='C938',
 CDS_LIB='pure_quanta',
 CDS_PART_NAME='Q_CAP_DIFFBUS_C0201-DIFF BUS_0.22UF,6.3V,20%,X6S,SA',
 VOLTAGE='6.3V',
 PART_NUMBER='SP_CH4221MEE01',
 VALUE='DIFF BUS_0.22UF',
 PRIM_FILE='./archive_libs/logical/q_cap_diffbus/chips/chips.prt';

PART_NAME
 C939 'Q_CAP_DIFFBUS_C0201-DIFF BUS_0.22UF,6.3V,20%,X6S,SA':;

SECTION_NUMBER 1
 '@T6G_MB_LIB.T6G(SCH_1):PAGE351_I164@PURE_QUANTA.Q_CAP_DIFFBUS(CHIPS)':
 C_PATH='@t6g_mb_lib.t6g(sch_1):page351_i164@pure_quanta.q_cap_diffbus(chips)',
 P_PATH='@t6g_mb_lib.t6g(sch_1):page63_i164@pure_quanta.q_cap_diffbus(chips)',
 PATH='I164',
 DRAWING='@T6G_MB_LIB.T6G(SCH_1):PAGE351',
 PIN_NAMES_ROTATE='TRUE',
 TOLERANCE='20%',
 MATERIAL='X6S',
 PHYS_PAGE='63',
 XY='(3975,3300)',
 ROT='2',
 VER='2',
 PACK_TYPE='C0201',
 LOCATION='C939',
 CDS_LIB='pure_quanta',
 CDS_PART_NAME='Q_CAP_DIFFBUS_C0201-DIFF BUS_0.22UF,6.3V,20%,X6S,SA',
 VOLTAGE='6.3V',
 PART_NUMBER='SP_CH4221MEE01',
 VALUE='DIFF BUS_0.22UF',
 PRIM_FILE='./archive_libs/logical/q_cap_diffbus/chips/chips.prt';

PART_NAME
 C940 'Q_CAP_DIFFBUS_C0201-DIFF BUS_0.22UF,6.3V,20%,X6S,SA':;

SECTION_NUMBER 1
 '@T6G_MB_LIB.T6G(SCH_1):PAGE351_I160@PURE_QUANTA.Q_CAP_DIFFBUS(CHIPS)':
 C_PATH='@t6g_mb_lib.t6g(sch_1):page351_i160@pure_quanta.q_cap_diffbus(chips)',
 P_PATH='@t6g_mb_lib.t6g(sch_1):page63_i160@pure_quanta.q_cap_diffbus(chips)',
 PATH='I160',
 DRAWING='@T6G_MB_LIB.T6G(SCH_1):PAGE351',
 PIN_NAMES_ROTATE='TRUE',
 TOLERANCE='20%',
 MATERIAL='X6S',
 PHYS_PAGE='63',
 XY='(3975,3150)',
 ROT='2',
 VER='2',
 PACK_TYPE='C0201',
 LOCATION='C940',
 CDS_LIB='pure_quanta',
 CDS_PART_NAME='Q_CAP_DIFFBUS_C0201-DIFF BUS_0.22UF,6.3V,20%,X6S,SA',
 VOLTAGE='6.3V',
 PART_NUMBER='SP_CH4221MEE01',
 VALUE='DIFF BUS_0.22UF',
 PRIM_FILE='./archive_libs/logical/q_cap_diffbus/chips/chips.prt';

PART_NAME
 C941 'Q_CAP_DIFFBUS_C0201-DIFF BUS_0.22UF,6.3V,20%,X6S,SA':;

SECTION_NUMBER 1
 '@T6G_MB_LIB.T6G(SCH_1):PAGE351_I159@PURE_QUANTA.Q_CAP_DIFFBUS(CHIPS)':
 C_PATH='@t6g_mb_lib.t6g(sch_1):page351_i159@pure_quanta.q_cap_diffbus(chips)',
 P_PATH='@t6g_mb_lib.t6g(sch_1):page63_i159@pure_quanta.q_cap_diffbus(chips)',
 PATH='I159',
 DRAWING='@T6G_MB_LIB.T6G(SCH_1):PAGE351',
 PIN_NAMES_ROTATE='TRUE',
 TOLERANCE='20%',
 MATERIAL='X6S',
 PHYS_PAGE='63',
 XY='(3975,3100)',
 ROT='2',
 VER='2',
 PACK_TYPE='C0201',
 LOCATION='C941',
 CDS_LIB='pure_quanta',
 CDS_PART_NAME='Q_CAP_DIFFBUS_C0201-DIFF BUS_0.22UF,6.3V,20%,X6S,SA',
 VOLTAGE='6.3V',
 PART_NUMBER='SP_CH4221MEE01',
 VALUE='DIFF BUS_0.22UF',
 PRIM_FILE='./archive_libs/logical/q_cap_diffbus/chips/chips.prt';

PART_NAME
 C942 'Q_CAP_DIFFBUS_C0201-DIFF BUS_0.22UF,6.3V,20%,X6S,SA':;

SECTION_NUMBER 1
 '@T6G_MB_LIB.T6G(SCH_1):PAGE351_I158@PURE_QUANTA.Q_CAP_DIFFBUS(CHIPS)':
 C_PATH='@t6g_mb_lib.t6g(sch_1):page351_i158@pure_quanta.q_cap_diffbus(chips)',
 P_PATH='@t6g_mb_lib.t6g(sch_1):page63_i158@pure_quanta.q_cap_diffbus(chips)',
 PATH='I158',
 DRAWING='@T6G_MB_LIB.T6G(SCH_1):PAGE351',
 PIN_NAMES_ROTATE='TRUE',
 TOLERANCE='20%',
 MATERIAL='X6S',
 PHYS_PAGE='63',
 XY='(3975,2950)',
 ROT='2',
 VER='2',
 PACK_TYPE='C0201',
 LOCATION='C942',
 CDS_LIB='pure_quanta',
 CDS_PART_NAME='Q_CAP_DIFFBUS_C0201-DIFF BUS_0.22UF,6.3V,20%,X6S,SA',
 VOLTAGE='6.3V',
 PART_NUMBER='SP_CH4221MEE01',
 VALUE='DIFF BUS_0.22UF',
 PRIM_FILE='./archive_libs/logical/q_cap_diffbus/chips/chips.prt';

PART_NAME
 C943 'Q_CAP_DIFFBUS_C0201-DIFF BUS_0.22UF,6.3V,20%,X6S,SA':;

SECTION_NUMBER 1
 '@T6G_MB_LIB.T6G(SCH_1):PAGE351_I157@PURE_QUANTA.Q_CAP_DIFFBUS(CHIPS)':
 C_PATH='@t6g_mb_lib.t6g(sch_1):page351_i157@pure_quanta.q_cap_diffbus(chips)',
 P_PATH='@t6g_mb_lib.t6g(sch_1):page63_i157@pure_quanta.q_cap_diffbus(chips)',
 PATH='I157',
 DRAWING='@T6G_MB_LIB.T6G(SCH_1):PAGE351',
 PIN_NAMES_ROTATE='TRUE',
 TOLERANCE='20%',
 MATERIAL='X6S',
 PHYS_PAGE='63',
 XY='(3975,2900)',
 ROT='2',
 VER='2',
 PACK_TYPE='C0201',
 LOCATION='C943',
 CDS_LIB='pure_quanta',
 CDS_PART_NAME='Q_CAP_DIFFBUS_C0201-DIFF BUS_0.22UF,6.3V,20%,X6S,SA',
 VOLTAGE='6.3V',
 PART_NUMBER='SP_CH4221MEE01',
 VALUE='DIFF BUS_0.22UF',
 PRIM_FILE='./archive_libs/logical/q_cap_diffbus/chips/chips.prt';

PART_NAME
 C944 'Q_CAP_DIFFBUS_C0201-DIFF BUS_0.22UF,6.3V,20%,X6S,SA':;

SECTION_NUMBER 1
 '@T6G_MB_LIB.T6G(SCH_1):PAGE351_I156@PURE_QUANTA.Q_CAP_DIFFBUS(CHIPS)':
 C_PATH='@t6g_mb_lib.t6g(sch_1):page351_i156@pure_quanta.q_cap_diffbus(chips)',
 P_PATH='@t6g_mb_lib.t6g(sch_1):page63_i156@pure_quanta.q_cap_diffbus(chips)',
 PATH='I156',
 DRAWING='@T6G_MB_LIB.T6G(SCH_1):PAGE351',
 PIN_NAMES_ROTATE='TRUE',
 TOLERANCE='20%',
 MATERIAL='X6S',
 PHYS_PAGE='63',
 XY='(3975,2750)',
 ROT='2',
 VER='2',
 PACK_TYPE='C0201',
 LOCATION='C944',
 CDS_LIB='pure_quanta',
 CDS_PART_NAME='Q_CAP_DIFFBUS_C0201-DIFF BUS_0.22UF,6.3V,20%,X6S,SA',
 VOLTAGE='6.3V',
 PART_NUMBER='SP_CH4221MEE01',
 VALUE='DIFF BUS_0.22UF',
 PRIM_FILE='./archive_libs/logical/q_cap_diffbus/chips/chips.prt';

PART_NAME
 C945 'Q_CAP_DIFFBUS_C0201-DIFF BUS_0.22UF,6.3V,20%,X6S,SA':;

SECTION_NUMBER 1
 '@T6G_MB_LIB.T6G(SCH_1):PAGE351_I155@PURE_QUANTA.Q_CAP_DIFFBUS(CHIPS)':
 C_PATH='@t6g_mb_lib.t6g(sch_1):page351_i155@pure_quanta.q_cap_diffbus(chips)',
 P_PATH='@t6g_mb_lib.t6g(sch_1):page63_i155@pure_quanta.q_cap_diffbus(chips)',
 PATH='I155',
 DRAWING='@T6G_MB_LIB.T6G(SCH_1):PAGE351',
 PIN_NAMES_ROTATE='TRUE',
 TOLERANCE='20%',
 MATERIAL='X6S',
 PHYS_PAGE='63',
 XY='(3975,2700)',
 ROT='2',
 VER='2',
 PACK_TYPE='C0201',
 LOCATION='C945',
 CDS_LIB='pure_quanta',
 CDS_PART_NAME='Q_CAP_DIFFBUS_C0201-DIFF BUS_0.22UF,6.3V,20%,X6S,SA',
 VOLTAGE='6.3V',
 PART_NUMBER='SP_CH4221MEE01',
 VALUE='DIFF BUS_0.22UF',
 PRIM_FILE='./archive_libs/logical/q_cap_diffbus/chips/chips.prt';

PART_NAME
 C946 'Q_CAP_DIFFBUS_C0201-DIFF BUS_0.22UF,6.3V,20%,X6S,SA':;

SECTION_NUMBER 1
 '@T6G_MB_LIB.T6G(SCH_1):PAGE351_I154@PURE_QUANTA.Q_CAP_DIFFBUS(CHIPS)':
 C_PATH='@t6g_mb_lib.t6g(sch_1):page351_i154@pure_quanta.q_cap_diffbus(chips)',
 P_PATH='@t6g_mb_lib.t6g(sch_1):page63_i154@pure_quanta.q_cap_diffbus(chips)',
 PATH='I154',
 DRAWING='@T6G_MB_LIB.T6G(SCH_1):PAGE351',
 PIN_NAMES_ROTATE='TRUE',
 TOLERANCE='20%',
 MATERIAL='X6S',
 PHYS_PAGE='63',
 XY='(3975,2550)',
 ROT='2',
 VER='2',
 PACK_TYPE='C0201',
 LOCATION='C946',
 CDS_LIB='pure_quanta',
 CDS_PART_NAME='Q_CAP_DIFFBUS_C0201-DIFF BUS_0.22UF,6.3V,20%,X6S,SA',
 VOLTAGE='6.3V',
 PART_NUMBER='SP_CH4221MEE01',
 VALUE='DIFF BUS_0.22UF',
 PRIM_FILE='./archive_libs/logical/q_cap_diffbus/chips/chips.prt';

PART_NAME
 C947 'Q_CAP_DIFFBUS_C0201-DIFF BUS_0.22UF,6.3V,20%,X6S,SA':;

SECTION_NUMBER 1
 '@T6G_MB_LIB.T6G(SCH_1):PAGE351_I153@PURE_QUANTA.Q_CAP_DIFFBUS(CHIPS)':
 C_PATH='@t6g_mb_lib.t6g(sch_1):page351_i153@pure_quanta.q_cap_diffbus(chips)',
 P_PATH='@t6g_mb_lib.t6g(sch_1):page63_i153@pure_quanta.q_cap_diffbus(chips)',
 PATH='I153',
 DRAWING='@T6G_MB_LIB.T6G(SCH_1):PAGE351',
 PIN_NAMES_ROTATE='TRUE',
 TOLERANCE='20%',
 MATERIAL='X6S',
 PHYS_PAGE='63',
 XY='(3975,2500)',
 ROT='2',
 VER='2',
 PACK_TYPE='C0201',
 LOCATION='C947',
 CDS_LIB='pure_quanta',
 CDS_PART_NAME='Q_CAP_DIFFBUS_C0201-DIFF BUS_0.22UF,6.3V,20%,X6S,SA',
 VOLTAGE='6.3V',
 PART_NUMBER='SP_CH4221MEE01',
 VALUE='DIFF BUS_0.22UF',
 PRIM_FILE='./archive_libs/logical/q_cap_diffbus/chips/chips.prt';

PART_NAME
 C948 'Q_CAP_DIFFBUS_C0201-DIFF BUS_0.22UF,6.3V,20%,X6S,SA':;

SECTION_NUMBER 1
 '@T6G_MB_LIB.T6G(SCH_1):PAGE351_I152@PURE_QUANTA.Q_CAP_DIFFBUS(CHIPS)':
 C_PATH='@t6g_mb_lib.t6g(sch_1):page351_i152@pure_quanta.q_cap_diffbus(chips)',
 P_PATH='@t6g_mb_lib.t6g(sch_1):page63_i152@pure_quanta.q_cap_diffbus(chips)',
 PATH='I152',
 DRAWING='@T6G_MB_LIB.T6G(SCH_1):PAGE351',
 PIN_NAMES_ROTATE='TRUE',
 TOLERANCE='20%',
 MATERIAL='X6S',
 PHYS_PAGE='63',
 XY='(3975,2350)',
 ROT='2',
 VER='2',
 PACK_TYPE='C0201',
 LOCATION='C948',
 CDS_LIB='pure_quanta',
 CDS_PART_NAME='Q_CAP_DIFFBUS_C0201-DIFF BUS_0.22UF,6.3V,20%,X6S,SA',
 VOLTAGE='6.3V',
 PART_NUMBER='SP_CH4221MEE01',
 VALUE='DIFF BUS_0.22UF',
 PRIM_FILE='./archive_libs/logical/q_cap_diffbus/chips/chips.prt';

PART_NAME
 C949 'Q_CAP_DIFFBUS_C0201-DIFF BUS_0.22UF,6.3V,20%,X6S,SA':;

SECTION_NUMBER 1
 '@T6G_MB_LIB.T6G(SCH_1):PAGE351_I151@PURE_QUANTA.Q_CAP_DIFFBUS(CHIPS)':
 C_PATH='@t6g_mb_lib.t6g(sch_1):page351_i151@pure_quanta.q_cap_diffbus(chips)',
 P_PATH='@t6g_mb_lib.t6g(sch_1):page63_i151@pure_quanta.q_cap_diffbus(chips)',
 PATH='I151',
 DRAWING='@T6G_MB_LIB.T6G(SCH_1):PAGE351',
 PIN_NAMES_ROTATE='TRUE',
 TOLERANCE='20%',
 MATERIAL='X6S',
 PHYS_PAGE='63',
 XY='(3975,2300)',
 ROT='2',
 VER='2',
 PACK_TYPE='C0201',
 LOCATION='C949',
 CDS_LIB='pure_quanta',
 CDS_PART_NAME='Q_CAP_DIFFBUS_C0201-DIFF BUS_0.22UF,6.3V,20%,X6S,SA',
 VOLTAGE='6.3V',
 PART_NUMBER='SP_CH4221MEE01',
 VALUE='DIFF BUS_0.22UF',
 PRIM_FILE='./archive_libs/logical/q_cap_diffbus/chips/chips.prt';

PART_NAME
 C950 'Q_CAP_DIFFBUS_C0201-DIFF BUS_0.22UF,6.3V,20%,X6S,SA':;

SECTION_NUMBER 1
 '@T6G_MB_LIB.T6G(SCH_1):PAGE351_I137@PURE_QUANTA.Q_CAP_DIFFBUS(CHIPS)':
 C_PATH='@t6g_mb_lib.t6g(sch_1):page351_i137@pure_quanta.q_cap_diffbus(chips)',
 P_PATH='@t6g_mb_lib.t6g(sch_1):page63_i137@pure_quanta.q_cap_diffbus(chips)',
 PATH='I137',
 DRAWING='@T6G_MB_LIB.T6G(SCH_1):PAGE351',
 PIN_NAMES_ROTATE='TRUE',
 TOLERANCE='20%',
 MATERIAL='X6S',
 PHYS_PAGE='63',
 XY='(3975,1775)',
 ROT='2',
 VER='2',
 PACK_TYPE='C0201',
 LOCATION='C950',
 CDS_LIB='pure_quanta',
 CDS_PART_NAME='Q_CAP_DIFFBUS_C0201-DIFF BUS_0.22UF,6.3V,20%,X6S,SA',
 VOLTAGE='6.3V',
 PART_NUMBER='SP_CH4221MEE01',
 VALUE='DIFF BUS_0.22UF',
 PRIM_FILE='./archive_libs/logical/q_cap_diffbus/chips/chips.prt';

PART_NAME
 C951 'Q_CAP_DIFFBUS_C0201-DIFF BUS_0.22UF,6.3V,20%,X6S,SA':;

SECTION_NUMBER 1
 '@T6G_MB_LIB.T6G(SCH_1):PAGE351_I136@PURE_QUANTA.Q_CAP_DIFFBUS(CHIPS)':
 C_PATH='@t6g_mb_lib.t6g(sch_1):page351_i136@pure_quanta.q_cap_diffbus(chips)',
 P_PATH='@t6g_mb_lib.t6g(sch_1):page63_i136@pure_quanta.q_cap_diffbus(chips)',
 PATH='I136',
 DRAWING='@T6G_MB_LIB.T6G(SCH_1):PAGE351',
 PIN_NAMES_ROTATE='TRUE',
 TOLERANCE='20%',
 MATERIAL='X6S',
 PHYS_PAGE='63',
 XY='(3975,1725)',
 ROT='2',
 VER='2',
 PACK_TYPE='C0201',
 LOCATION='C951',
 CDS_LIB='pure_quanta',
 CDS_PART_NAME='Q_CAP_DIFFBUS_C0201-DIFF BUS_0.22UF,6.3V,20%,X6S,SA',
 VOLTAGE='6.3V',
 PART_NUMBER='SP_CH4221MEE01',
 VALUE='DIFF BUS_0.22UF',
 PRIM_FILE='./archive_libs/logical/q_cap_diffbus/chips/chips.prt';

PART_NAME
 C952 'Q_CAP_DIFFBUS_C0201-DIFF BUS_0.22UF,6.3V,20%,X6S,SA':;

SECTION_NUMBER 1
 '@T6G_MB_LIB.T6G(SCH_1):PAGE351_I135@PURE_QUANTA.Q_CAP_DIFFBUS(CHIPS)':
 C_PATH='@t6g_mb_lib.t6g(sch_1):page351_i135@pure_quanta.q_cap_diffbus(chips)',
 P_PATH='@t6g_mb_lib.t6g(sch_1):page63_i135@pure_quanta.q_cap_diffbus(chips)',
 PATH='I135',
 DRAWING='@T6G_MB_LIB.T6G(SCH_1):PAGE351',
 PIN_NAMES_ROTATE='TRUE',
 TOLERANCE='20%',
 MATERIAL='X6S',
 PHYS_PAGE='63',
 XY='(3975,1575)',
 ROT='2',
 VER='2',
 PACK_TYPE='C0201',
 LOCATION='C952',
 CDS_LIB='pure_quanta',
 CDS_PART_NAME='Q_CAP_DIFFBUS_C0201-DIFF BUS_0.22UF,6.3V,20%,X6S,SA',
 VOLTAGE='6.3V',
 PART_NUMBER='SP_CH4221MEE01',
 VALUE='DIFF BUS_0.22UF',
 PRIM_FILE='./archive_libs/logical/q_cap_diffbus/chips/chips.prt';

PART_NAME
 C953 'Q_CAP_DIFFBUS_C0201-DIFF BUS_0.22UF,6.3V,20%,X6S,SA':;

SECTION_NUMBER 1
 '@T6G_MB_LIB.T6G(SCH_1):PAGE351_I134@PURE_QUANTA.Q_CAP_DIFFBUS(CHIPS)':
 C_PATH='@t6g_mb_lib.t6g(sch_1):page351_i134@pure_quanta.q_cap_diffbus(chips)',
 P_PATH='@t6g_mb_lib.t6g(sch_1):page63_i134@pure_quanta.q_cap_diffbus(chips)',
 PATH='I134',
 DRAWING='@T6G_MB_LIB.T6G(SCH_1):PAGE351',
 PIN_NAMES_ROTATE='TRUE',
 TOLERANCE='20%',
 MATERIAL='X6S',
 PHYS_PAGE='63',
 XY='(3975,1525)',
 ROT='2',
 VER='2',
 PACK_TYPE='C0201',
 LOCATION='C953',
 CDS_LIB='pure_quanta',
 CDS_PART_NAME='Q_CAP_DIFFBUS_C0201-DIFF BUS_0.22UF,6.3V,20%,X6S,SA',
 VOLTAGE='6.3V',
 PART_NUMBER='SP_CH4221MEE01',
 VALUE='DIFF BUS_0.22UF',
 PRIM_FILE='./archive_libs/logical/q_cap_diffbus/chips/chips.prt';

PART_NAME
 C954 'Q_CAP_DIFFBUS_C0201-DIFF BUS_0.22UF,6.3V,20%,X6S,SA':;

SECTION_NUMBER 1
 '@T6G_MB_LIB.T6G(SCH_1):PAGE351_I133@PURE_QUANTA.Q_CAP_DIFFBUS(CHIPS)':
 C_PATH='@t6g_mb_lib.t6g(sch_1):page351_i133@pure_quanta.q_cap_diffbus(chips)',
 P_PATH='@t6g_mb_lib.t6g(sch_1):page63_i133@pure_quanta.q_cap_diffbus(chips)',
 PATH='I133',
 DRAWING='@T6G_MB_LIB.T6G(SCH_1):PAGE351',
 PIN_NAMES_ROTATE='TRUE',
 TOLERANCE='20%',
 MATERIAL='X6S',
 PHYS_PAGE='63',
 XY='(3975,1375)',
 ROT='2',
 VER='2',
 PACK_TYPE='C0201',
 LOCATION='C954',
 CDS_LIB='pure_quanta',
 CDS_PART_NAME='Q_CAP_DIFFBUS_C0201-DIFF BUS_0.22UF,6.3V,20%,X6S,SA',
 VOLTAGE='6.3V',
 PART_NUMBER='SP_CH4221MEE01',
 VALUE='DIFF BUS_0.22UF',
 PRIM_FILE='./archive_libs/logical/q_cap_diffbus/chips/chips.prt';

PART_NAME
 C955 'Q_CAP_DIFFBUS_C0201-DIFF BUS_0.22UF,6.3V,20%,X6S,SA':;

SECTION_NUMBER 1
 '@T6G_MB_LIB.T6G(SCH_1):PAGE351_I208@PURE_QUANTA.Q_CAP_DIFFBUS(CHIPS)':
 C_PATH='@t6g_mb_lib.t6g(sch_1):page351_i208@pure_quanta.q_cap_diffbus(chips)',
 P_PATH='@t6g_mb_lib.t6g(sch_1):page63_i208@pure_quanta.q_cap_diffbus(chips)',
 PATH='I208',
 DRAWING='@T6G_MB_LIB.T6G(SCH_1):PAGE351',
 PIN_NAMES_ROTATE='TRUE',
 TOLERANCE='20%',
 MATERIAL='X6S',
 PHYS_PAGE='63',
 XY='(3975,1325)',
 ROT='2',
 VER='2',
 PACK_TYPE='C0201',
 LOCATION='C955',
 CDS_LIB='pure_quanta',
 CDS_PART_NAME='Q_CAP_DIFFBUS_C0201-DIFF BUS_0.22UF,6.3V,20%,X6S,SA',
 VOLTAGE='6.3V',
 PART_NUMBER='SP_CH4221MEE01',
 VALUE='DIFF BUS_0.22UF',
 PRIM_FILE='./archive_libs/logical/q_cap_diffbus/chips/chips.prt';

PART_NAME
 C956 'Q_CAP_DIFFBUS_C0201-DIFF BUS_0.22UF,6.3V,20%,X6S,SA':;

SECTION_NUMBER 1
 '@T6G_MB_LIB.T6G(SCH_1):PAGE351_I207@PURE_QUANTA.Q_CAP_DIFFBUS(CHIPS)':
 C_PATH='@t6g_mb_lib.t6g(sch_1):page351_i207@pure_quanta.q_cap_diffbus(chips)',
 P_PATH='@t6g_mb_lib.t6g(sch_1):page63_i207@pure_quanta.q_cap_diffbus(chips)',
 PATH='I207',
 DRAWING='@T6G_MB_LIB.T6G(SCH_1):PAGE351',
 PIN_NAMES_ROTATE='TRUE',
 TOLERANCE='20%',
 MATERIAL='X6S',
 PHYS_PAGE='63',
 XY='(3975,1175)',
 ROT='2',
 VER='2',
 PACK_TYPE='C0201',
 LOCATION='C956',
 CDS_LIB='pure_quanta',
 CDS_PART_NAME='Q_CAP_DIFFBUS_C0201-DIFF BUS_0.22UF,6.3V,20%,X6S,SA',
 VOLTAGE='6.3V',
 PART_NUMBER='SP_CH4221MEE01',
 VALUE='DIFF BUS_0.22UF',
 PRIM_FILE='./archive_libs/logical/q_cap_diffbus/chips/chips.prt';

PART_NAME
 C957 'Q_CAP_DIFFBUS_C0201-DIFF BUS_0.22UF,6.3V,20%,X6S,SA':;

SECTION_NUMBER 1
 '@T6G_MB_LIB.T6G(SCH_1):PAGE351_I206@PURE_QUANTA.Q_CAP_DIFFBUS(CHIPS)':
 C_PATH='@t6g_mb_lib.t6g(sch_1):page351_i206@pure_quanta.q_cap_diffbus(chips)',
 P_PATH='@t6g_mb_lib.t6g(sch_1):page63_i206@pure_quanta.q_cap_diffbus(chips)',
 PATH='I206',
 DRAWING='@T6G_MB_LIB.T6G(SCH_1):PAGE351',
 PIN_NAMES_ROTATE='TRUE',
 TOLERANCE='20%',
 MATERIAL='X6S',
 PHYS_PAGE='63',
 XY='(3975,1125)',
 ROT='2',
 VER='2',
 PACK_TYPE='C0201',
 LOCATION='C957',
 CDS_LIB='pure_quanta',
 CDS_PART_NAME='Q_CAP_DIFFBUS_C0201-DIFF BUS_0.22UF,6.3V,20%,X6S,SA',
 VOLTAGE='6.3V',
 PART_NUMBER='SP_CH4221MEE01',
 VALUE='DIFF BUS_0.22UF',
 PRIM_FILE='./archive_libs/logical/q_cap_diffbus/chips/chips.prt';

PART_NAME
 C958 'Q_CAP_DIFFBUS_C0201-DIFF BUS_0.22UF,6.3V,20%,X6S,SA':;

SECTION_NUMBER 1
 '@T6G_MB_LIB.T6G(SCH_1):PAGE351_I128@PURE_QUANTA.Q_CAP_DIFFBUS(CHIPS)':
 C_PATH='@t6g_mb_lib.t6g(sch_1):page351_i128@pure_quanta.q_cap_diffbus(chips)',
 P_PATH='@t6g_mb_lib.t6g(sch_1):page63_i128@pure_quanta.q_cap_diffbus(chips)',
 PATH='I128',
 DRAWING='@T6G_MB_LIB.T6G(SCH_1):PAGE351',
 PIN_NAMES_ROTATE='TRUE',
 TOLERANCE='20%',
 MATERIAL='X6S',
 PHYS_PAGE='63',
 XY='(3975,975)',
 ROT='2',
 VER='2',
 PACK_TYPE='C0201',
 LOCATION='C958',
 CDS_LIB='pure_quanta',
 CDS_PART_NAME='Q_CAP_DIFFBUS_C0201-DIFF BUS_0.22UF,6.3V,20%,X6S,SA',
 VOLTAGE='6.3V',
 PART_NUMBER='SP_CH4221MEE01',
 VALUE='DIFF BUS_0.22UF',
 PRIM_FILE='./archive_libs/logical/q_cap_diffbus/chips/chips.prt';

PART_NAME
 C959 'Q_CAP_DIFFBUS_C0201-DIFF BUS_0.22UF,6.3V,20%,X6S,SA':;

SECTION_NUMBER 1
 '@T6G_MB_LIB.T6G(SCH_1):PAGE351_I127@PURE_QUANTA.Q_CAP_DIFFBUS(CHIPS)':
 C_PATH='@t6g_mb_lib.t6g(sch_1):page351_i127@pure_quanta.q_cap_diffbus(chips)',
 P_PATH='@t6g_mb_lib.t6g(sch_1):page63_i127@pure_quanta.q_cap_diffbus(chips)',
 PATH='I127',
 DRAWING='@T6G_MB_LIB.T6G(SCH_1):PAGE351',
 PIN_NAMES_ROTATE='TRUE',
 TOLERANCE='20%',
 MATERIAL='X6S',
 PHYS_PAGE='63',
 XY='(3975,925)',
 ROT='2',
 VER='2',
 PACK_TYPE='C0201',
 LOCATION='C959',
 CDS_LIB='pure_quanta',
 CDS_PART_NAME='Q_CAP_DIFFBUS_C0201-DIFF BUS_0.22UF,6.3V,20%,X6S,SA',
 VOLTAGE='6.3V',
 PART_NUMBER='SP_CH4221MEE01',
 VALUE='DIFF BUS_0.22UF',
 PRIM_FILE='./archive_libs/logical/q_cap_diffbus/chips/chips.prt';

PART_NAME
 C960 'Q_CAP_DIFFBUS_C0201-DIFF BUS_0.22UF,6.3V,20%,X6S,SA':;

SECTION_NUMBER 1
 '@T6G_MB_LIB.T6G(SCH_1):PAGE351_I126@PURE_QUANTA.Q_CAP_DIFFBUS(CHIPS)':
 C_PATH='@t6g_mb_lib.t6g(sch_1):page351_i126@pure_quanta.q_cap_diffbus(chips)',
 P_PATH='@t6g_mb_lib.t6g(sch_1):page63_i126@pure_quanta.q_cap_diffbus(chips)',
 PATH='I126',
 DRAWING='@T6G_MB_LIB.T6G(SCH_1):PAGE351',
 PIN_NAMES_ROTATE='TRUE',
 TOLERANCE='20%',
 MATERIAL='X6S',
 PHYS_PAGE='63',
 XY='(3975,775)',
 ROT='2',
 VER='2',
 PACK_TYPE='C0201',
 LOCATION='C960',
 CDS_LIB='pure_quanta',
 CDS_PART_NAME='Q_CAP_DIFFBUS_C0201-DIFF BUS_0.22UF,6.3V,20%,X6S,SA',
 VOLTAGE='6.3V',
 PART_NUMBER='SP_CH4221MEE01',
 VALUE='DIFF BUS_0.22UF',
 PRIM_FILE='./archive_libs/logical/q_cap_diffbus/chips/chips.prt';

PART_NAME
 C961 'Q_CAP_DIFFBUS_C0201-DIFF BUS_0.22UF,6.3V,20%,X6S,SA':;

SECTION_NUMBER 1
 '@T6G_MB_LIB.T6G(SCH_1):PAGE351_I125@PURE_QUANTA.Q_CAP_DIFFBUS(CHIPS)':
 C_PATH='@t6g_mb_lib.t6g(sch_1):page351_i125@pure_quanta.q_cap_diffbus(chips)',
 P_PATH='@t6g_mb_lib.t6g(sch_1):page63_i125@pure_quanta.q_cap_diffbus(chips)',
 PATH='I125',
 DRAWING='@T6G_MB_LIB.T6G(SCH_1):PAGE351',
 PIN_NAMES_ROTATE='TRUE',
 TOLERANCE='20%',
 MATERIAL='X6S',
 PHYS_PAGE='63',
 XY='(3975,725)',
 ROT='2',
 VER='2',
 PACK_TYPE='C0201',
 LOCATION='C961',
 CDS_LIB='pure_quanta',
 CDS_PART_NAME='Q_CAP_DIFFBUS_C0201-DIFF BUS_0.22UF,6.3V,20%,X6S,SA',
 VOLTAGE='6.3V',
 PART_NUMBER='SP_CH4221MEE01',
 VALUE='DIFF BUS_0.22UF',
 PRIM_FILE='./archive_libs/logical/q_cap_diffbus/chips/chips.prt';

PART_NAME
 C962 'Q_CAP_DIFFBUS_C0201-DIFF BUS_0.22UF,6.3V,20%,X6S,SA':;

SECTION_NUMBER 1
 '@T6G_MB_LIB.T6G(SCH_1):PAGE351_I124@PURE_QUANTA.Q_CAP_DIFFBUS(CHIPS)':
 C_PATH='@t6g_mb_lib.t6g(sch_1):page351_i124@pure_quanta.q_cap_diffbus(chips)',
 P_PATH='@t6g_mb_lib.t6g(sch_1):page63_i124@pure_quanta.q_cap_diffbus(chips)',
 PATH='I124',
 DRAWING='@T6G_MB_LIB.T6G(SCH_1):PAGE351',
 PIN_NAMES_ROTATE='TRUE',
 TOLERANCE='20%',
 MATERIAL='X6S',
 PHYS_PAGE='63',
 XY='(3975,575)',
 ROT='2',
 VER='2',
 PACK_TYPE='C0201',
 LOCATION='C962',
 CDS_LIB='pure_quanta',
 CDS_PART_NAME='Q_CAP_DIFFBUS_C0201-DIFF BUS_0.22UF,6.3V,20%,X6S,SA',
 VOLTAGE='6.3V',
 PART_NUMBER='SP_CH4221MEE01',
 VALUE='DIFF BUS_0.22UF',
 PRIM_FILE='./archive_libs/logical/q_cap_diffbus/chips/chips.prt';

PART_NAME
 C963 'Q_CAP_DIFFBUS_C0201-DIFF BUS_0.22UF,6.3V,20%,X6S,SA':;

SECTION_NUMBER 1
 '@T6G_MB_LIB.T6G(SCH_1):PAGE351_I123@PURE_QUANTA.Q_CAP_DIFFBUS(CHIPS)':
 C_PATH='@t6g_mb_lib.t6g(sch_1):page351_i123@pure_quanta.q_cap_diffbus(chips)',
 P_PATH='@t6g_mb_lib.t6g(sch_1):page63_i123@pure_quanta.q_cap_diffbus(chips)',
 PATH='I123',
 DRAWING='@T6G_MB_LIB.T6G(SCH_1):PAGE351',
 PIN_NAMES_ROTATE='TRUE',
 TOLERANCE='20%',
 MATERIAL='X6S',
 PHYS_PAGE='63',
 XY='(3975,525)',
 ROT='2',
 VER='2',
 PACK_TYPE='C0201',
 LOCATION='C963',
 CDS_LIB='pure_quanta',
 CDS_PART_NAME='Q_CAP_DIFFBUS_C0201-DIFF BUS_0.22UF,6.3V,20%,X6S,SA',
 VOLTAGE='6.3V',
 PART_NUMBER='SP_CH4221MEE01',
 VALUE='DIFF BUS_0.22UF',
 PRIM_FILE='./archive_libs/logical/q_cap_diffbus/chips/chips.prt';

PART_NAME
 C964 'Q_CAP_DIFFBUS_C0201-DIFF BUS_0.22UF,6.3V,20%,X6S,SA':;

SECTION_NUMBER 1
 '@T6G_MB_LIB.T6G(SCH_1):PAGE351_I122@PURE_QUANTA.Q_CAP_DIFFBUS(CHIPS)':
 C_PATH='@t6g_mb_lib.t6g(sch_1):page351_i122@pure_quanta.q_cap_diffbus(chips)',
 P_PATH='@t6g_mb_lib.t6g(sch_1):page63_i122@pure_quanta.q_cap_diffbus(chips)',
 PATH='I122',
 DRAWING='@T6G_MB_LIB.T6G(SCH_1):PAGE351',
 PIN_NAMES_ROTATE='TRUE',
 TOLERANCE='20%',
 MATERIAL='X6S',
 PHYS_PAGE='63',
 XY='(3975,375)',
 ROT='2',
 VER='2',
 PACK_TYPE='C0201',
 LOCATION='C964',
 CDS_LIB='pure_quanta',
 CDS_PART_NAME='Q_CAP_DIFFBUS_C0201-DIFF BUS_0.22UF,6.3V,20%,X6S,SA',
 VOLTAGE='6.3V',
 PART_NUMBER='SP_CH4221MEE01',
 VALUE='DIFF BUS_0.22UF',
 PRIM_FILE='./archive_libs/logical/q_cap_diffbus/chips/chips.prt';

PART_NAME
 C965 'Q_CAP_DIFFBUS_C0201-DIFF BUS_0.22UF,6.3V,20%,X6S,SA':;

SECTION_NUMBER 1
 '@T6G_MB_LIB.T6G(SCH_1):PAGE351_I121@PURE_QUANTA.Q_CAP_DIFFBUS(CHIPS)':
 C_PATH='@t6g_mb_lib.t6g(sch_1):page351_i121@pure_quanta.q_cap_diffbus(chips)',
 P_PATH='@t6g_mb_lib.t6g(sch_1):page63_i121@pure_quanta.q_cap_diffbus(chips)',
 PATH='I121',
 DRAWING='@T6G_MB_LIB.T6G(SCH_1):PAGE351',
 PIN_NAMES_ROTATE='TRUE',
 TOLERANCE='20%',
 MATERIAL='X6S',
 PHYS_PAGE='63',
 XY='(3975,325)',
 ROT='2',
 VER='2',
 PACK_TYPE='C0201',
 LOCATION='C965',
 CDS_LIB='pure_quanta',
 CDS_PART_NAME='Q_CAP_DIFFBUS_C0201-DIFF BUS_0.22UF,6.3V,20%,X6S,SA',
 VOLTAGE='6.3V',
 PART_NUMBER='SP_CH4221MEE01',
 VALUE='DIFF BUS_0.22UF',
 PRIM_FILE='./archive_libs/logical/q_cap_diffbus/chips/chips.prt';

PART_NAME
 C966 'Q_CAP_C0805-100UF,4V,20%,X6S,CH710KMEA01':;

SECTION_NUMBER 1
 '@T6G_MB_LIB.T6G(SCH_1):PAGE422_I58@PURE_QUANTA.Q_CAP(CHIPS)':
 C_PATH='@t6g_mb_lib.t6g(sch_1):page422_i58@pure_quanta.q_cap(chips)',
 P_PATH='@t6g_mb_lib.t6g(sch_1):page301_i58@pure_quanta.q_cap(chips)',
 PATH='I58',
 DRAWING='@T6G_MB_LIB.T6G(SCH_1):PAGE422',
 TOLERANCE='20%',
 MATERIAL='X6S',
 PHYS_PAGE='301',
 XY='(-2650,4475)',
 ROT='0',
 VER='1',
 PACK_TYPE='C0805',
 LOCATION='C966',
 CDS_LIB='pure_quanta',
 CDS_PART_NAME='Q_CAP_C0805-100UF,4V,20%,X6S,CH710KMEA01',
 VOLTAGE='4V',
 PART_NUMBER='CH710KMEA01',
 VALUE='100UF',
 PRIM_FILE='./archive_libs/logical/q_cap/chips/chips.prt';

PART_NAME
 C967 'Q_CAP_0402-4.7UF,6.3V,20%,X6S,CH5471MEB01':;

SECTION_NUMBER 1
 '@T6G_MB_LIB.T6G(SCH_1):PAGE422_I56@PURE_QUANTA.Q_CAP(CHIPS)':
 C_PATH='@t6g_mb_lib.t6g(sch_1):page422_i56@pure_quanta.q_cap(chips)',
 P_PATH='@t6g_mb_lib.t6g(sch_1):page301_i56@pure_quanta.q_cap(chips)',
 PATH='I56',
 DRAWING='@T6G_MB_LIB.T6G(SCH_1):PAGE422',
 TOLERANCE='20%',
 MATERIAL='X6S',
 PHYS_PAGE='301',
 XY='(-2650,3850)',
 ROT='0',
 VER='1',
 PACK_TYPE='0402',
 LOCATION='C967',
 CDS_LIB='pure_quanta',
 CDS_PART_NAME='Q_CAP_0402-4.7UF,6.3V,20%,X6S,CH5471MEB01',
 VOLTAGE='6.3V',
 PART_NUMBER='CH5471MEB01',
 VALUE='4.7UF',
 PRIM_FILE='./archive_libs/logical/q_cap/chips/chips.prt';

PART_NAME
 C968 'Q_CAP_C0201-0.1UF,10V,10%,X7S,CH4102K6E00':;

SECTION_NUMBER 1
 '@T6G_MB_LIB.T6G(SCH_1):PAGE422_I69@PURE_QUANTA.Q_CAP(CHIPS)':
 C_PATH='@t6g_mb_lib.t6g(sch_1):page422_i69@pure_quanta.q_cap(chips)',
 P_PATH='@t6g_mb_lib.t6g(sch_1):page301_i69@pure_quanta.q_cap(chips)',
 PATH='I69',
 DRAWING='@T6G_MB_LIB.T6G(SCH_1):PAGE422',
 TOLERANCE='10%',
 MATERIAL='X7S',
 PHYS_PAGE='301',
 XY='(-1225,2525)',
 ROT='0',
 VER='1',
 PACK_TYPE='C0201',
 LOCATION='C968',
 CDS_LIB='pure_quanta',
 CDS_PART_NAME='Q_CAP_C0201-0.1UF,10V,10%,X7S,CH4102K6E00',
 VOLTAGE='10V',
 PART_NUMBER='CH4102K6E00',
 VALUE='0.1UF',
 PRIM_FILE='./archive_libs/logical/q_cap/chips/chips.prt';

PART_NAME
 C969 'Q_CAP_C0402-22UF,4V,20%,X6S,CH622KMEB02':;

SECTION_NUMBER 1
 '@T6G_MB_LIB.T6G(SCH_1):PAGE422_I59@PURE_QUANTA.Q_CAP(CHIPS)':
 C_PATH='@t6g_mb_lib.t6g(sch_1):page422_i59@pure_quanta.q_cap(chips)',
 P_PATH='@t6g_mb_lib.t6g(sch_1):page301_i59@pure_quanta.q_cap(chips)',
 PATH='I59',
 DRAWING='@T6G_MB_LIB.T6G(SCH_1):PAGE422',
 TOLERANCE='20%',
 MATERIAL='X6S',
 PHYS_PAGE='301',
 XY='(-2400,4475)',
 ROT='0',
 VER='1',
 PACK_TYPE='C0402',
 LOCATION='C969',
 CDS_LIB='pure_quanta',
 CDS_PART_NAME='Q_CAP_C0402-22UF,4V,20%,X6S,CH622KMEB02',
 VOLTAGE='4V',
 PART_NUMBER='CH622KMEB02',
 VALUE='22UF',
 PRIM_FILE='./archive_libs/logical/q_cap/chips/chips.prt';

PART_NAME
 C970 'Q_CAP_0402-4.7UF,6.3V,20%,X6S,CH5471MEB01':;

SECTION_NUMBER 1
 '@T6G_MB_LIB.T6G(SCH_1):PAGE422_I57@PURE_QUANTA.Q_CAP(CHIPS)':
 C_PATH='@t6g_mb_lib.t6g(sch_1):page422_i57@pure_quanta.q_cap(chips)',
 P_PATH='@t6g_mb_lib.t6g(sch_1):page301_i57@pure_quanta.q_cap(chips)',
 PATH='I57',
 DRAWING='@T6G_MB_LIB.T6G(SCH_1):PAGE422',
 TOLERANCE='20%',
 MATERIAL='X6S',
 PHYS_PAGE='301',
 XY='(-2400,3850)',
 ROT='0',
 VER='1',
 PACK_TYPE='0402',
 LOCATION='C970',
 CDS_LIB='pure_quanta',
 CDS_PART_NAME='Q_CAP_0402-4.7UF,6.3V,20%,X6S,CH5471MEB01',
 VOLTAGE='6.3V',
 PART_NUMBER='CH5471MEB01',
 VALUE='4.7UF',
 PRIM_FILE='./archive_libs/logical/q_cap/chips/chips.prt';

PART_NAME
 C971 'Q_CAP_C0402-10UF,6.3V,20%,X6S,CH6101MEB01':;

SECTION_NUMBER 1
 '@T6G_MB_LIB.T6G(SCH_1):PAGE422_I79@PURE_QUANTA.Q_CAP(CHIPS)':
 C_PATH='@t6g_mb_lib.t6g(sch_1):page422_i79@pure_quanta.q_cap(chips)',
 P_PATH='@t6g_mb_lib.t6g(sch_1):page301_i79@pure_quanta.q_cap(chips)',
 PATH='I79',
 DRAWING='@T6G_MB_LIB.T6G(SCH_1):PAGE422',
 TOLERANCE='20%',
 MATERIAL='X6S',
 PHYS_PAGE='301',
 XY='(-2675,5725)',
 ROT='0',
 VER='1',
 PACK_TYPE='C0402',
 LOCATION='C971',
 CDS_LIB='pure_quanta',
 CDS_PART_NAME='Q_CAP_C0402-10UF,6.3V,20%,X6S,CH6101MEB01',
 VOLTAGE='6.3V',
 PART_NUMBER='CH6101MEB01',
 VALUE='10UF',
 PRIM_FILE='./archive_libs/logical/q_cap/chips/chips.prt';

PART_NAME
 C972 'Q_CAP_C0201-0.1UF,10V,10%,X7S,CH4102K6E00':;

SECTION_NUMBER 1
 '@T6G_MB_LIB.T6G(SCH_1):PAGE422_I92@PURE_QUANTA.Q_CAP(CHIPS)':
 C_PATH='@t6g_mb_lib.t6g(sch_1):page422_i92@pure_quanta.q_cap(chips)',
 P_PATH='@t6g_mb_lib.t6g(sch_1):page301_i92@pure_quanta.q_cap(chips)',
 PATH='I92',
 DRAWING='@T6G_MB_LIB.T6G(SCH_1):PAGE422',
 TOLERANCE='10%',
 MATERIAL='X7S',
 PHYS_PAGE='301',
 XY='(-1575,3200)',
 ROT='0',
 VER='1',
 PACK_TYPE='C0201',
 LOCATION='C972',
 CDS_LIB='pure_quanta',
 CDS_PART_NAME='Q_CAP_C0201-0.1UF,10V,10%,X7S,CH4102K6E00',
 VOLTAGE='10V',
 PART_NUMBER='CH4102K6E00',
 VALUE='0.1UF',
 PRIM_FILE='./archive_libs/logical/q_cap/chips/chips.prt';

PART_NAME
 C973 'Q_CAP_C0402-10UF,6.3V,20%,X6S,CH6101MEB01':;

SECTION_NUMBER 1
 '@T6G_MB_LIB.T6G(SCH_1):PAGE422_I75@PURE_QUANTA.Q_CAP(CHIPS)':
 C_PATH='@t6g_mb_lib.t6g(sch_1):page422_i75@pure_quanta.q_cap(chips)',
 P_PATH='@t6g_mb_lib.t6g(sch_1):page301_i75@pure_quanta.q_cap(chips)',
 PATH='I75',
 DRAWING='@T6G_MB_LIB.T6G(SCH_1):PAGE422',
 TOLERANCE='20%',
 MATERIAL='X6S',
 PHYS_PAGE='301',
 XY='(-1125,4475)',
 ROT='0',
 VER='1',
 PACK_TYPE='C0402',
 LOCATION='C973',
 CDS_LIB='pure_quanta',
 CDS_PART_NAME='Q_CAP_C0402-10UF,6.3V,20%,X6S,CH6101MEB01',
 VOLTAGE='6.3V',
 PART_NUMBER='CH6101MEB01',
 VALUE='10UF',
 PRIM_FILE='./archive_libs/logical/q_cap/chips/chips.prt';

PART_NAME
 C974 'Q_CAP_C0402-22UF,4V,20%,X6S,CH622KMEB02':;

SECTION_NUMBER 1
 '@T6G_MB_LIB.T6G(SCH_1):PAGE422_I64@PURE_QUANTA.Q_CAP(CHIPS)':
 C_PATH='@t6g_mb_lib.t6g(sch_1):page422_i64@pure_quanta.q_cap(chips)',
 P_PATH='@t6g_mb_lib.t6g(sch_1):page301_i64@pure_quanta.q_cap(chips)',
 PATH='I64',
 DRAWING='@T6G_MB_LIB.T6G(SCH_1):PAGE422',
 TOLERANCE='20%',
 MATERIAL='X6S',
 PHYS_PAGE='301',
 XY='(-1950,4475)',
 ROT='0',
 VER='1',
 PACK_TYPE='C0402',
 LOCATION='C974',
 CDS_LIB='pure_quanta',
 CDS_PART_NAME='Q_CAP_C0402-22UF,4V,20%,X6S,CH622KMEB02',
 VOLTAGE='4V',
 PART_NUMBER='CH622KMEB02',
 VALUE='22UF',
 PRIM_FILE='./archive_libs/logical/q_cap/chips/chips.prt';

PART_NAME
 C975 'Q_CAP_0201-1UF,4V,20%,X6S,CH-10KMEE00':;

SECTION_NUMBER 1
 '@T6G_MB_LIB.T6G(SCH_1):PAGE422_I54@PURE_QUANTA.Q_CAP(CHIPS)':
 C_PATH='@t6g_mb_lib.t6g(sch_1):page422_i54@pure_quanta.q_cap(chips)',
 P_PATH='@t6g_mb_lib.t6g(sch_1):page301_i54@pure_quanta.q_cap(chips)',
 PATH='I54',
 DRAWING='@T6G_MB_LIB.T6G(SCH_1):PAGE422',
 TOLERANCE='20%',
 MATERIAL='X6S',
 PHYS_PAGE='301',
 XY='(-2375,3200)',
 ROT='0',
 VER='1',
 PACK_TYPE='0201',
 LOCATION='C975',
 CDS_LIB='pure_quanta',
 CDS_PART_NAME='Q_CAP_0201-1UF,4V,20%,X6S,CH-10KMEE00',
 VOLTAGE='4V',
 PART_NUMBER='CH-10KMEE00',
 VALUE='1UF',
 PRIM_FILE='./archive_libs/logical/q_cap/chips/chips.prt';

PART_NAME
 C976 'Q_CAP_0402-4.7UF,6.3V,20%,X6S,CH5471MEB01':;

SECTION_NUMBER 1
 '@T6G_MB_LIB.T6G(SCH_1):PAGE422_I80@PURE_QUANTA.Q_CAP(CHIPS)':
 C_PATH='@t6g_mb_lib.t6g(sch_1):page422_i80@pure_quanta.q_cap(chips)',
 P_PATH='@t6g_mb_lib.t6g(sch_1):page301_i80@pure_quanta.q_cap(chips)',
 PATH='I80',
 DRAWING='@T6G_MB_LIB.T6G(SCH_1):PAGE422',
 TOLERANCE='20%',
 MATERIAL='X6S',
 PHYS_PAGE='301',
 XY='(-2375,5725)',
 ROT='0',
 VER='1',
 PACK_TYPE='0402',
 LOCATION='C976',
 CDS_LIB='pure_quanta',
 CDS_PART_NAME='Q_CAP_0402-4.7UF,6.3V,20%,X6S,CH5471MEB01',
 VOLTAGE='6.3V',
 PART_NUMBER='CH5471MEB01',
 VALUE='4.7UF',
 PRIM_FILE='./archive_libs/logical/q_cap/chips/chips.prt';

PART_NAME
 C977 'Q_CAP_0402-4.7UF,6.3V,20%,X6S,CH5471MEB01':;

SECTION_NUMBER 1
 '@T6G_MB_LIB.T6G(SCH_1):PAGE422_I60@PURE_QUANTA.Q_CAP(CHIPS)':
 C_PATH='@t6g_mb_lib.t6g(sch_1):page422_i60@pure_quanta.q_cap(chips)',
 P_PATH='@t6g_mb_lib.t6g(sch_1):page301_i60@pure_quanta.q_cap(chips)',
 PATH='I60',
 DRAWING='@T6G_MB_LIB.T6G(SCH_1):PAGE422',
 TOLERANCE='20%',
 MATERIAL='X6S',
 PHYS_PAGE='301',
 XY='(-2175,3850)',
 ROT='0',
 VER='1',
 PACK_TYPE='0402',
 LOCATION='C977',
 CDS_LIB='pure_quanta',
 CDS_PART_NAME='Q_CAP_0402-4.7UF,6.3V,20%,X6S,CH5471MEB01',
 VOLTAGE='6.3V',
 PART_NUMBER='CH5471MEB01',
 VALUE='4.7UF',
 PRIM_FILE='./archive_libs/logical/q_cap/chips/chips.prt';

PART_NAME
 C978 'Q_CAP_0201-1UF,4V,20%,X6S,CH-10KMEE00':;

SECTION_NUMBER 1
 '@T6G_MB_LIB.T6G(SCH_1):PAGE422_I61@PURE_QUANTA.Q_CAP(CHIPS)':
 C_PATH='@t6g_mb_lib.t6g(sch_1):page422_i61@pure_quanta.q_cap(chips)',
 P_PATH='@t6g_mb_lib.t6g(sch_1):page301_i61@pure_quanta.q_cap(chips)',
 PATH='I61',
 DRAWING='@T6G_MB_LIB.T6G(SCH_1):PAGE422',
 TOLERANCE='20%',
 MATERIAL='X6S',
 PHYS_PAGE='301',
 XY='(-1950,3850)',
 ROT='0',
 VER='1',
 PACK_TYPE='0201',
 LOCATION='C978',
 CDS_LIB='pure_quanta',
 CDS_PART_NAME='Q_CAP_0201-1UF,4V,20%,X6S,CH-10KMEE00',
 VOLTAGE='4V',
 PART_NUMBER='CH-10KMEE00',
 VALUE='1UF',
 PRIM_FILE='./archive_libs/logical/q_cap/chips/chips.prt';

PART_NAME
 C979 'Q_CAP_0201-1UF,4V,20%,X6S,CH-10KMEE00':;

SECTION_NUMBER 1
 '@T6G_MB_LIB.T6G(SCH_1):PAGE422_I55@PURE_QUANTA.Q_CAP(CHIPS)':
 C_PATH='@t6g_mb_lib.t6g(sch_1):page422_i55@pure_quanta.q_cap(chips)',
 P_PATH='@t6g_mb_lib.t6g(sch_1):page301_i55@pure_quanta.q_cap(chips)',
 PATH='I55',
 DRAWING='@T6G_MB_LIB.T6G(SCH_1):PAGE422',
 TOLERANCE='20%',
 MATERIAL='X6S',
 PHYS_PAGE='301',
 XY='(-2100,3200)',
 ROT='0',
 VER='1',
 PACK_TYPE='0201',
 LOCATION='C979',
 CDS_LIB='pure_quanta',
 CDS_PART_NAME='Q_CAP_0201-1UF,4V,20%,X6S,CH-10KMEE00',
 VOLTAGE='4V',
 PART_NUMBER='CH-10KMEE00',
 VALUE='1UF',
 PRIM_FILE='./archive_libs/logical/q_cap/chips/chips.prt';

PART_NAME
 C980 'Q_CAP_0201-1UF,4V,20%,X6S,CH-10KMEE00':;

SECTION_NUMBER 1
 '@T6G_MB_LIB.T6G(SCH_1):PAGE422_I81@PURE_QUANTA.Q_CAP(CHIPS)':
 C_PATH='@t6g_mb_lib.t6g(sch_1):page422_i81@pure_quanta.q_cap(chips)',
 P_PATH='@t6g_mb_lib.t6g(sch_1):page301_i81@pure_quanta.q_cap(chips)',
 PATH='I81',
 DRAWING='@T6G_MB_LIB.T6G(SCH_1):PAGE422',
 TOLERANCE='20%',
 MATERIAL='X6S',
 PHYS_PAGE='301',
 XY='(-2075,5725)',
 ROT='0',
 VER='1',
 PACK_TYPE='0201',
 LOCATION='C980',
 CDS_LIB='pure_quanta',
 CDS_PART_NAME='Q_CAP_0201-1UF,4V,20%,X6S,CH-10KMEE00',
 VOLTAGE='4V',
 PART_NUMBER='CH-10KMEE00',
 VALUE='1UF',
 PRIM_FILE='./archive_libs/logical/q_cap/chips/chips.prt';

PART_NAME
 C981 'Q_CAP_0402-4.7UF,6.3V,20%,X6S,CH5471MEB01':;

SECTION_NUMBER 1
 '@T6G_MB_LIB.T6G(SCH_1):PAGE422_I49@PURE_QUANTA.Q_CAP(CHIPS)':
 C_PATH='@t6g_mb_lib.t6g(sch_1):page422_i49@pure_quanta.q_cap(chips)',
 P_PATH='@t6g_mb_lib.t6g(sch_1):page301_i49@pure_quanta.q_cap(chips)',
 PATH='I49',
 DRAWING='@T6G_MB_LIB.T6G(SCH_1):PAGE422',
 TOLERANCE='20%',
 MATERIAL='X6S',
 PHYS_PAGE='301',
 XY='(-2875,3850)',
 ROT='0',
 VER='1',
 PACK_TYPE='0402',
 LOCATION='C981',
 CDS_LIB='pure_quanta',
 CDS_PART_NAME='Q_CAP_0402-4.7UF,6.3V,20%,X6S,CH5471MEB01',
 VOLTAGE='6.3V',
 PART_NUMBER='CH5471MEB01',
 VALUE='4.7UF',
 PRIM_FILE='./archive_libs/logical/q_cap/chips/chips.prt';

PART_NAME
 C982 'Q_CAP_C0201-0.1UF,10V,10%,X7S,CH4102K6E00':;

SECTION_NUMBER 1
 '@T6G_MB_LIB.T6G(SCH_1):PAGE422_I34@PURE_QUANTA.Q_CAP(CHIPS)':
 C_PATH='@t6g_mb_lib.t6g(sch_1):page422_i34@pure_quanta.q_cap(chips)',
 P_PATH='@t6g_mb_lib.t6g(sch_1):page301_i34@pure_quanta.q_cap(chips)',
 PATH='I34',
 DRAWING='@T6G_MB_LIB.T6G(SCH_1):PAGE422',
 TOLERANCE='10%',
 MATERIAL='X7S',
 PHYS_PAGE='301',
 XY='(-3050,2525)',
 ROT='0',
 VER='1',
 PACK_TYPE='C0201',
 LOCATION='C982',
 CDS_LIB='pure_quanta',
 CDS_PART_NAME='Q_CAP_C0201-0.1UF,10V,10%,X7S,CH4102K6E00',
 VOLTAGE='10V',
 PART_NUMBER='CH4102K6E00',
 VALUE='0.1UF',
 PRIM_FILE='./archive_libs/logical/q_cap/chips/chips.prt';

PART_NAME
 C983 'Q_CAP_0201-1UF,4V,20%,X6S,CH-10KMEE00':;

SECTION_NUMBER 1
 '@T6G_MB_LIB.T6G(SCH_1):PAGE422_I66@PURE_QUANTA.Q_CAP(CHIPS)':
 C_PATH='@t6g_mb_lib.t6g(sch_1):page422_i66@pure_quanta.q_cap(chips)',
 P_PATH='@t6g_mb_lib.t6g(sch_1):page301_i66@pure_quanta.q_cap(chips)',
 PATH='I66',
 DRAWING='@T6G_MB_LIB.T6G(SCH_1):PAGE422',
 TOLERANCE='20%',
 MATERIAL='X6S',
 PHYS_PAGE='301',
 XY='(-1825,3200)',
 ROT='0',
 VER='1',
 PACK_TYPE='0201',
 LOCATION='C983',
 CDS_LIB='pure_quanta',
 CDS_PART_NAME='Q_CAP_0201-1UF,4V,20%,X6S,CH-10KMEE00',
 VOLTAGE='4V',
 PART_NUMBER='CH-10KMEE00',
 VALUE='1UF',
 PRIM_FILE='./archive_libs/logical/q_cap/chips/chips.prt';

PART_NAME
 C984 'Q_CAP_C0201-0.1UF,10V,10%,X7S,CH4102K6E00':;

SECTION_NUMBER 1
 '@T6G_MB_LIB.T6G(SCH_1):PAGE422_I35@PURE_QUANTA.Q_CAP(CHIPS)':
 C_PATH='@t6g_mb_lib.t6g(sch_1):page422_i35@pure_quanta.q_cap(chips)',
 P_PATH='@t6g_mb_lib.t6g(sch_1):page301_i35@pure_quanta.q_cap(chips)',
 PATH='I35',
 DRAWING='@T6G_MB_LIB.T6G(SCH_1):PAGE422',
 TOLERANCE='10%',
 MATERIAL='X7S',
 PHYS_PAGE='301',
 XY='(-2750,2525)',
 ROT='0',
 VER='1',
 PACK_TYPE='C0201',
 LOCATION='C984',
 CDS_LIB='pure_quanta',
 CDS_PART_NAME='Q_CAP_C0201-0.1UF,10V,10%,X7S,CH4102K6E00',
 VOLTAGE='10V',
 PART_NUMBER='CH4102K6E00',
 VALUE='0.1UF',
 PRIM_FILE='./archive_libs/logical/q_cap/chips/chips.prt';

PART_NAME
 C985 'Q_CAP_C0201-0.1UF,10V,10%,X7S,CH4102K6E00':;

SECTION_NUMBER 1
 '@T6G_MB_LIB.T6G(SCH_1):PAGE422_I93@PURE_QUANTA.Q_CAP(CHIPS)':
 C_PATH='@t6g_mb_lib.t6g(sch_1):page422_i93@pure_quanta.q_cap(chips)',
 P_PATH='@t6g_mb_lib.t6g(sch_1):page301_i93@pure_quanta.q_cap(chips)',
 PATH='I93',
 DRAWING='@T6G_MB_LIB.T6G(SCH_1):PAGE422',
 TOLERANCE='10%',
 MATERIAL='X7S',
 PHYS_PAGE='301',
 XY='(-1325,3200)',
 ROT='0',
 VER='1',
 PACK_TYPE='C0201',
 LOCATION='C985',
 CDS_LIB='pure_quanta',
 CDS_PART_NAME='Q_CAP_C0201-0.1UF,10V,10%,X7S,CH4102K6E00',
 VOLTAGE='10V',
 PART_NUMBER='CH4102K6E00',
 VALUE='0.1UF',
 PRIM_FILE='./archive_libs/logical/q_cap/chips/chips.prt';

PART_NAME
 C986 'Q_CAP_C0402-10UF,6.3V,20%,X6S,CH6101MEB01':;

SECTION_NUMBER 1
 '@T6G_MB_LIB.T6G(SCH_1):PAGE422_I74@PURE_QUANTA.Q_CAP(CHIPS)':
 C_PATH='@t6g_mb_lib.t6g(sch_1):page422_i74@pure_quanta.q_cap(chips)',
 P_PATH='@t6g_mb_lib.t6g(sch_1):page301_i74@pure_quanta.q_cap(chips)',
 PATH='I74',
 DRAWING='@T6G_MB_LIB.T6G(SCH_1):PAGE422',
 TOLERANCE='20%',
 MATERIAL='X6S',
 PHYS_PAGE='301',
 XY='(-1425,4475)',
 ROT='0',
 VER='1',
 PACK_TYPE='C0402',
 LOCATION='C986',
 CDS_LIB='pure_quanta',
 CDS_PART_NAME='Q_CAP_C0402-10UF,6.3V,20%,X6S,CH6101MEB01',
 VOLTAGE='6.3V',
 PART_NUMBER='CH6101MEB01',
 VALUE='10UF',
 PRIM_FILE='./archive_libs/logical/q_cap/chips/chips.prt';

PART_NAME
 C987 'Q_CAP_C0201-0.1UF,10V,10%,X7S,CH4102K6E00':;

SECTION_NUMBER 1
 '@T6G_MB_LIB.T6G(SCH_1):PAGE422_I41@PURE_QUANTA.Q_CAP(CHIPS)':
 C_PATH='@t6g_mb_lib.t6g(sch_1):page422_i41@pure_quanta.q_cap(chips)',
 P_PATH='@t6g_mb_lib.t6g(sch_1):page301_i41@pure_quanta.q_cap(chips)',
 PATH='I41',
 DRAWING='@T6G_MB_LIB.T6G(SCH_1):PAGE422',
 TOLERANCE='10%',
 MATERIAL='X7S',
 PHYS_PAGE='301',
 XY='(-2275,2525)',
 ROT='0',
 VER='1',
 PACK_TYPE='C0201',
 LOCATION='C987',
 CDS_LIB='pure_quanta',
 CDS_PART_NAME='Q_CAP_C0201-0.1UF,10V,10%,X7S,CH4102K6E00',
 VOLTAGE='10V',
 PART_NUMBER='CH4102K6E00',
 VALUE='0.1UF',
 PRIM_FILE='./archive_libs/logical/q_cap/chips/chips.prt';

PART_NAME
 C988 'Q_CAP_C0402-22UF,4V,20%,X6S,CH622KMEB02':;

SECTION_NUMBER 1
 '@T6G_MB_LIB.T6G(SCH_1):PAGE422_I63@PURE_QUANTA.Q_CAP(CHIPS)':
 C_PATH='@t6g_mb_lib.t6g(sch_1):page422_i63@pure_quanta.q_cap(chips)',
 P_PATH='@t6g_mb_lib.t6g(sch_1):page301_i63@pure_quanta.q_cap(chips)',
 PATH='I63',
 DRAWING='@T6G_MB_LIB.T6G(SCH_1):PAGE422',
 TOLERANCE='20%',
 MATERIAL='X6S',
 PHYS_PAGE='301',
 XY='(-2175,4475)',
 ROT='0',
 VER='1',
 PACK_TYPE='C0402',
 LOCATION='C988',
 CDS_LIB='pure_quanta',
 CDS_PART_NAME='Q_CAP_C0402-22UF,4V,20%,X6S,CH622KMEB02',
 VOLTAGE='4V',
 PART_NUMBER='CH622KMEB02',
 VALUE='22UF',
 PRIM_FILE='./archive_libs/logical/q_cap/chips/chips.prt';

PART_NAME
 C989 'Q_CAP_C0201-0.1UF,10V,10%,X7S,CH4102K6E00':;

SECTION_NUMBER 1
 '@T6G_MB_LIB.T6G(SCH_1):PAGE421_I23@PURE_QUANTA.Q_CAP(CHIPS)':
 C_PATH='@t6g_mb_lib.t6g(sch_1):page421_i23@pure_quanta.q_cap(chips)',
 P_PATH='@t6g_mb_lib.t6g(sch_1):page300_i23@pure_quanta.q_cap(chips)',
 PATH='I23',
 DRAWING='@T6G_MB_LIB.T6G(SCH_1):PAGE421',
 TOLERANCE='10%',
 MATERIAL='X7S',
 PHYS_PAGE='300',
 XY='(-5550,6150)',
 ROT='0',
 VER='1',
 PACK_TYPE='C0201',
 LOCATION='C989',
 CDS_LIB='pure_quanta',
 CDS_PART_NAME='Q_CAP_C0201-0.1UF,10V,10%,X7S,CH4102K6E00',
 VOLTAGE='10V',
 PART_NUMBER='CH4102K6E00',
 VALUE='0.1UF',
 PRIM_FILE='./archive_libs/logical/q_cap/chips/chips.prt';

PART_NAME
 C990 'Q_CAP_C0805-100UF,4V,20%,X6S,CH710KMEA01':;

SECTION_NUMBER 1
 '@T6G_MB_LIB.T6G(SCH_1):PAGE433_I19@PURE_QUANTA.Q_CAP(CHIPS)':
 C_PATH='@t6g_mb_lib.t6g(sch_1):page433_i19@pure_quanta.q_cap(chips)',
 P_PATH='@t6g_mb_lib.t6g(sch_1):page312_i19@pure_quanta.q_cap(chips)',
 PATH='I19',
 DRAWING='@T6G_MB_LIB.T6G(SCH_1):PAGE433',
 TOLERANCE='20%',
 MATERIAL='X6S',
 PHYS_PAGE='312',
 XY='(-7200,5200)',
 ROT='0',
 VER='1',
 PACK_TYPE='C0805',
 LOCATION='C990',
 CDS_LIB='pure_quanta',
 CDS_PART_NAME='Q_CAP_C0805-100UF,4V,20%,X6S,CH710KMEA01',
 VOLTAGE='4V',
 PART_NUMBER='CH710KMEA01',
 VALUE='100UF',
 PRIM_FILE='./archive_libs/logical/q_cap/chips/chips.prt';

PART_NAME
 C991 'Q_CAP_C0805-100UF,4V,20%,X6S,CH710KMEA01':;

SECTION_NUMBER 1
 '@T6G_MB_LIB.T6G(SCH_1):PAGE433_I12@PURE_QUANTA.Q_CAP(CHIPS)':
 C_PATH='@t6g_mb_lib.t6g(sch_1):page433_i12@pure_quanta.q_cap(chips)',
 P_PATH='@t6g_mb_lib.t6g(sch_1):page312_i12@pure_quanta.q_cap(chips)',
 PATH='I12',
 DRAWING='@T6G_MB_LIB.T6G(SCH_1):PAGE433',
 TOLERANCE='20%',
 MATERIAL='X6S',
 PHYS_PAGE='312',
 XY='(-7350,4375)',
 ROT='0',
 VER='1',
 PACK_TYPE='C0805',
 LOCATION='C991',
 CDS_LIB='pure_quanta',
 CDS_PART_NAME='Q_CAP_C0805-100UF,4V,20%,X6S,CH710KMEA01',
 VOLTAGE='4V',
 PART_NUMBER='CH710KMEA01',
 VALUE='100UF',
 PRIM_FILE='./archive_libs/logical/q_cap/chips/chips.prt';

PART_NAME
 C992 'Q_CAP_C0402-22UF,4V,20%,X6S,CH622KMEB02':;

SECTION_NUMBER 1
 '@T6G_MB_LIB.T6G(SCH_1):PAGE433_I20@PURE_QUANTA.Q_CAP(CHIPS)':
 C_PATH='@t6g_mb_lib.t6g(sch_1):page433_i20@pure_quanta.q_cap(chips)',
 P_PATH='@t6g_mb_lib.t6g(sch_1):page312_i20@pure_quanta.q_cap(chips)',
 PATH='I20',
 DRAWING='@T6G_MB_LIB.T6G(SCH_1):PAGE433',
 TOLERANCE='20%',
 MATERIAL='X6S',
 PHYS_PAGE='312',
 XY='(-6950,5200)',
 ROT='0',
 VER='1',
 PACK_TYPE='C0402',
 LOCATION='C992',
 CDS_LIB='pure_quanta',
 CDS_PART_NAME='Q_CAP_C0402-22UF,4V,20%,X6S,CH622KMEB02',
 VOLTAGE='4V',
 PART_NUMBER='CH622KMEB02',
 VALUE='22UF',
 PRIM_FILE='./archive_libs/logical/q_cap/chips/chips.prt';

PART_NAME
 C993 'Q_CAP_C0402-22UF,4V,20%,X6S,CH622KMEB02':;

SECTION_NUMBER 1
 '@T6G_MB_LIB.T6G(SCH_1):PAGE433_I13@PURE_QUANTA.Q_CAP(CHIPS)':
 C_PATH='@t6g_mb_lib.t6g(sch_1):page433_i13@pure_quanta.q_cap(chips)',
 P_PATH='@t6g_mb_lib.t6g(sch_1):page312_i13@pure_quanta.q_cap(chips)',
 PATH='I13',
 DRAWING='@T6G_MB_LIB.T6G(SCH_1):PAGE433',
 TOLERANCE='20%',
 MATERIAL='X6S',
 PHYS_PAGE='312',
 XY='(-7125,4375)',
 ROT='0',
 VER='1',
 PACK_TYPE='C0402',
 LOCATION='C993',
 CDS_LIB='pure_quanta',
 CDS_PART_NAME='Q_CAP_C0402-22UF,4V,20%,X6S,CH622KMEB02',
 VOLTAGE='4V',
 PART_NUMBER='CH622KMEB02',
 VALUE='22UF',
 PRIM_FILE='./archive_libs/logical/q_cap/chips/chips.prt';

PART_NAME
 C994 'Q_CAP_C0402-10UF,6.3V,20%,X6S,CH6101MEB01':;

SECTION_NUMBER 1
 '@T6G_MB_LIB.T6G(SCH_1):PAGE433_I21@PURE_QUANTA.Q_CAP(CHIPS)':
 C_PATH='@t6g_mb_lib.t6g(sch_1):page433_i21@pure_quanta.q_cap(chips)',
 P_PATH='@t6g_mb_lib.t6g(sch_1):page312_i21@pure_quanta.q_cap(chips)',
 PATH='I21',
 DRAWING='@T6G_MB_LIB.T6G(SCH_1):PAGE433',
 TOLERANCE='20%',
 MATERIAL='X6S',
 PHYS_PAGE='312',
 XY='(-6700,5175)',
 ROT='0',
 VER='1',
 PACK_TYPE='C0402',
 LOCATION='C994',
 CDS_LIB='pure_quanta',
 CDS_PART_NAME='Q_CAP_C0402-10UF,6.3V,20%,X6S,CH6101MEB01',
 VOLTAGE='6.3V',
 PART_NUMBER='CH6101MEB01',
 VALUE='10UF',
 PRIM_FILE='./archive_libs/logical/q_cap/chips/chips.prt';

PART_NAME
 C995 'Q_CAP_C0402-10UF,6.3V,20%,X6S,CH6101MEB01':;

SECTION_NUMBER 1
 '@T6G_MB_LIB.T6G(SCH_1):PAGE433_I15@PURE_QUANTA.Q_CAP(CHIPS)':
 C_PATH='@t6g_mb_lib.t6g(sch_1):page433_i15@pure_quanta.q_cap(chips)',
 P_PATH='@t6g_mb_lib.t6g(sch_1):page312_i15@pure_quanta.q_cap(chips)',
 PATH='I15',
 DRAWING='@T6G_MB_LIB.T6G(SCH_1):PAGE433',
 TOLERANCE='20%',
 MATERIAL='X6S',
 PHYS_PAGE='312',
 XY='(-6925,4375)',
 ROT='0',
 VER='1',
 PACK_TYPE='C0402',
 LOCATION='C995',
 CDS_LIB='pure_quanta',
 CDS_PART_NAME='Q_CAP_C0402-10UF,6.3V,20%,X6S,CH6101MEB01',
 VOLTAGE='6.3V',
 PART_NUMBER='CH6101MEB01',
 VALUE='10UF',
 PRIM_FILE='./archive_libs/logical/q_cap/chips/chips.prt';

PART_NAME
 C996 'Q_CAP_0402-4.7UF,6.3V,20%,X6S,CH5471MEB01':;

SECTION_NUMBER 1
 '@T6G_MB_LIB.T6G(SCH_1):PAGE433_I16@PURE_QUANTA.Q_CAP(CHIPS)':
 C_PATH='@t6g_mb_lib.t6g(sch_1):page433_i16@pure_quanta.q_cap(chips)',
 P_PATH='@t6g_mb_lib.t6g(sch_1):page312_i16@pure_quanta.q_cap(chips)',
 PATH='I16',
 DRAWING='@T6G_MB_LIB.T6G(SCH_1):PAGE433',
 TOLERANCE='20%',
 MATERIAL='X6S',
 PHYS_PAGE='312',
 XY='(-6725,4375)',
 ROT='0',
 VER='1',
 PACK_TYPE='0402',
 LOCATION='C996',
 CDS_LIB='pure_quanta',
 CDS_PART_NAME='Q_CAP_0402-4.7UF,6.3V,20%,X6S,CH5471MEB01',
 VOLTAGE='6.3V',
 PART_NUMBER='CH5471MEB01',
 VALUE='4.7UF',
 PRIM_FILE='./archive_libs/logical/q_cap/chips/chips.prt';

PART_NAME
 C997 'Q_CAP_0402-4.7UF,6.3V,20%,X6S,CH5471MEB01':;

SECTION_NUMBER 1
 '@T6G_MB_LIB.T6G(SCH_1):PAGE433_I22@PURE_QUANTA.Q_CAP(CHIPS)':
 C_PATH='@t6g_mb_lib.t6g(sch_1):page433_i22@pure_quanta.q_cap(chips)',
 P_PATH='@t6g_mb_lib.t6g(sch_1):page312_i22@pure_quanta.q_cap(chips)',
 PATH='I22',
 DRAWING='@T6G_MB_LIB.T6G(SCH_1):PAGE433',
 TOLERANCE='20%',
 MATERIAL='X6S',
 PHYS_PAGE='312',
 XY='(-6450,5175)',
 ROT='0',
 VER='1',
 PACK_TYPE='0402',
 LOCATION='C997',
 CDS_LIB='pure_quanta',
 CDS_PART_NAME='Q_CAP_0402-4.7UF,6.3V,20%,X6S,CH5471MEB01',
 VOLTAGE='6.3V',
 PART_NUMBER='CH5471MEB01',
 VALUE='4.7UF',
 PRIM_FILE='./archive_libs/logical/q_cap/chips/chips.prt';

PART_NAME
 C998 'Q_CAP_0201-1UF,4V,20%,X6S,CH-10KMEE00':;

SECTION_NUMBER 1
 '@T6G_MB_LIB.T6G(SCH_1):PAGE433_I17@PURE_QUANTA.Q_CAP(CHIPS)':
 C_PATH='@t6g_mb_lib.t6g(sch_1):page433_i17@pure_quanta.q_cap(chips)',
 P_PATH='@t6g_mb_lib.t6g(sch_1):page312_i17@pure_quanta.q_cap(chips)',
 PATH='I17',
 DRAWING='@T6G_MB_LIB.T6G(SCH_1):PAGE433',
 TOLERANCE='20%',
 MATERIAL='X6S',
 PHYS_PAGE='312',
 XY='(-6500,4375)',
 ROT='0',
 VER='1',
 PACK_TYPE='0201',
 LOCATION='C998',
 CDS_LIB='pure_quanta',
 CDS_PART_NAME='Q_CAP_0201-1UF,4V,20%,X6S,CH-10KMEE00',
 VOLTAGE='4V',
 PART_NUMBER='CH-10KMEE00',
 VALUE='1UF',
 PRIM_FILE='./archive_libs/logical/q_cap/chips/chips.prt';

PART_NAME
 C999 'Q_CAP_0201-1UF,4V,20%,X6S,CH-10KMEE00':;

SECTION_NUMBER 1
 '@T6G_MB_LIB.T6G(SCH_1):PAGE433_I5@PURE_QUANTA.Q_CAP(CHIPS)':
 C_PATH='@t6g_mb_lib.t6g(sch_1):page433_i5@pure_quanta.q_cap(chips)',
 P_PATH='@t6g_mb_lib.t6g(sch_1):page312_i5@pure_quanta.q_cap(chips)',
 PATH='I5',
 DRAWING='@T6G_MB_LIB.T6G(SCH_1):PAGE433',
 TOLERANCE='20%',
 MATERIAL='X6S',
 PHYS_PAGE='312',
 XY='(-6925,3300)',
 ROT='0',
 VER='1',
 PACK_TYPE='0201',
 LOCATION='C999',
 CDS_LIB='pure_quanta',
 CDS_PART_NAME='Q_CAP_0201-1UF,4V,20%,X6S,CH-10KMEE00',
 VOLTAGE='4V',
 PART_NUMBER='CH-10KMEE00',
 VALUE='1UF',
 PRIM_FILE='./archive_libs/logical/q_cap/chips/chips.prt';

PART_NAME
 C1000 'Q_CAP_0201-1UF,4V,20%,X6S,CH-10KMEE00':;

SECTION_NUMBER 1
 '@T6G_MB_LIB.T6G(SCH_1):PAGE433_I24@PURE_QUANTA.Q_CAP(CHIPS)':
 C_PATH='@t6g_mb_lib.t6g(sch_1):page433_i24@pure_quanta.q_cap(chips)',
 P_PATH='@t6g_mb_lib.t6g(sch_1):page312_i24@pure_quanta.q_cap(chips)',
 PATH='I24',
 DRAWING='@T6G_MB_LIB.T6G(SCH_1):PAGE433',
 TOLERANCE='20%',
 MATERIAL='X6S',
 PHYS_PAGE='312',
 XY='(-6300,4375)',
 ROT='0',
 VER='1',
 PACK_TYPE='0201',
 LOCATION='C1000',
 CDS_LIB='pure_quanta',
 CDS_PART_NAME='Q_CAP_0201-1UF,4V,20%,X6S,CH-10KMEE00',
 VOLTAGE='4V',
 PART_NUMBER='CH-10KMEE00',
 VALUE='1UF',
 PRIM_FILE='./archive_libs/logical/q_cap/chips/chips.prt';

PART_NAME
 C1001 'Q_CAP_C0201-0.1UF,10V,10%,X7S,CH4102K6E00':;

SECTION_NUMBER 1
 '@T6G_MB_LIB.T6G(SCH_1):PAGE433_I25@PURE_QUANTA.Q_CAP(CHIPS)':
 C_PATH='@t6g_mb_lib.t6g(sch_1):page433_i25@pure_quanta.q_cap(chips)',
 P_PATH='@t6g_mb_lib.t6g(sch_1):page312_i25@pure_quanta.q_cap(chips)',
 PATH='I25',
 DRAWING='@T6G_MB_LIB.T6G(SCH_1):PAGE433',
 TOLERANCE='10%',
 MATERIAL='X7S',
 PHYS_PAGE='312',
 XY='(-6075,4375)',
 ROT='0',
 VER='1',
 PACK_TYPE='C0201',
 LOCATION='C1001',
 CDS_LIB='pure_quanta',
 CDS_PART_NAME='Q_CAP_C0201-0.1UF,10V,10%,X7S,CH4102K6E00',
 VOLTAGE='10V',
 PART_NUMBER='CH4102K6E00',
 VALUE='0.1UF',
 PRIM_FILE='./archive_libs/logical/q_cap/chips/chips.prt';

PART_NAME
 C1002 'Q_CAP_C0201-0.1UF,10V,10%,X7S,CH4102K6E00':;

SECTION_NUMBER 1
 '@T6G_MB_LIB.T6G(SCH_1):PAGE433_I6@PURE_QUANTA.Q_CAP(CHIPS)':
 C_PATH='@t6g_mb_lib.t6g(sch_1):page433_i6@pure_quanta.q_cap(chips)',
 P_PATH='@t6g_mb_lib.t6g(sch_1):page312_i6@pure_quanta.q_cap(chips)',
 PATH='I6',
 DRAWING='@T6G_MB_LIB.T6G(SCH_1):PAGE433',
 TOLERANCE='10%',
 MATERIAL='X7S',
 PHYS_PAGE='312',
 XY='(-6650,3275)',
 ROT='0',
 VER='1',
 PACK_TYPE='C0201',
 LOCATION='C1002',
 CDS_LIB='pure_quanta',
 CDS_PART_NAME='Q_CAP_C0201-0.1UF,10V,10%,X7S,CH4102K6E00',
 VOLTAGE='10V',
 PART_NUMBER='CH4102K6E00',
 VALUE='0.1UF',
 PRIM_FILE='./archive_libs/logical/q_cap/chips/chips.prt';

PART_NAME
 C1003 'Q_CAP_C0201-0.1UF,10V,10%,X7S,CH4102K6E00':;

SECTION_NUMBER 1
 '@T6G_MB_LIB.T6G(SCH_1):PAGE433_I26@PURE_QUANTA.Q_CAP(CHIPS)':
 C_PATH='@t6g_mb_lib.t6g(sch_1):page433_i26@pure_quanta.q_cap(chips)',
 P_PATH='@t6g_mb_lib.t6g(sch_1):page312_i26@pure_quanta.q_cap(chips)',
 PATH='I26',
 DRAWING='@T6G_MB_LIB.T6G(SCH_1):PAGE433',
 TOLERANCE='10%',
 MATERIAL='X7S',
 PHYS_PAGE='312',
 XY='(-5825,4375)',
 ROT='0',
 VER='1',
 PACK_TYPE='C0201',
 LOCATION='C1003',
 CDS_LIB='pure_quanta',
 CDS_PART_NAME='Q_CAP_C0201-0.1UF,10V,10%,X7S,CH4102K6E00',
 VOLTAGE='10V',
 PART_NUMBER='CH4102K6E00',
 VALUE='0.1UF',
 PRIM_FILE='./archive_libs/logical/q_cap/chips/chips.prt';

PART_NAME
 C1004 'Q_CAP_C0201-0.1UF,10V,10%,X7S,CH4102K6E00':;

SECTION_NUMBER 1
 '@T6G_MB_LIB.T6G(SCH_1):PAGE433_I27@PURE_QUANTA.Q_CAP(CHIPS)':
 C_PATH='@t6g_mb_lib.t6g(sch_1):page433_i27@pure_quanta.q_cap(chips)',
 P_PATH='@t6g_mb_lib.t6g(sch_1):page312_i27@pure_quanta.q_cap(chips)',
 PATH='I27',
 DRAWING='@T6G_MB_LIB.T6G(SCH_1):PAGE433',
 TOLERANCE='10%',
 MATERIAL='X7S',
 PHYS_PAGE='312',
 XY='(-5575,4375)',
 ROT='0',
 VER='1',
 PACK_TYPE='C0201',
 LOCATION='C1004',
 CDS_LIB='pure_quanta',
 CDS_PART_NAME='Q_CAP_C0201-0.1UF,10V,10%,X7S,CH4102K6E00',
 VOLTAGE='10V',
 PART_NUMBER='CH4102K6E00',
 VALUE='0.1UF',
 PRIM_FILE='./archive_libs/logical/q_cap/chips/chips.prt';

PART_NAME
 C1005 'Q_CAP_C0201-0.1UF,10V,10%,X7S,CH4102K6E00':;

SECTION_NUMBER 1
 '@T6G_MB_LIB.T6G(SCH_1):PAGE433_I28@PURE_QUANTA.Q_CAP(CHIPS)':
 C_PATH='@t6g_mb_lib.t6g(sch_1):page433_i28@pure_quanta.q_cap(chips)',
 P_PATH='@t6g_mb_lib.t6g(sch_1):page312_i28@pure_quanta.q_cap(chips)',
 PATH='I28',
 DRAWING='@T6G_MB_LIB.T6G(SCH_1):PAGE433',
 TOLERANCE='10%',
 MATERIAL='X7S',
 PHYS_PAGE='312',
 XY='(-5300,4375)',
 ROT='0',
 VER='1',
 PACK_TYPE='C0201',
 LOCATION='C1005',
 CDS_LIB='pure_quanta',
 CDS_PART_NAME='Q_CAP_C0201-0.1UF,10V,10%,X7S,CH4102K6E00',
 VOLTAGE='10V',
 PART_NUMBER='CH4102K6E00',
 VALUE='0.1UF',
 PRIM_FILE='./archive_libs/logical/q_cap/chips/chips.prt';

PART_NAME
 C1006 'Q_CAP_0201-1UF,4V,20%,X6S,CH-10KMEE00':;

SECTION_NUMBER 1
 '@T6G_MB_LIB.T6G(SCH_1):PAGE433_I46@PURE_QUANTA.Q_CAP(CHIPS)':
 C_PATH='@t6g_mb_lib.t6g(sch_1):page433_i46@pure_quanta.q_cap(chips)',
 P_PATH='@t6g_mb_lib.t6g(sch_1):page312_i46@pure_quanta.q_cap(chips)',
 PATH='I46',
 DRAWING='@T6G_MB_LIB.T6G(SCH_1):PAGE433',
 TOLERANCE='20%',
 MATERIAL='X6S',
 PHYS_PAGE='312',
 XY='(-2925,3125)',
 ROT='0',
 VER='1',
 PACK_TYPE='0201',
 LOCATION='C1006',
 CDS_LIB='pure_quanta',
 CDS_PART_NAME='Q_CAP_0201-1UF,4V,20%,X6S,CH-10KMEE00',
 VOLTAGE='4V',
 PART_NUMBER='CH-10KMEE00',
 VALUE='1UF',
 PRIM_FILE='./archive_libs/logical/q_cap/chips/chips.prt';

PART_NAME
 C1007 'Q_CAP_C0201-0.1UF,10V,10%,X7S,CH4102K6E00':;

SECTION_NUMBER 1
 '@T6G_MB_LIB.T6G(SCH_1):PAGE433_I81@PURE_QUANTA.Q_CAP(CHIPS)':
 C_PATH='@t6g_mb_lib.t6g(sch_1):page433_i81@pure_quanta.q_cap(chips)',
 P_PATH='@t6g_mb_lib.t6g(sch_1):page312_i81@pure_quanta.q_cap(chips)',
 PATH='I81',
 DRAWING='@T6G_MB_LIB.T6G(SCH_1):PAGE433',
 TOLERANCE='10%',
 MATERIAL='X7S',
 PHYS_PAGE='312',
 XY='(-2075,5600)',
 ROT='0',
 VER='1',
 PACK_TYPE='C0201',
 LOCATION='C1007',
 CDS_LIB='pure_quanta',
 CDS_PART_NAME='Q_CAP_C0201-0.1UF,10V,10%,X7S,CH4102K6E00',
 VOLTAGE='10V',
 PART_NUMBER='CH4102K6E00',
 VALUE='0.1UF',
 PRIM_FILE='./archive_libs/logical/q_cap/chips/chips.prt';

PART_NAME
 C1008 'Q_CAP_C0201-0.1UF,10V,10%,X7S,CH4102K6E00':;

SECTION_NUMBER 1
 '@T6G_MB_LIB.T6G(SCH_1):PAGE433_I52@PURE_QUANTA.Q_CAP(CHIPS)':
 C_PATH='@t6g_mb_lib.t6g(sch_1):page433_i52@pure_quanta.q_cap(chips)',
 P_PATH='@t6g_mb_lib.t6g(sch_1):page312_i52@pure_quanta.q_cap(chips)',
 PATH='I52',
 DRAWING='@T6G_MB_LIB.T6G(SCH_1):PAGE433',
 TOLERANCE='10%',
 MATERIAL='X7S',
 PHYS_PAGE='312',
 XY='(-2325,2425)',
 ROT='0',
 VER='1',
 PACK_TYPE='C0201',
 LOCATION='C1008',
 CDS_LIB='pure_quanta',
 CDS_PART_NAME='Q_CAP_C0201-0.1UF,10V,10%,X7S,CH4102K6E00',
 VOLTAGE='10V',
 PART_NUMBER='CH4102K6E00',
 VALUE='0.1UF',
 PRIM_FILE='./archive_libs/logical/q_cap/chips/chips.prt';

PART_NAME
 C1009 'Q_CAP_C0201-0.1UF,10V,10%,X7S,CH4102K6E00':;

SECTION_NUMBER 1
 '@T6G_MB_LIB.T6G(SCH_1):PAGE433_I82@PURE_QUANTA.Q_CAP(CHIPS)':
 C_PATH='@t6g_mb_lib.t6g(sch_1):page433_i82@pure_quanta.q_cap(chips)',
 P_PATH='@t6g_mb_lib.t6g(sch_1):page312_i82@pure_quanta.q_cap(chips)',
 PATH='I82',
 DRAWING='@T6G_MB_LIB.T6G(SCH_1):PAGE433',
 TOLERANCE='10%',
 MATERIAL='X7S',
 PHYS_PAGE='312',
 XY='(-1800,5600)',
 ROT='0',
 VER='1',
 PACK_TYPE='C0201',
 LOCATION='C1009',
 CDS_LIB='pure_quanta',
 CDS_PART_NAME='Q_CAP_C0201-0.1UF,10V,10%,X7S,CH4102K6E00',
 VOLTAGE='10V',
 PART_NUMBER='CH4102K6E00',
 VALUE='0.1UF',
 PRIM_FILE='./archive_libs/logical/q_cap/chips/chips.prt';

PART_NAME
 C1010 'Q_CAP_C0201-0.1UF,10V,10%,X7S,CH4102K6E00':;

SECTION_NUMBER 1
 '@T6G_MB_LIB.T6G(SCH_1):PAGE433_I41@PURE_QUANTA.Q_CAP(CHIPS)':
 C_PATH='@t6g_mb_lib.t6g(sch_1):page433_i41@pure_quanta.q_cap(chips)',
 P_PATH='@t6g_mb_lib.t6g(sch_1):page312_i41@pure_quanta.q_cap(chips)',
 PATH='I41',
 DRAWING='@T6G_MB_LIB.T6G(SCH_1):PAGE433',
 TOLERANCE='10%',
 MATERIAL='X7S',
 PHYS_PAGE='312',
 XY='(-3350,2425)',
 ROT='0',
 VER='1',
 PACK_TYPE='C0201',
 LOCATION='C1010',
 CDS_LIB='pure_quanta',
 CDS_PART_NAME='Q_CAP_C0201-0.1UF,10V,10%,X7S,CH4102K6E00',
 VOLTAGE='10V',
 PART_NUMBER='CH4102K6E00',
 VALUE='0.1UF',
 PRIM_FILE='./archive_libs/logical/q_cap/chips/chips.prt';

PART_NAME
 C1011 'Q_CAP_C0201-0.1UF,10V,10%,X7S,CH4102K6E00':;

SECTION_NUMBER 1
 '@T6G_MB_LIB.T6G(SCH_1):PAGE433_I53@PURE_QUANTA.Q_CAP(CHIPS)':
 C_PATH='@t6g_mb_lib.t6g(sch_1):page433_i53@pure_quanta.q_cap(chips)',
 P_PATH='@t6g_mb_lib.t6g(sch_1):page312_i53@pure_quanta.q_cap(chips)',
 PATH='I53',
 DRAWING='@T6G_MB_LIB.T6G(SCH_1):PAGE433',
 TOLERANCE='10%',
 MATERIAL='X7S',
 PHYS_PAGE='312',
 XY='(-2050,2425)',
 ROT='0',
 VER='1',
 PACK_TYPE='C0201',
 LOCATION='C1011',
 CDS_LIB='pure_quanta',
 CDS_PART_NAME='Q_CAP_C0201-0.1UF,10V,10%,X7S,CH4102K6E00',
 VOLTAGE='10V',
 PART_NUMBER='CH4102K6E00',
 VALUE='0.1UF',
 PRIM_FILE='./archive_libs/logical/q_cap/chips/chips.prt';

PART_NAME
 C1012 'Q_CAP_C0201-0.1UF,10V,10%,X7S,CH4102K6E00':;

SECTION_NUMBER 1
 '@T6G_MB_LIB.T6G(SCH_1):PAGE433_I84@PURE_QUANTA.Q_CAP(CHIPS)':
 C_PATH='@t6g_mb_lib.t6g(sch_1):page433_i84@pure_quanta.q_cap(chips)',
 P_PATH='@t6g_mb_lib.t6g(sch_1):page312_i84@pure_quanta.q_cap(chips)',
 PATH='I84',
 DRAWING='@T6G_MB_LIB.T6G(SCH_1):PAGE433',
 TOLERANCE='10%',
 MATERIAL='X7S',
 PHYS_PAGE='312',
 XY='(-1550,5600)',
 ROT='0',
 VER='1',
 PACK_TYPE='C0201',
 LOCATION='C1012',
 CDS_LIB='pure_quanta',
 CDS_PART_NAME='Q_CAP_C0201-0.1UF,10V,10%,X7S,CH4102K6E00',
 VOLTAGE='10V',
 PART_NUMBER='CH4102K6E00',
 VALUE='0.1UF',
 PRIM_FILE='./archive_libs/logical/q_cap/chips/chips.prt';

PART_NAME
 C1013 'Q_CAP_0201-1UF,4V,20%,X6S,CH-10KMEE00':;

SECTION_NUMBER 1
 '@T6G_MB_LIB.T6G(SCH_1):PAGE433_I62@PURE_QUANTA.Q_CAP(CHIPS)':
 C_PATH='@t6g_mb_lib.t6g(sch_1):page433_i62@pure_quanta.q_cap(chips)',
 P_PATH='@t6g_mb_lib.t6g(sch_1):page312_i62@pure_quanta.q_cap(chips)',
 PATH='I62',
 DRAWING='@T6G_MB_LIB.T6G(SCH_1):PAGE433',
 TOLERANCE='20%',
 MATERIAL='X6S',
 PHYS_PAGE='312',
 XY='(-1800,3750)',
 ROT='0',
 VER='1',
 PACK_TYPE='0201',
 LOCATION='C1013',
 CDS_LIB='pure_quanta',
 CDS_PART_NAME='Q_CAP_0201-1UF,4V,20%,X6S,CH-10KMEE00',
 VOLTAGE='4V',
 PART_NUMBER='CH-10KMEE00',
 VALUE='1UF',
 PRIM_FILE='./archive_libs/logical/q_cap/chips/chips.prt';

PART_NAME
 C1014 'Q_CAP_C0201-0.1UF,10V,10%,X7S,CH4102K6E00':;

SECTION_NUMBER 1
 '@T6G_MB_LIB.T6G(SCH_1):PAGE433_I30@PURE_QUANTA.Q_CAP(CHIPS)':
 C_PATH='@t6g_mb_lib.t6g(sch_1):page433_i30@pure_quanta.q_cap(chips)',
 P_PATH='@t6g_mb_lib.t6g(sch_1):page312_i30@pure_quanta.q_cap(chips)',
 PATH='I30',
 DRAWING='@T6G_MB_LIB.T6G(SCH_1):PAGE433',
 TOLERANCE='10%',
 MATERIAL='X7S',
 PHYS_PAGE='312',
 XY='(-3175,1325)',
 ROT='0',
 VER='1',
 PACK_TYPE='C0201',
 LOCATION='C1014',
 CDS_LIB='pure_quanta',
 CDS_PART_NAME='Q_CAP_C0201-0.1UF,10V,10%,X7S,CH4102K6E00',
 VOLTAGE='10V',
 PART_NUMBER='CH4102K6E00',
 VALUE='0.1UF',
 PRIM_FILE='./archive_libs/logical/q_cap/chips/chips.prt';

PART_NAME
 C1015 'Q_CAP_0201-1UF,4V,20%,X6S,CH-10KMEE00':;

SECTION_NUMBER 1
 '@T6G_MB_LIB.T6G(SCH_1):PAGE433_I49@PURE_QUANTA.Q_CAP(CHIPS)':
 C_PATH='@t6g_mb_lib.t6g(sch_1):page433_i49@pure_quanta.q_cap(chips)',
 P_PATH='@t6g_mb_lib.t6g(sch_1):page312_i49@pure_quanta.q_cap(chips)',
 PATH='I49',
 DRAWING='@T6G_MB_LIB.T6G(SCH_1):PAGE433',
 TOLERANCE='20%',
 MATERIAL='X6S',
 PHYS_PAGE='312',
 XY='(-2450,3100)',
 ROT='0',
 VER='1',
 PACK_TYPE='0201',
 LOCATION='C1015',
 CDS_LIB='pure_quanta',
 CDS_PART_NAME='Q_CAP_0201-1UF,4V,20%,X6S,CH-10KMEE00',
 VOLTAGE='4V',
 PART_NUMBER='CH-10KMEE00',
 VALUE='1UF',
 PRIM_FILE='./archive_libs/logical/q_cap/chips/chips.prt';

PART_NAME
 C1016 'Q_CAP_0201-1UF,4V,20%,X6S,CH-10KMEE00':;

SECTION_NUMBER 1
 '@T6G_MB_LIB.T6G(SCH_1):PAGE433_I76@PURE_QUANTA.Q_CAP(CHIPS)':
 C_PATH='@t6g_mb_lib.t6g(sch_1):page433_i76@pure_quanta.q_cap(chips)',
 P_PATH='@t6g_mb_lib.t6g(sch_1):page312_i76@pure_quanta.q_cap(chips)',
 PATH='I76',
 DRAWING='@T6G_MB_LIB.T6G(SCH_1):PAGE433',
 TOLERANCE='20%',
 MATERIAL='X6S',
 PHYS_PAGE='312',
 XY='(-2375,5625)',
 ROT='0',
 VER='1',
 PACK_TYPE='0201',
 LOCATION='C1016',
 CDS_LIB='pure_quanta',
 CDS_PART_NAME='Q_CAP_0201-1UF,4V,20%,X6S,CH-10KMEE00',
 VOLTAGE='4V',
 PART_NUMBER='CH-10KMEE00',
 VALUE='1UF',
 PRIM_FILE='./archive_libs/logical/q_cap/chips/chips.prt';

PART_NAME
 C1017 'Q_CAP_0201-1UF,4V,20%,X6S,CH-10KMEE00':;

SECTION_NUMBER 1
 '@T6G_MB_LIB.T6G(SCH_1):PAGE433_I63@PURE_QUANTA.Q_CAP(CHIPS)':
 C_PATH='@t6g_mb_lib.t6g(sch_1):page433_i63@pure_quanta.q_cap(chips)',
 P_PATH='@t6g_mb_lib.t6g(sch_1):page312_i63@pure_quanta.q_cap(chips)',
 PATH='I63',
 DRAWING='@T6G_MB_LIB.T6G(SCH_1):PAGE433',
 TOLERANCE='20%',
 MATERIAL='X6S',
 PHYS_PAGE='312',
 XY='(-1550,3750)',
 ROT='0',
 VER='1',
 PACK_TYPE='0201',
 LOCATION='C1017',
 CDS_LIB='pure_quanta',
 CDS_PART_NAME='Q_CAP_0201-1UF,4V,20%,X6S,CH-10KMEE00',
 VOLTAGE='4V',
 PART_NUMBER='CH-10KMEE00',
 VALUE='1UF',
 PRIM_FILE='./archive_libs/logical/q_cap/chips/chips.prt';

PART_NAME
 C1018 'Q_CAP_0201-1UF,4V,20%,X6S,CH-10KMEE00':;

SECTION_NUMBER 1
 '@T6G_MB_LIB.T6G(SCH_1):PAGE433_I90@PURE_QUANTA.Q_CAP(CHIPS)':
 C_PATH='@t6g_mb_lib.t6g(sch_1):page433_i90@pure_quanta.q_cap(chips)',
 P_PATH='@t6g_mb_lib.t6g(sch_1):page312_i90@pure_quanta.q_cap(chips)',
 PATH='I90',
 DRAWING='@T6G_MB_LIB.T6G(SCH_1):PAGE433',
 TOLERANCE='20%',
 MATERIAL='X6S',
 PHYS_PAGE='312',
 XY='(-2925,1325)',
 ROT='0',
 VER='1',
 PACK_TYPE='0201',
 LOCATION='C1018',
 CDS_LIB='pure_quanta',
 CDS_PART_NAME='Q_CAP_0201-1UF,4V,20%,X6S,CH-10KMEE00',
 VOLTAGE='4V',
 PART_NUMBER='CH-10KMEE00',
 VALUE='1UF',
 PRIM_FILE='./archive_libs/logical/q_cap/chips/chips.prt';

PART_NAME
 C1019 'Q_CAP_0201-1UF,4V,20%,X6S,CH-10KMEE00':;

SECTION_NUMBER 1
 '@T6G_MB_LIB.T6G(SCH_1):PAGE433_I57@PURE_QUANTA.Q_CAP(CHIPS)':
 C_PATH='@t6g_mb_lib.t6g(sch_1):page433_i57@pure_quanta.q_cap(chips)',
 P_PATH='@t6g_mb_lib.t6g(sch_1):page312_i57@pure_quanta.q_cap(chips)',
 PATH='I57',
 DRAWING='@T6G_MB_LIB.T6G(SCH_1):PAGE433',
 TOLERANCE='20%',
 MATERIAL='X6S',
 PHYS_PAGE='312',
 XY='(-2225,3100)',
 ROT='0',
 VER='1',
 PACK_TYPE='0201',
 LOCATION='C1019',
 CDS_LIB='pure_quanta',
 CDS_PART_NAME='Q_CAP_0201-1UF,4V,20%,X6S,CH-10KMEE00',
 VOLTAGE='4V',
 PART_NUMBER='CH-10KMEE00',
 VALUE='1UF',
 PRIM_FILE='./archive_libs/logical/q_cap/chips/chips.prt';

PART_NAME
 C1020 'Q_CAP_0201-1UF,4V,20%,X6S,CH-10KMEE00':;

SECTION_NUMBER 1
 '@T6G_MB_LIB.T6G(SCH_1):PAGE433_I91@PURE_QUANTA.Q_CAP(CHIPS)':
 C_PATH='@t6g_mb_lib.t6g(sch_1):page433_i91@pure_quanta.q_cap(chips)',
 P_PATH='@t6g_mb_lib.t6g(sch_1):page312_i91@pure_quanta.q_cap(chips)',
 PATH='I91',
 DRAWING='@T6G_MB_LIB.T6G(SCH_1):PAGE433',
 TOLERANCE='20%',
 MATERIAL='X6S',
 PHYS_PAGE='312',
 XY='(-2625,1325)',
 ROT='0',
 VER='1',
 PACK_TYPE='0201',
 LOCATION='C1020',
 CDS_LIB='pure_quanta',
 CDS_PART_NAME='Q_CAP_0201-1UF,4V,20%,X6S,CH-10KMEE00',
 VOLTAGE='4V',
 PART_NUMBER='CH-10KMEE00',
 VALUE='1UF',
 PRIM_FILE='./archive_libs/logical/q_cap/chips/chips.prt';

PART_NAME
 C1021 'Q_CAP_C0201-0.1UF,10V,10%,X7S,CH4102K6E00':;

SECTION_NUMBER 1
 '@T6G_MB_LIB.T6G(SCH_1):PAGE433_I35@PURE_QUANTA.Q_CAP(CHIPS)':
 C_PATH='@t6g_mb_lib.t6g(sch_1):page433_i35@pure_quanta.q_cap(chips)',
 P_PATH='@t6g_mb_lib.t6g(sch_1):page312_i35@pure_quanta.q_cap(chips)',
 PATH='I35',
 DRAWING='@T6G_MB_LIB.T6G(SCH_1):PAGE433',
 TOLERANCE='10%',
 MATERIAL='X7S',
 PHYS_PAGE='312',
 XY='(-2375,1325)',
 ROT='0',
 VER='1',
 PACK_TYPE='C0201',
 LOCATION='C1021',
 CDS_LIB='pure_quanta',
 CDS_PART_NAME='Q_CAP_C0201-0.1UF,10V,10%,X7S,CH4102K6E00',
 VOLTAGE='10V',
 PART_NUMBER='CH4102K6E00',
 VALUE='0.1UF',
 PRIM_FILE='./archive_libs/logical/q_cap/chips/chips.prt';

PART_NAME
 C1022 'Q_CAP_C0805-100UF,4V,20%,X6S,CH710KMEA01':;

SECTION_NUMBER 1
 '@T6G_MB_LIB.T6G(SCH_1):PAGE433_I66@PURE_QUANTA.Q_CAP(CHIPS)':
 C_PATH='@t6g_mb_lib.t6g(sch_1):page433_i66@pure_quanta.q_cap(chips)',
 P_PATH='@t6g_mb_lib.t6g(sch_1):page312_i66@pure_quanta.q_cap(chips)',
 PATH='I66',
 DRAWING='@T6G_MB_LIB.T6G(SCH_1):PAGE433',
 TOLERANCE='20%',
 MATERIAL='X6S',
 PHYS_PAGE='312',
 XY='(-3625,4375)',
 ROT='0',
 VER='1',
 PACK_TYPE='C0805',
 LOCATION='C1022',
 CDS_LIB='pure_quanta',
 CDS_PART_NAME='Q_CAP_C0805-100UF,4V,20%,X6S,CH710KMEA01',
 VOLTAGE='4V',
 PART_NUMBER='CH710KMEA01',
 VALUE='100UF',
 PRIM_FILE='./archive_libs/logical/q_cap/chips/chips.prt';

PART_NAME
 C1023 'Q_CAP_C0402-10UF,6.3V,20%,X6S,CH6101MEB01':;

SECTION_NUMBER 1
 '@T6G_MB_LIB.T6G(SCH_1):PAGE433_I39@PURE_QUANTA.Q_CAP(CHIPS)':
 C_PATH='@t6g_mb_lib.t6g(sch_1):page433_i39@pure_quanta.q_cap(chips)',
 P_PATH='@t6g_mb_lib.t6g(sch_1):page312_i39@pure_quanta.q_cap(chips)',
 PATH='I39',
 DRAWING='@T6G_MB_LIB.T6G(SCH_1):PAGE433',
 TOLERANCE='20%',
 MATERIAL='X6S',
 PHYS_PAGE='312',
 XY='(-3625,3750)',
 ROT='0',
 VER='1',
 PACK_TYPE='C0402',
 LOCATION='C1023',
 CDS_LIB='pure_quanta',
 CDS_PART_NAME='Q_CAP_C0402-10UF,6.3V,20%,X6S,CH6101MEB01',
 VOLTAGE='6.3V',
 PART_NUMBER='CH6101MEB01',
 VALUE='10UF',
 PRIM_FILE='./archive_libs/logical/q_cap/chips/chips.prt';

PART_NAME
 C1024 'Q_CAP_0201-1UF,4V,20%,X6S,CH-10KMEE00':;

SECTION_NUMBER 1
 '@T6G_MB_LIB.T6G(SCH_1):PAGE433_I37@PURE_QUANTA.Q_CAP(CHIPS)':
 C_PATH='@t6g_mb_lib.t6g(sch_1):page433_i37@pure_quanta.q_cap(chips)',
 P_PATH='@t6g_mb_lib.t6g(sch_1):page312_i37@pure_quanta.q_cap(chips)',
 PATH='I37',
 DRAWING='@T6G_MB_LIB.T6G(SCH_1):PAGE433',
 TOLERANCE='20%',
 MATERIAL='X6S',
 PHYS_PAGE='312',
 XY='(-3625,3125)',
 ROT='0',
 VER='1',
 PACK_TYPE='0201',
 LOCATION='C1024',
 CDS_LIB='pure_quanta',
 CDS_PART_NAME='Q_CAP_0201-1UF,4V,20%,X6S,CH-10KMEE00',
 VOLTAGE='4V',
 PART_NUMBER='CH-10KMEE00',
 VALUE='1UF',
 PRIM_FILE='./archive_libs/logical/q_cap/chips/chips.prt';

PART_NAME
 C1025 'Q_CAP_C0805-100UF,4V,20%,X6S,CH710KMEA01':;

SECTION_NUMBER 1
 '@T6G_MB_LIB.T6G(SCH_1):PAGE433_I67@PURE_QUANTA.Q_CAP(CHIPS)':
 C_PATH='@t6g_mb_lib.t6g(sch_1):page433_i67@pure_quanta.q_cap(chips)',
 P_PATH='@t6g_mb_lib.t6g(sch_1):page312_i67@pure_quanta.q_cap(chips)',
 PATH='I67',
 DRAWING='@T6G_MB_LIB.T6G(SCH_1):PAGE433',
 TOLERANCE='20%',
 MATERIAL='X6S',
 PHYS_PAGE='312',
 XY='(-3400,4375)',
 ROT='0',
 VER='1',
 PACK_TYPE='C0805',
 LOCATION='C1025',
 CDS_LIB='pure_quanta',
 CDS_PART_NAME='Q_CAP_C0805-100UF,4V,20%,X6S,CH710KMEA01',
 VOLTAGE='4V',
 PART_NUMBER='CH710KMEA01',
 VALUE='100UF',
 PRIM_FILE='./archive_libs/logical/q_cap/chips/chips.prt';

PART_NAME
 C1026 'Q_CAP_C0402-22UF,4V,20%,X6S,CH622KMEB02':;

SECTION_NUMBER 1
 '@T6G_MB_LIB.T6G(SCH_1):PAGE433_I72@PURE_QUANTA.Q_CAP(CHIPS)':
 C_PATH='@t6g_mb_lib.t6g(sch_1):page433_i72@pure_quanta.q_cap(chips)',
 P_PATH='@t6g_mb_lib.t6g(sch_1):page312_i72@pure_quanta.q_cap(chips)',
 PATH='I72',
 DRAWING='@T6G_MB_LIB.T6G(SCH_1):PAGE433',
 TOLERANCE='20%',
 MATERIAL='X6S',
 PHYS_PAGE='312',
 XY='(-2700,4375)',
 ROT='0',
 VER='1',
 PACK_TYPE='C0402',
 LOCATION='C1026',
 CDS_LIB='pure_quanta',
 CDS_PART_NAME='Q_CAP_C0402-22UF,4V,20%,X6S,CH622KMEB02',
 VOLTAGE='4V',
 PART_NUMBER='CH622KMEB02',
 VALUE='22UF',
 PRIM_FILE='./archive_libs/logical/q_cap/chips/chips.prt';

PART_NAME
 C1027 'Q_CAP_0201-1UF,4V,20%,X6S,CH-10KMEE00':;

SECTION_NUMBER 1
 '@T6G_MB_LIB.T6G(SCH_1):PAGE433_I38@PURE_QUANTA.Q_CAP(CHIPS)':
 C_PATH='@t6g_mb_lib.t6g(sch_1):page433_i38@pure_quanta.q_cap(chips)',
 P_PATH='@t6g_mb_lib.t6g(sch_1):page312_i38@pure_quanta.q_cap(chips)',
 PATH='I38',
 DRAWING='@T6G_MB_LIB.T6G(SCH_1):PAGE433',
 TOLERANCE='20%',
 MATERIAL='X6S',
 PHYS_PAGE='312',
 XY='(-3400,3125)',
 ROT='0',
 VER='1',
 PACK_TYPE='0201',
 LOCATION='C1027',
 CDS_LIB='pure_quanta',
 CDS_PART_NAME='Q_CAP_0201-1UF,4V,20%,X6S,CH-10KMEE00',
 VOLTAGE='4V',
 PART_NUMBER='CH-10KMEE00',
 VALUE='1UF',
 PRIM_FILE='./archive_libs/logical/q_cap/chips/chips.prt';

PART_NAME
 C1028 'Q_CAP_C0805-100UF,4V,20%,X6S,CH710KMEA01':;

SECTION_NUMBER 1
 '@T6G_MB_LIB.T6G(SCH_1):PAGE433_I69@PURE_QUANTA.Q_CAP(CHIPS)':
 C_PATH='@t6g_mb_lib.t6g(sch_1):page433_i69@pure_quanta.q_cap(chips)',
 P_PATH='@t6g_mb_lib.t6g(sch_1):page312_i69@pure_quanta.q_cap(chips)',
 PATH='I69',
 DRAWING='@T6G_MB_LIB.T6G(SCH_1):PAGE433',
 TOLERANCE='20%',
 MATERIAL='X6S',
 PHYS_PAGE='312',
 XY='(-3575,5650)',
 ROT='0',
 VER='1',
 PACK_TYPE='C0805',
 LOCATION='C1028',
 CDS_LIB='pure_quanta',
 CDS_PART_NAME='Q_CAP_C0805-100UF,4V,20%,X6S,CH710KMEA01',
 VOLTAGE='4V',
 PART_NUMBER='CH710KMEA01',
 VALUE='100UF',
 PRIM_FILE='./archive_libs/logical/q_cap/chips/chips.prt';

PART_NAME
 C1029 'Q_CAP_C0805-100UF,4V,20%,X6S,CH710KMEA01':;

SECTION_NUMBER 1
 '@T6G_MB_LIB.T6G(SCH_1):PAGE433_I70@PURE_QUANTA.Q_CAP(CHIPS)':
 C_PATH='@t6g_mb_lib.t6g(sch_1):page433_i70@pure_quanta.q_cap(chips)',
 P_PATH='@t6g_mb_lib.t6g(sch_1):page312_i70@pure_quanta.q_cap(chips)',
 PATH='I70',
 DRAWING='@T6G_MB_LIB.T6G(SCH_1):PAGE433',
 TOLERANCE='20%',
 MATERIAL='X6S',
 PHYS_PAGE='312',
 XY='(-3175,4375)',
 ROT='0',
 VER='1',
 PACK_TYPE='C0805',
 LOCATION='C1029',
 CDS_LIB='pure_quanta',
 CDS_PART_NAME='Q_CAP_C0805-100UF,4V,20%,X6S,CH710KMEA01',
 VOLTAGE='4V',
 PART_NUMBER='CH710KMEA01',
 VALUE='100UF',
 PRIM_FILE='./archive_libs/logical/q_cap/chips/chips.prt';

PART_NAME
 C1030 'Q_CAP_C0402-22UF,4V,20%,X6S,CH622KMEB02':;

SECTION_NUMBER 1
 '@T6G_MB_LIB.T6G(SCH_1):PAGE433_I77@PURE_QUANTA.Q_CAP(CHIPS)':
 C_PATH='@t6g_mb_lib.t6g(sch_1):page433_i77@pure_quanta.q_cap(chips)',
 P_PATH='@t6g_mb_lib.t6g(sch_1):page312_i77@pure_quanta.q_cap(chips)',
 PATH='I77',
 DRAWING='@T6G_MB_LIB.T6G(SCH_1):PAGE433',
 TOLERANCE='20%',
 MATERIAL='X6S',
 PHYS_PAGE='312',
 XY='(-2250,4375)',
 ROT='0',
 VER='1',
 PACK_TYPE='C0402',
 LOCATION='C1030',
 CDS_LIB='pure_quanta',
 CDS_PART_NAME='Q_CAP_C0402-22UF,4V,20%,X6S,CH622KMEB02',
 VOLTAGE='4V',
 PART_NUMBER='CH622KMEB02',
 VALUE='22UF',
 PRIM_FILE='./archive_libs/logical/q_cap/chips/chips.prt';

PART_NAME
 C1031 'Q_CAP_0201-1UF,4V,20%,X6S,CH-10KMEE00':;

SECTION_NUMBER 1
 '@T6G_MB_LIB.T6G(SCH_1):PAGE433_I45@PURE_QUANTA.Q_CAP(CHIPS)':
 C_PATH='@t6g_mb_lib.t6g(sch_1):page433_i45@pure_quanta.q_cap(chips)',
 P_PATH='@t6g_mb_lib.t6g(sch_1):page312_i45@pure_quanta.q_cap(chips)',
 PATH='I45',
 DRAWING='@T6G_MB_LIB.T6G(SCH_1):PAGE433',
 TOLERANCE='20%',
 MATERIAL='X6S',
 PHYS_PAGE='312',
 XY='(-3150,3125)',
 ROT='0',
 VER='1',
 PACK_TYPE='0201',
 LOCATION='C1031',
 CDS_LIB='pure_quanta',
 CDS_PART_NAME='Q_CAP_0201-1UF,4V,20%,X6S,CH-10KMEE00',
 VOLTAGE='4V',
 PART_NUMBER='CH-10KMEE00',
 VALUE='1UF',
 PRIM_FILE='./archive_libs/logical/q_cap/chips/chips.prt';

PART_NAME
 C1032 'Q_CAP_C0402-22UF,4V,20%,X6S,CH622KMEB02':;

SECTION_NUMBER 1
 '@T6G_MB_LIB.T6G(SCH_1):PAGE433_I74@PURE_QUANTA.Q_CAP(CHIPS)':
 C_PATH='@t6g_mb_lib.t6g(sch_1):page433_i74@pure_quanta.q_cap(chips)',
 P_PATH='@t6g_mb_lib.t6g(sch_1):page312_i74@pure_quanta.q_cap(chips)',
 PATH='I74',
 DRAWING='@T6G_MB_LIB.T6G(SCH_1):PAGE433',
 TOLERANCE='20%',
 MATERIAL='X6S',
 PHYS_PAGE='312',
 XY='(-3300,5650)',
 ROT='0',
 VER='1',
 PACK_TYPE='C0402',
 LOCATION='C1032',
 CDS_LIB='pure_quanta',
 CDS_PART_NAME='Q_CAP_C0402-22UF,4V,20%,X6S,CH622KMEB02',
 VOLTAGE='4V',
 PART_NUMBER='CH622KMEB02',
 VALUE='22UF',
 PRIM_FILE='./archive_libs/logical/q_cap/chips/chips.prt';

PART_NAME
 C1033 'Q_CAP_C0805-100UF,4V,20%,X6S,CH710KMEA01':;

SECTION_NUMBER 1
 '@T6G_MB_LIB.T6G(SCH_1):PAGE433_I71@PURE_QUANTA.Q_CAP(CHIPS)':
 C_PATH='@t6g_mb_lib.t6g(sch_1):page433_i71@pure_quanta.q_cap(chips)',
 P_PATH='@t6g_mb_lib.t6g(sch_1):page312_i71@pure_quanta.q_cap(chips)',
 PATH='I71',
 DRAWING='@T6G_MB_LIB.T6G(SCH_1):PAGE433',
 TOLERANCE='20%',
 MATERIAL='X6S',
 PHYS_PAGE='312',
 XY='(-2950,4375)',
 ROT='0',
 VER='1',
 PACK_TYPE='C0805',
 LOCATION='C1033',
 CDS_LIB='pure_quanta',
 CDS_PART_NAME='Q_CAP_C0805-100UF,4V,20%,X6S,CH710KMEA01',
 VOLTAGE='4V',
 PART_NUMBER='CH710KMEA01',
 VALUE='100UF',
 PRIM_FILE='./archive_libs/logical/q_cap/chips/chips.prt';

PART_NAME
 C1034 'Q_CAP_0402-4.7UF,6.3V,20%,X6S,CH5471MEB01':;

SECTION_NUMBER 1
 '@T6G_MB_LIB.T6G(SCH_1):PAGE433_I47@PURE_QUANTA.Q_CAP(CHIPS)':
 C_PATH='@t6g_mb_lib.t6g(sch_1):page433_i47@pure_quanta.q_cap(chips)',
 P_PATH='@t6g_mb_lib.t6g(sch_1):page312_i47@pure_quanta.q_cap(chips)',
 PATH='I47',
 DRAWING='@T6G_MB_LIB.T6G(SCH_1):PAGE433',
 TOLERANCE='20%',
 MATERIAL='X6S',
 PHYS_PAGE='312',
 XY='(-2950,3750)',
 ROT='0',
 VER='1',
 PACK_TYPE='0402',
 LOCATION='C1034',
 CDS_LIB='pure_quanta',
 CDS_PART_NAME='Q_CAP_0402-4.7UF,6.3V,20%,X6S,CH5471MEB01',
 VOLTAGE='6.3V',
 PART_NUMBER='CH5471MEB01',
 VALUE='4.7UF',
 PRIM_FILE='./archive_libs/logical/q_cap/chips/chips.prt';

PART_NAME
 C1035 'Q_CAP_C0201-0.1UF,10V,10%,X7S,CH4102K6E00':;

SECTION_NUMBER 1
 '@T6G_MB_LIB.T6G(SCH_1):PAGE433_I44@PURE_QUANTA.Q_CAP(CHIPS)':
 C_PATH='@t6g_mb_lib.t6g(sch_1):page433_i44@pure_quanta.q_cap(chips)',
 P_PATH='@t6g_mb_lib.t6g(sch_1):page312_i44@pure_quanta.q_cap(chips)',
 PATH='I44',
 DRAWING='@T6G_MB_LIB.T6G(SCH_1):PAGE433',
 TOLERANCE='10%',
 MATERIAL='X7S',
 PHYS_PAGE='312',
 XY='(-2575,2425)',
 ROT='0',
 VER='1',
 PACK_TYPE='C0201',
 LOCATION='C1035',
 CDS_LIB='pure_quanta',
 CDS_PART_NAME='Q_CAP_C0201-0.1UF,10V,10%,X7S,CH4102K6E00',
 VOLTAGE='10V',
 PART_NUMBER='CH4102K6E00',
 VALUE='0.1UF',
 PRIM_FILE='./archive_libs/logical/q_cap/chips/chips.prt';

PART_NAME
 C1036 'Q_CAP_C0402-10UF,6.3V,20%,X6S,CH6101MEB01':;

SECTION_NUMBER 1
 '@T6G_MB_LIB.T6G(SCH_1):PAGE433_I40@PURE_QUANTA.Q_CAP(CHIPS)':
 C_PATH='@t6g_mb_lib.t6g(sch_1):page433_i40@pure_quanta.q_cap(chips)',
 P_PATH='@t6g_mb_lib.t6g(sch_1):page312_i40@pure_quanta.q_cap(chips)',
 PATH='I40',
 DRAWING='@T6G_MB_LIB.T6G(SCH_1):PAGE433',
 TOLERANCE='20%',
 MATERIAL='X6S',
 PHYS_PAGE='312',
 XY='(-3400,3750)',
 ROT='0',
 VER='1',
 PACK_TYPE='C0402',
 LOCATION='C1036',
 CDS_LIB='pure_quanta',
 CDS_PART_NAME='Q_CAP_C0402-10UF,6.3V,20%,X6S,CH6101MEB01',
 VOLTAGE='6.3V',
 PART_NUMBER='CH6101MEB01',
 VALUE='10UF',
 PRIM_FILE='./archive_libs/logical/q_cap/chips/chips.prt';

PART_NAME
 C1037 'Q_CAP_C0402-10UF,6.3V,20%,X6S,CH6101MEB01':;

SECTION_NUMBER 1
 '@T6G_MB_LIB.T6G(SCH_1):PAGE433_I79@PURE_QUANTA.Q_CAP(CHIPS)':
 C_PATH='@t6g_mb_lib.t6g(sch_1):page433_i79@pure_quanta.q_cap(chips)',
 P_PATH='@t6g_mb_lib.t6g(sch_1):page312_i79@pure_quanta.q_cap(chips)',
 PATH='I79',
 DRAWING='@T6G_MB_LIB.T6G(SCH_1):PAGE433',
 TOLERANCE='20%',
 MATERIAL='X6S',
 PHYS_PAGE='312',
 XY='(-1725,4375)',
 ROT='0',
 VER='1',
 PACK_TYPE='C0402',
 LOCATION='C1037',
 CDS_LIB='pure_quanta',
 CDS_PART_NAME='Q_CAP_C0402-10UF,6.3V,20%,X6S,CH6101MEB01',
 VOLTAGE='6.3V',
 PART_NUMBER='CH6101MEB01',
 VALUE='10UF',
 PRIM_FILE='./archive_libs/logical/q_cap/chips/chips.prt';

PART_NAME
 C1038 'Q_CAP_0402-4.7UF,6.3V,20%,X6S,CH5471MEB01':;

SECTION_NUMBER 1
 '@T6G_MB_LIB.T6G(SCH_1):PAGE433_I75@PURE_QUANTA.Q_CAP(CHIPS)':
 C_PATH='@t6g_mb_lib.t6g(sch_1):page433_i75@pure_quanta.q_cap(chips)',
 P_PATH='@t6g_mb_lib.t6g(sch_1):page312_i75@pure_quanta.q_cap(chips)',
 PATH='I75',
 DRAWING='@T6G_MB_LIB.T6G(SCH_1):PAGE433',
 TOLERANCE='20%',
 MATERIAL='X6S',
 PHYS_PAGE='312',
 XY='(-2675,5625)',
 ROT='0',
 VER='1',
 PACK_TYPE='0402',
 LOCATION='C1038',
 CDS_LIB='pure_quanta',
 CDS_PART_NAME='Q_CAP_0402-4.7UF,6.3V,20%,X6S,CH5471MEB01',
 VOLTAGE='6.3V',
 PART_NUMBER='CH5471MEB01',
 VALUE='4.7UF',
 PRIM_FILE='./archive_libs/logical/q_cap/chips/chips.prt';

PART_NAME
 C1039 'Q_CAP_0201-1UF,4V,20%,X6S,CH-10KMEE00':;

SECTION_NUMBER 1
 '@T6G_MB_LIB.T6G(SCH_1):PAGE433_I48@PURE_QUANTA.Q_CAP(CHIPS)':
 C_PATH='@t6g_mb_lib.t6g(sch_1):page433_i48@pure_quanta.q_cap(chips)',
 P_PATH='@t6g_mb_lib.t6g(sch_1):page312_i48@pure_quanta.q_cap(chips)',
 PATH='I48',
 DRAWING='@T6G_MB_LIB.T6G(SCH_1):PAGE433',
 TOLERANCE='20%',
 MATERIAL='X6S',
 PHYS_PAGE='312',
 XY='(-2675,3125)',
 ROT='0',
 VER='1',
 PACK_TYPE='0201',
 LOCATION='C1039',
 CDS_LIB='pure_quanta',
 CDS_PART_NAME='Q_CAP_0201-1UF,4V,20%,X6S,CH-10KMEE00',
 VOLTAGE='4V',
 PART_NUMBER='CH-10KMEE00',
 VALUE='1UF',
 PRIM_FILE='./archive_libs/logical/q_cap/chips/chips.prt';

PART_NAME
 C1040 'Q_CAP_C0402-22UF,4V,20%,X6S,CH622KMEB02':;

SECTION_NUMBER 1
 '@T6G_MB_LIB.T6G(SCH_1):PAGE433_I86@PURE_QUANTA.Q_CAP(CHIPS)':
 C_PATH='@t6g_mb_lib.t6g(sch_1):page433_i86@pure_quanta.q_cap(chips)',
 P_PATH='@t6g_mb_lib.t6g(sch_1):page312_i86@pure_quanta.q_cap(chips)',
 PATH='I86',
 DRAWING='@T6G_MB_LIB.T6G(SCH_1):PAGE433',
 TOLERANCE='20%',
 MATERIAL='X6S',
 PHYS_PAGE='312',
 XY='(-2475,4375)',
 ROT='0',
 VER='1',
 PACK_TYPE='C0402',
 LOCATION='C1040',
 CDS_LIB='pure_quanta',
 CDS_PART_NAME='Q_CAP_C0402-22UF,4V,20%,X6S,CH622KMEB02',
 VOLTAGE='4V',
 PART_NUMBER='CH622KMEB02',
 VALUE='22UF',
 PRIM_FILE='./archive_libs/logical/q_cap/chips/chips.prt';

PART_NAME
 C1041 'Q_CAP_C0402-22UF,4V,20%,X6S,CH622KMEB02':;

SECTION_NUMBER 1
 '@T6G_MB_LIB.T6G(SCH_1):PAGE433_I78@PURE_QUANTA.Q_CAP(CHIPS)':
 C_PATH='@t6g_mb_lib.t6g(sch_1):page433_i78@pure_quanta.q_cap(chips)',
 P_PATH='@t6g_mb_lib.t6g(sch_1):page312_i78@pure_quanta.q_cap(chips)',
 PATH='I78',
 DRAWING='@T6G_MB_LIB.T6G(SCH_1):PAGE433',
 TOLERANCE='20%',
 MATERIAL='X6S',
 PHYS_PAGE='312',
 XY='(-2025,4375)',
 ROT='0',
 VER='1',
 PACK_TYPE='C0402',
 LOCATION='C1041',
 CDS_LIB='pure_quanta',
 CDS_PART_NAME='Q_CAP_C0402-22UF,4V,20%,X6S,CH622KMEB02',
 VOLTAGE='4V',
 PART_NUMBER='CH622KMEB02',
 VALUE='22UF',
 PRIM_FILE='./archive_libs/logical/q_cap/chips/chips.prt';

PART_NAME
 C1042 'Q_CAP_C0402-100NF,50V,10%,X7R,CH4106K1B01':
 REUSE_ID='81';

SECTION_NUMBER 1
 '@T6G_MB_LIB.T6G(SCH_1):PAGE273_I18@PURE_QUANTA.Q_CAP(CHIPS)':
 C_PATH='@t6g_mb_lib.t6g(sch_1):page273_i18@pure_quanta.q_cap(chips)',
 P_PATH='@t6g_mb_lib.t6g(sch_1):page188_i18@pure_quanta.q_cap(chips)',
 PATH='I18',
 DRAWING='@T6G_MB_LIB.T6G(SCH_1):PAGE273',
 BOM_COST='VR_SYSTEM ',
 TOLERANCE='10%',
 MATERIAL='X7R',
 PHYS_PAGE='188',
 XY='(-5975,7575)',
 ROT='2',
 VER='1',
 PACK_TYPE='C0402',
 LOCATION='C1042',
 CDS_LIB='pure_quanta',
 CDS_PART_NAME='Q_CAP_C0402-100NF,50V,10%,X7R,CH4106K1B01',
 REUSE_ID='81',
 VOLTAGE='50V',
 PART_NUMBER='CH4106K1B01',
 VALUE='100NF',
 PRIM_FILE='./archive_libs/logical/q_cap/chips/chips.prt';

PART_NAME
 C1043 'Q_CAP_C0201-0.1UF,10V,10%,X7S,CH4102K6E00':;

SECTION_NUMBER 1
 '@T6G_MB_LIB.T6G(SCH_1):PAGE433_I54@PURE_QUANTA.Q_CAP(CHIPS)':
 C_PATH='@t6g_mb_lib.t6g(sch_1):page433_i54@pure_quanta.q_cap(chips)',
 P_PATH='@t6g_mb_lib.t6g(sch_1):page312_i54@pure_quanta.q_cap(chips)',
 PATH='I54',
 DRAWING='@T6G_MB_LIB.T6G(SCH_1):PAGE433',
 TOLERANCE='10%',
 MATERIAL='X7S',
 PHYS_PAGE='312',
 XY='(-1775,2425)',
 ROT='0',
 VER='1',
 PACK_TYPE='C0201',
 LOCATION='C1043',
 CDS_LIB='pure_quanta',
 CDS_PART_NAME='Q_CAP_C0201-0.1UF,10V,10%,X7S,CH4102K6E00',
 VOLTAGE='10V',
 PART_NUMBER='CH4102K6E00',
 VALUE='0.1UF',
 PRIM_FILE='./archive_libs/logical/q_cap/chips/chips.prt';

PART_NAME
 C1044 'Q_CAP_C0402-10UF,6.3V,20%,X6S,CH6101MEB01':;

SECTION_NUMBER 1
 '@T6G_MB_LIB.T6G(SCH_1):PAGE433_I73@PURE_QUANTA.Q_CAP(CHIPS)':
 C_PATH='@t6g_mb_lib.t6g(sch_1):page433_i73@pure_quanta.q_cap(chips)',
 P_PATH='@t6g_mb_lib.t6g(sch_1):page312_i73@pure_quanta.q_cap(chips)',
 PATH='I73',
 DRAWING='@T6G_MB_LIB.T6G(SCH_1):PAGE433',
 TOLERANCE='20%',
 MATERIAL='X6S',
 PHYS_PAGE='312',
 XY='(-2975,5625)',
 ROT='0',
 VER='1',
 PACK_TYPE='C0402',
 LOCATION='C1044',
 CDS_LIB='pure_quanta',
 CDS_PART_NAME='Q_CAP_C0402-10UF,6.3V,20%,X6S,CH6101MEB01',
 VOLTAGE='6.3V',
 PART_NUMBER='CH6101MEB01',
 VALUE='10UF',
 PRIM_FILE='./archive_libs/logical/q_cap/chips/chips.prt';

PART_NAME
 C1045 'Q_CAP_0402-4.7UF,6.3V,20%,X6S,CH5471MEB01':;

SECTION_NUMBER 1
 '@T6G_MB_LIB.T6G(SCH_1):PAGE433_I87@PURE_QUANTA.Q_CAP(CHIPS)':
 C_PATH='@t6g_mb_lib.t6g(sch_1):page433_i87@pure_quanta.q_cap(chips)',
 P_PATH='@t6g_mb_lib.t6g(sch_1):page312_i87@pure_quanta.q_cap(chips)',
 PATH='I87',
 DRAWING='@T6G_MB_LIB.T6G(SCH_1):PAGE433',
 TOLERANCE='20%',
 MATERIAL='X6S',
 PHYS_PAGE='312',
 XY='(-3175,3750)',
 ROT='0',
 VER='1',
 PACK_TYPE='0402',
 LOCATION='C1045',
 CDS_LIB='pure_quanta',
 CDS_PART_NAME='Q_CAP_0402-4.7UF,6.3V,20%,X6S,CH5471MEB01',
 VOLTAGE='6.3V',
 PART_NUMBER='CH5471MEB01',
 VALUE='4.7UF',
 PRIM_FILE='./archive_libs/logical/q_cap/chips/chips.prt';

PART_NAME
 C1046 'Q_CAP_0201-1UF,4V,20%,X6S,CH-10KMEE00':;

SECTION_NUMBER 1
 '@T6G_MB_LIB.T6G(SCH_1):PAGE433_I59@PURE_QUANTA.Q_CAP(CHIPS)':
 C_PATH='@t6g_mb_lib.t6g(sch_1):page433_i59@pure_quanta.q_cap(chips)',
 P_PATH='@t6g_mb_lib.t6g(sch_1):page312_i59@pure_quanta.q_cap(chips)',
 PATH='I59',
 DRAWING='@T6G_MB_LIB.T6G(SCH_1):PAGE433',
 TOLERANCE='20%',
 MATERIAL='X6S',
 PHYS_PAGE='312',
 XY='(-2250,3750)',
 ROT='0',
 VER='1',
 PACK_TYPE='0201',
 LOCATION='C1046',
 CDS_LIB='pure_quanta',
 CDS_PART_NAME='Q_CAP_0201-1UF,4V,20%,X6S,CH-10KMEE00',
 VOLTAGE='4V',
 PART_NUMBER='CH-10KMEE00',
 VALUE='1UF',
 PRIM_FILE='./archive_libs/logical/q_cap/chips/chips.prt';

PART_NAME
 C1047 'Q_CAP_C0201-0.1UF,10V,10%,X7S,CH4102K6E00':;

SECTION_NUMBER 1
 '@T6G_MB_LIB.T6G(SCH_1):PAGE433_I56@PURE_QUANTA.Q_CAP(CHIPS)':
 C_PATH='@t6g_mb_lib.t6g(sch_1):page433_i56@pure_quanta.q_cap(chips)',
 P_PATH='@t6g_mb_lib.t6g(sch_1):page312_i56@pure_quanta.q_cap(chips)',
 PATH='I56',
 DRAWING='@T6G_MB_LIB.T6G(SCH_1):PAGE433',
 TOLERANCE='10%',
 MATERIAL='X7S',
 PHYS_PAGE='312',
 XY='(-1525,2425)',
 ROT='0',
 VER='1',
 PACK_TYPE='C0201',
 LOCATION='C1047',
 CDS_LIB='pure_quanta',
 CDS_PART_NAME='Q_CAP_C0201-0.1UF,10V,10%,X7S,CH4102K6E00',
 VOLTAGE='10V',
 PART_NUMBER='CH4102K6E00',
 VALUE='0.1UF',
 PRIM_FILE='./archive_libs/logical/q_cap/chips/chips.prt';

PART_NAME
 C1048 'Q_CAP_C0201-0.1UF,10V,10%,X7S,CH4102K6E00':;

SECTION_NUMBER 1
 '@T6G_MB_LIB.T6G(SCH_1):PAGE433_I85@PURE_QUANTA.Q_CAP(CHIPS)':
 C_PATH='@t6g_mb_lib.t6g(sch_1):page433_i85@pure_quanta.q_cap(chips)',
 P_PATH='@t6g_mb_lib.t6g(sch_1):page312_i85@pure_quanta.q_cap(chips)',
 PATH='I85',
 DRAWING='@T6G_MB_LIB.T6G(SCH_1):PAGE433',
 TOLERANCE='10%',
 MATERIAL='X7S',
 PHYS_PAGE='312',
 XY='(-1275,5600)',
 ROT='0',
 VER='1',
 PACK_TYPE='C0201',
 LOCATION='C1048',
 CDS_LIB='pure_quanta',
 CDS_PART_NAME='Q_CAP_C0201-0.1UF,10V,10%,X7S,CH4102K6E00',
 VOLTAGE='10V',
 PART_NUMBER='CH4102K6E00',
 VALUE='0.1UF',
 PRIM_FILE='./archive_libs/logical/q_cap/chips/chips.prt';

PART_NAME
 C1049 'Q_CAP_C0402-10UF,6.3V,20%,X6S,CH6101MEB01':;

SECTION_NUMBER 1
 '@T6G_MB_LIB.T6G(SCH_1):PAGE433_I80@PURE_QUANTA.Q_CAP(CHIPS)':
 C_PATH='@t6g_mb_lib.t6g(sch_1):page433_i80@pure_quanta.q_cap(chips)',
 P_PATH='@t6g_mb_lib.t6g(sch_1):page312_i80@pure_quanta.q_cap(chips)',
 PATH='I80',
 DRAWING='@T6G_MB_LIB.T6G(SCH_1):PAGE433',
 TOLERANCE='20%',
 MATERIAL='X6S',
 PHYS_PAGE='312',
 XY='(-1425,4375)',
 ROT='0',
 VER='1',
 PACK_TYPE='C0402',
 LOCATION='C1049',
 CDS_LIB='pure_quanta',
 CDS_PART_NAME='Q_CAP_C0402-10UF,6.3V,20%,X6S,CH6101MEB01',
 VOLTAGE='6.3V',
 PART_NUMBER='CH6101MEB01',
 VALUE='10UF',
 PRIM_FILE='./archive_libs/logical/q_cap/chips/chips.prt';

PART_NAME
 C1050 'Q_CAP_0201-1UF,4V,20%,X6S,CH-10KMEE00':;

SECTION_NUMBER 1
 '@T6G_MB_LIB.T6G(SCH_1):PAGE433_I60@PURE_QUANTA.Q_CAP(CHIPS)':
 C_PATH='@t6g_mb_lib.t6g(sch_1):page433_i60@pure_quanta.q_cap(chips)',
 P_PATH='@t6g_mb_lib.t6g(sch_1):page312_i60@pure_quanta.q_cap(chips)',
 PATH='I60',
 DRAWING='@T6G_MB_LIB.T6G(SCH_1):PAGE433',
 TOLERANCE='20%',
 MATERIAL='X6S',
 PHYS_PAGE='312',
 XY='(-2025,3750)',
 ROT='0',
 VER='1',
 PACK_TYPE='0201',
 LOCATION='C1050',
 CDS_LIB='pure_quanta',
 CDS_PART_NAME='Q_CAP_0201-1UF,4V,20%,X6S,CH-10KMEE00',
 VOLTAGE='4V',
 PART_NUMBER='CH-10KMEE00',
 VALUE='1UF',
 PRIM_FILE='./archive_libs/logical/q_cap/chips/chips.prt';

PART_NAME
 C1051 'Q_CAP_C0201-0.1UF,10V,10%,X7S,CH4102K6E00':;

SECTION_NUMBER 1
 '@T6G_MB_LIB.T6G(SCH_1):PAGE433_I92@PURE_QUANTA.Q_CAP(CHIPS)':
 C_PATH='@t6g_mb_lib.t6g(sch_1):page433_i92@pure_quanta.q_cap(chips)',
 P_PATH='@t6g_mb_lib.t6g(sch_1):page312_i92@pure_quanta.q_cap(chips)',
 PATH='I92',
 DRAWING='@T6G_MB_LIB.T6G(SCH_1):PAGE433',
 TOLERANCE='10%',
 MATERIAL='X7S',
 PHYS_PAGE='312',
 XY='(-2000,3100)',
 ROT='0',
 VER='1',
 PACK_TYPE='C0201',
 LOCATION='C1051',
 CDS_LIB='pure_quanta',
 CDS_PART_NAME='Q_CAP_C0201-0.1UF,10V,10%,X7S,CH4102K6E00',
 VOLTAGE='10V',
 PART_NUMBER='CH4102K6E00',
 VALUE='0.1UF',
 PRIM_FILE='./archive_libs/logical/q_cap/chips/chips.prt';

PART_NAME
 C1052 'Q_CAP_C0201-0.1UF,10V,10%,X7S,CH4102K6E00':;

SECTION_NUMBER 1
 '@T6G_MB_LIB.T6G(SCH_1):PAGE433_I42@PURE_QUANTA.Q_CAP(CHIPS)':
 C_PATH='@t6g_mb_lib.t6g(sch_1):page433_i42@pure_quanta.q_cap(chips)',
 P_PATH='@t6g_mb_lib.t6g(sch_1):page312_i42@pure_quanta.q_cap(chips)',
 PATH='I42',
 DRAWING='@T6G_MB_LIB.T6G(SCH_1):PAGE433',
 TOLERANCE='10%',
 MATERIAL='X7S',
 PHYS_PAGE='312',
 XY='(-3050,2425)',
 ROT='0',
 VER='1',
 PACK_TYPE='C0201',
 LOCATION='C1052',
 CDS_LIB='pure_quanta',
 CDS_PART_NAME='Q_CAP_C0201-0.1UF,10V,10%,X7S,CH4102K6E00',
 VOLTAGE='10V',
 PART_NUMBER='CH4102K6E00',
 VALUE='0.1UF',
 PRIM_FILE='./archive_libs/logical/q_cap/chips/chips.prt';

PART_NAME
 C1053 'Q_CAP_C0201-0.1UF,10V,10%,X7S,CH4102K6E00':;

SECTION_NUMBER 1
 '@T6G_MB_LIB.T6G(SCH_1):PAGE433_I93@PURE_QUANTA.Q_CAP(CHIPS)':
 C_PATH='@t6g_mb_lib.t6g(sch_1):page433_i93@pure_quanta.q_cap(chips)',
 P_PATH='@t6g_mb_lib.t6g(sch_1):page312_i93@pure_quanta.q_cap(chips)',
 PATH='I93',
 DRAWING='@T6G_MB_LIB.T6G(SCH_1):PAGE433',
 TOLERANCE='10%',
 MATERIAL='X7S',
 PHYS_PAGE='312',
 XY='(-1750,3100)',
 ROT='0',
 VER='1',
 PACK_TYPE='C0201',
 LOCATION='C1053',
 CDS_LIB='pure_quanta',
 CDS_PART_NAME='Q_CAP_C0201-0.1UF,10V,10%,X7S,CH4102K6E00',
 VOLTAGE='10V',
 PART_NUMBER='CH4102K6E00',
 VALUE='0.1UF',
 PRIM_FILE='./archive_libs/logical/q_cap/chips/chips.prt';

PART_NAME
 C1054 'Q_CAP_0402-4.7UF,6.3V,20%,X6S,CH5471MEB01':;

SECTION_NUMBER 1
 '@T6G_MB_LIB.T6G(SCH_1):PAGE433_I50@PURE_QUANTA.Q_CAP(CHIPS)':
 C_PATH='@t6g_mb_lib.t6g(sch_1):page433_i50@pure_quanta.q_cap(chips)',
 P_PATH='@t6g_mb_lib.t6g(sch_1):page312_i50@pure_quanta.q_cap(chips)',
 PATH='I50',
 DRAWING='@T6G_MB_LIB.T6G(SCH_1):PAGE433',
 TOLERANCE='20%',
 MATERIAL='X6S',
 PHYS_PAGE='312',
 XY='(-2700,3750)',
 ROT='0',
 VER='1',
 PACK_TYPE='0402',
 LOCATION='C1054',
 CDS_LIB='pure_quanta',
 CDS_PART_NAME='Q_CAP_0402-4.7UF,6.3V,20%,X6S,CH5471MEB01',
 VOLTAGE='6.3V',
 PART_NUMBER='CH5471MEB01',
 VALUE='4.7UF',
 PRIM_FILE='./archive_libs/logical/q_cap/chips/chips.prt';

PART_NAME
 C1055 'Q_CAP_C0201-0.1UF,10V,10%,X7S,CH4102K6E00':;

SECTION_NUMBER 1
 '@T6G_MB_LIB.T6G(SCH_1):PAGE433_I43@PURE_QUANTA.Q_CAP(CHIPS)':
 C_PATH='@t6g_mb_lib.t6g(sch_1):page433_i43@pure_quanta.q_cap(chips)',
 P_PATH='@t6g_mb_lib.t6g(sch_1):page312_i43@pure_quanta.q_cap(chips)',
 PATH='I43',
 DRAWING='@T6G_MB_LIB.T6G(SCH_1):PAGE433',
 TOLERANCE='10%',
 MATERIAL='X7S',
 PHYS_PAGE='312',
 XY='(-2825,2425)',
 ROT='0',
 VER='1',
 PACK_TYPE='C0201',
 LOCATION='C1055',
 CDS_LIB='pure_quanta',
 CDS_PART_NAME='Q_CAP_C0201-0.1UF,10V,10%,X7S,CH4102K6E00',
 VOLTAGE='10V',
 PART_NUMBER='CH4102K6E00',
 VALUE='0.1UF',
 PRIM_FILE='./archive_libs/logical/q_cap/chips/chips.prt';

PART_NAME
 C1056 'Q_CAP_0402-4.7UF,6.3V,20%,X6S,CH5471MEB01':;

SECTION_NUMBER 1
 '@T6G_MB_LIB.T6G(SCH_1):PAGE433_I51@PURE_QUANTA.Q_CAP(CHIPS)':
 C_PATH='@t6g_mb_lib.t6g(sch_1):page433_i51@pure_quanta.q_cap(chips)',
 P_PATH='@t6g_mb_lib.t6g(sch_1):page312_i51@pure_quanta.q_cap(chips)',
 PATH='I51',
 DRAWING='@T6G_MB_LIB.T6G(SCH_1):PAGE433',
 TOLERANCE='20%',
 MATERIAL='X6S',
 PHYS_PAGE='312',
 XY='(-2475,3750)',
 ROT='0',
 VER='1',
 PACK_TYPE='0402',
 LOCATION='C1056',
 CDS_LIB='pure_quanta',
 CDS_PART_NAME='Q_CAP_0402-4.7UF,6.3V,20%,X6S,CH5471MEB01',
 VOLTAGE='6.3V',
 PART_NUMBER='CH5471MEB01',
 VALUE='4.7UF',
 PRIM_FILE='./archive_libs/logical/q_cap/chips/chips.prt';

PART_NAME
 C1057 'Q_CAP_C0201-0.1UF,10V,10%,X7S,CH4102K6E00':;

SECTION_NUMBER 1
 '@T6G_MB_LIB.T6G(SCH_1):PAGE432_I23@PURE_QUANTA.Q_CAP(CHIPS)':
 C_PATH='@t6g_mb_lib.t6g(sch_1):page432_i23@pure_quanta.q_cap(chips)',
 P_PATH='@t6g_mb_lib.t6g(sch_1):page311_i23@pure_quanta.q_cap(chips)',
 PATH='I23',
 DRAWING='@T6G_MB_LIB.T6G(SCH_1):PAGE432',
 TOLERANCE='10%',
 MATERIAL='X7S',
 PHYS_PAGE='311',
 XY='(-5575,6125)',
 ROT='0',
 VER='1',
 PACK_TYPE='C0201',
 LOCATION='C1057',
 CDS_LIB='pure_quanta',
 CDS_PART_NAME='Q_CAP_C0201-0.1UF,10V,10%,X7S,CH4102K6E00',
 VOLTAGE='10V',
 PART_NUMBER='CH4102K6E00',
 VALUE='0.1UF',
 PRIM_FILE='./archive_libs/logical/q_cap/chips/chips.prt';

PART_NAME
 C1058 'Q_CAP_0402-0.1UF,25V,10%,X7R,CH4104K1B00':;

SECTION_NUMBER 1
 '@T6G_MB_LIB.T6G(SCH_1):PAGE340_I53@PURE_QUANTA.Q_CAP(CHIPS)':
 C_PATH='@t6g_mb_lib.t6g(sch_1):page340_i53@pure_quanta.q_cap(chips)',
 P_PATH='@t6g_mb_lib.t6g(sch_1):page136_i53@pure_quanta.q_cap(chips)',
 PATH='I53',
 DRAWING='@T6G_MB_LIB.T6G(SCH_1):PAGE340',
 TOLERANCE='10%',
 MATERIAL='X7R',
 PHYS_PAGE='136',
 XY='(-3100,7875)',
 ROT='2',
 VER='1',
 PACK_TYPE='0402',
 LOCATION='C1058',
 CDS_LIB='pure_quanta',
 CDS_PART_NAME='Q_CAP_0402-0.1UF,25V,10%,X7R,CH4104K1B00',
 VOLTAGE='25V',
 PART_NUMBER='CH4104K1B00',
 VALUE='0.1UF',
 PRIM_FILE='./archive_libs/logical/q_cap/chips/chips.prt';

PART_NAME
 C1059 'Q_CAP_0402-0.1UF,25V,10%,X7R,CH4104K1B00':;

SECTION_NUMBER 1
 '@T6G_MB_LIB.T6G(SCH_1):PAGE340_I40@PURE_QUANTA.Q_CAP(CHIPS)':
 C_PATH='@t6g_mb_lib.t6g(sch_1):page340_i40@pure_quanta.q_cap(chips)',
 P_PATH='@t6g_mb_lib.t6g(sch_1):page136_i40@pure_quanta.q_cap(chips)',
 PATH='I40',
 DRAWING='@T6G_MB_LIB.T6G(SCH_1):PAGE340',
 TOLERANCE='10%',
 MATERIAL='X7R',
 PHYS_PAGE='136',
 XY='(-150,9550)',
 ROT='0',
 VER='1',
 PACK_TYPE='0402',
 LOCATION='C1059',
 CDS_LIB='pure_quanta',
 CDS_PART_NAME='Q_CAP_0402-0.1UF,25V,10%,X7R,CH4104K1B00',
 VOLTAGE='25V',
 PART_NUMBER='CH4104K1B00',
 VALUE='0.1UF',
 PRIM_FILE='./archive_libs/logical/q_cap/chips/chips.prt';

PART_NAME
 C1060 'Q_CAP_0402-0.1UF,25V,10%,X7R,CH4104K1B00':;

SECTION_NUMBER 1
 '@T6G_MB_LIB.T6G(SCH_1):PAGE340_I69@PURE_QUANTA.Q_CAP(CHIPS)':
 C_PATH='@t6g_mb_lib.t6g(sch_1):page340_i69@pure_quanta.q_cap(chips)',
 P_PATH='@t6g_mb_lib.t6g(sch_1):page136_i69@pure_quanta.q_cap(chips)',
 PATH='I69',
 DRAWING='@T6G_MB_LIB.T6G(SCH_1):PAGE340',
 TOLERANCE='10%',
 MATERIAL='X7R',
 PHYS_PAGE='136',
 XY='(175,8650)',
 ROT='2',
 VER='1',
 PACK_TYPE='0402',
 LOCATION='C1060',
 CDS_LIB='pure_quanta',
 CDS_PART_NAME='Q_CAP_0402-0.1UF,25V,10%,X7R,CH4104K1B00',
 VOLTAGE='25V',
 PART_NUMBER='CH4104K1B00',
 VALUE='0.1UF',
 PRIM_FILE='./archive_libs/logical/q_cap/chips/chips.prt';

PART_NAME
 C1061 'Q_CAP_0402-0.1UF,25V,10%,X7R,CH4104K1B00':;

SECTION_NUMBER 1
 '@T6G_MB_LIB.T6G(SCH_1):PAGE257_I5@PURE_QUANTA.Q_CAP(CHIPS)':
 C_PATH='@t6g_mb_lib.t6g(sch_1):page257_i5@pure_quanta.q_cap(chips)',
 P_PATH='@t6g_mb_lib.t6g(sch_1):page142_i5@pure_quanta.q_cap(chips)',
 PATH='I5',
 DRAWING='@T6G_MB_LIB.T6G(SCH_1):PAGE257',
 TOLERANCE='10%',
 MATERIAL='X7R',
 PHYS_PAGE='142',
 XY='(-3300,2000)',
 ROT='2',
 VER='1',
 PACK_TYPE='0402',
 LOCATION='C1061',
 CDS_LIB='pure_quanta',
 CDS_PART_NAME='Q_CAP_0402-0.1UF,25V,10%,X7R,CH4104K1B00',
 VOLTAGE='25V',
 PART_NUMBER='CH4104K1B00',
 VALUE='0.1UF',
 PRIM_FILE='./archive_libs/logical/q_cap/chips/chips.prt';

PART_NAME
 C1062 'Q_CAP_0402-0.1UF,25V,10%,X7R,CH4104K1B00':;

SECTION_NUMBER 1
 '@T6G_MB_LIB.T6G(SCH_1):PAGE257_I36@PURE_QUANTA.Q_CAP(CHIPS)':
 C_PATH='@t6g_mb_lib.t6g(sch_1):page257_i36@pure_quanta.q_cap(chips)',
 P_PATH='@t6g_mb_lib.t6g(sch_1):page142_i36@pure_quanta.q_cap(chips)',
 PATH='I36',
 DRAWING='@T6G_MB_LIB.T6G(SCH_1):PAGE257',
 TOLERANCE='10%',
 MATERIAL='X7R',
 PHYS_PAGE='142',
 XY='(-350,3675)',
 ROT='0',
 VER='1',
 PACK_TYPE='0402',
 LOCATION='C1062',
 CDS_LIB='pure_quanta',
 CDS_PART_NAME='Q_CAP_0402-0.1UF,25V,10%,X7R,CH4104K1B00',
 VOLTAGE='25V',
 PART_NUMBER='CH4104K1B00',
 VALUE='0.1UF',
 PRIM_FILE='./archive_libs/logical/q_cap/chips/chips.prt';

PART_NAME
 C1063 'Q_CAP_0402-0.1UF,25V,10%,X7R,CH4104K1B00':;

SECTION_NUMBER 1
 '@T6G_MB_LIB.T6G(SCH_1):PAGE257_I55@PURE_QUANTA.Q_CAP(CHIPS)':
 C_PATH='@t6g_mb_lib.t6g(sch_1):page257_i55@pure_quanta.q_cap(chips)',
 P_PATH='@t6g_mb_lib.t6g(sch_1):page142_i55@pure_quanta.q_cap(chips)',
 PATH='I55',
 DRAWING='@T6G_MB_LIB.T6G(SCH_1):PAGE257',
 TOLERANCE='10%',
 MATERIAL='X7R',
 PHYS_PAGE='142',
 XY='(-25,2775)',
 ROT='2',
 VER='1',
 PACK_TYPE='0402',
 LOCATION='C1063',
 CDS_LIB='pure_quanta',
 CDS_PART_NAME='Q_CAP_0402-0.1UF,25V,10%,X7R,CH4104K1B00',
 VOLTAGE='25V',
 PART_NUMBER='CH4104K1B00',
 VALUE='0.1UF',
 PRIM_FILE='./archive_libs/logical/q_cap/chips/chips.prt';

PART_NAME
 C1064 'Q_CAP_0402-0.1UF,25V,10%,X7R,CH4104K1B00':;

SECTION_NUMBER 1
 '@T6G_MB_LIB.T6G(SCH_1):PAGE257_I46@PURE_QUANTA.Q_CAP(CHIPS)':
 C_PATH='@t6g_mb_lib.t6g(sch_1):page257_i46@pure_quanta.q_cap(chips)',
 P_PATH='@t6g_mb_lib.t6g(sch_1):page142_i46@pure_quanta.q_cap(chips)',
 PATH='I46',
 DRAWING='@T6G_MB_LIB.T6G(SCH_1):PAGE257',
 TOLERANCE='10%',
 MATERIAL='X7R',
 PHYS_PAGE='142',
 XY='(850,1000)',
 ROT='0',
 VER='1',
 PACK_TYPE='0402',
 LOCATION='C1064',
 CDS_LIB='pure_quanta',
 CDS_PART_NAME='Q_CAP_0402-0.1UF,25V,10%,X7R,CH4104K1B00',
 VOLTAGE='25V',
 PART_NUMBER='CH4104K1B00',
 VALUE='0.1UF',
 PRIM_FILE='./archive_libs/logical/q_cap/chips/chips.prt';

PART_NAME
 C1065 'Q_CAP_0402-0.1UF,25V,10%,X7R,CH4104K1B00':;

SECTION_NUMBER 1
 '@T6G_MB_LIB.T6G(SCH_1):PAGE257_I14@PURE_QUANTA.Q_CAP(CHIPS)':
 C_PATH='@t6g_mb_lib.t6g(sch_1):page257_i14@pure_quanta.q_cap(chips)',
 P_PATH='@t6g_mb_lib.t6g(sch_1):page142_i14@pure_quanta.q_cap(chips)',
 PATH='I14',
 DRAWING='@T6G_MB_LIB.T6G(SCH_1):PAGE257',
 TOLERANCE='10%',
 MATERIAL='X7R',
 PHYS_PAGE='142',
 XY='(-250,-175)',
 ROT='2',
 VER='1',
 PACK_TYPE='0402',
 LOCATION='C1065',
 CDS_LIB='pure_quanta',
 CDS_PART_NAME='Q_CAP_0402-0.1UF,25V,10%,X7R,CH4104K1B00',
 VOLTAGE='25V',
 PART_NUMBER='CH4104K1B00',
 VALUE='0.1UF',
 PRIM_FILE='./archive_libs/logical/q_cap/chips/chips.prt';

PART_NAME
 C1066 'Q_CAP_C0201-0.1UF,10V,10%,X7S,CH4102K6E00':;

SECTION_NUMBER 1
 '@T6G_MB_LIB.T6G(SCH_1):PAGE376_I48@PURE_QUANTA.Q_CAP(CHIPS)':
 C_PATH='@t6g_mb_lib.t6g(sch_1):page376_i48@pure_quanta.q_cap(chips)',
 P_PATH='@t6g_mb_lib.t6g(sch_1):page186_i48@pure_quanta.q_cap(chips)',
 PATH='I48',
 DRAWING='@T6G_MB_LIB.T6G(SCH_1):PAGE376',
 TOLERANCE='10%',
 MATERIAL='X7S',
 PHYS_PAGE='186',
 XY='(-5575,3175)',
 ROT='0',
 VER='1',
 PACK_TYPE='C0201',
 LOCATION='C1066',
 CDS_LIB='pure_quanta',
 CDS_PART_NAME='Q_CAP_C0201-0.1UF,10V,10%,X7S,CH4102K6E00',
 VOLTAGE='10V',
 PART_NUMBER='CH4102K6E00',
 VALUE='0.1UF',
 PRIM_FILE='./archive_libs/logical/q_cap/chips/chips.prt';

PART_NAME
 C1067 'Q_CAP_C0201-0.1UF,10V,10%,X7S,CH4102K6E00':;

SECTION_NUMBER 1
 '@T6G_MB_LIB.T6G(SCH_1):PAGE376_I37@PURE_QUANTA.Q_CAP(CHIPS)':
 C_PATH='@t6g_mb_lib.t6g(sch_1):page376_i37@pure_quanta.q_cap(chips)',
 P_PATH='@t6g_mb_lib.t6g(sch_1):page186_i37@pure_quanta.q_cap(chips)',
 PATH='I37',
 DRAWING='@T6G_MB_LIB.T6G(SCH_1):PAGE376',
 TOLERANCE='10%',
 MATERIAL='X7S',
 PHYS_PAGE='186',
 XY='(-5525,4650)',
 ROT='0',
 VER='1',
 PACK_TYPE='C0201',
 LOCATION='C1067',
 CDS_LIB='pure_quanta',
 CDS_PART_NAME='Q_CAP_C0201-0.1UF,10V,10%,X7S,CH4102K6E00',
 VOLTAGE='10V',
 PART_NUMBER='CH4102K6E00',
 VALUE='0.1UF',
 PRIM_FILE='./archive_libs/logical/q_cap/chips/chips.prt';

PART_NAME
 C1068 'Q_CAP_C0201-0.1UF,10V,10%,X7S,CH4102K6E00':;

SECTION_NUMBER 1
 '@T6G_MB_LIB.T6G(SCH_1):PAGE376_I65@PURE_QUANTA.Q_CAP(CHIPS)':
 C_PATH='@t6g_mb_lib.t6g(sch_1):page376_i65@pure_quanta.q_cap(chips)',
 P_PATH='@t6g_mb_lib.t6g(sch_1):page186_i65@pure_quanta.q_cap(chips)',
 PATH='I65',
 DRAWING='@T6G_MB_LIB.T6G(SCH_1):PAGE376',
 TOLERANCE='10%',
 MATERIAL='X7S',
 PHYS_PAGE='186',
 XY='(-5525,1575)',
 ROT='0',
 VER='1',
 PACK_TYPE='C0201',
 LOCATION='C1068',
 CDS_LIB='pure_quanta',
 CDS_PART_NAME='Q_CAP_C0201-0.1UF,10V,10%,X7S,CH4102K6E00',
 VOLTAGE='10V',
 PART_NUMBER='CH4102K6E00',
 VALUE='0.1UF',
 PRIM_FILE='./archive_libs/logical/q_cap/chips/chips.prt';

PART_NAME
 C1069 'Q_CAP_C0201-0.1UF,10V,10%,X7S,CH4102K6E00':;

SECTION_NUMBER 1
 '@T6G_MB_LIB.T6G(SCH_1):PAGE376_I24@PURE_QUANTA.Q_CAP(CHIPS)':
 C_PATH='@t6g_mb_lib.t6g(sch_1):page376_i24@pure_quanta.q_cap(chips)',
 P_PATH='@t6g_mb_lib.t6g(sch_1):page186_i24@pure_quanta.q_cap(chips)',
 PATH='I24',
 DRAWING='@T6G_MB_LIB.T6G(SCH_1):PAGE376',
 TOLERANCE='10%',
 MATERIAL='X7S',
 PHYS_PAGE='186',
 XY='(-5450,6075)',
 ROT='0',
 VER='1',
 PACK_TYPE='C0201',
 LOCATION='C1069',
 CDS_LIB='pure_quanta',
 CDS_PART_NAME='Q_CAP_C0201-0.1UF,10V,10%,X7S,CH4102K6E00',
 VOLTAGE='10V',
 PART_NUMBER='CH4102K6E00',
 VALUE='0.1UF',
 PRIM_FILE='./archive_libs/logical/q_cap/chips/chips.prt';

PART_NAME
 C1070 'Q_CAP_C0201-0.1UF,10V,10%,X7S,CH4102K6E00':;

SECTION_NUMBER 1
 '@T6G_MB_LIB.T6G(SCH_1):PAGE376_I99@PURE_QUANTA.Q_CAP(CHIPS)':
 C_PATH='@t6g_mb_lib.t6g(sch_1):page376_i99@pure_quanta.q_cap(chips)',
 P_PATH='@t6g_mb_lib.t6g(sch_1):page186_i99@pure_quanta.q_cap(chips)',
 PATH='I99',
 DRAWING='@T6G_MB_LIB.T6G(SCH_1):PAGE376',
 TOLERANCE='10%',
 MATERIAL='X7S',
 PHYS_PAGE='186',
 XY='(-1200,2550)',
 ROT='0',
 VER='1',
 PACK_TYPE='C0201',
 LOCATION='C1070',
 CDS_LIB='pure_quanta',
 CDS_PART_NAME='Q_CAP_C0201-0.1UF,10V,10%,X7S,CH4102K6E00',
 VOLTAGE='10V',
 PART_NUMBER='CH4102K6E00',
 VALUE='0.1UF',
 PRIM_FILE='./archive_libs/logical/q_cap/chips/chips.prt';

PART_NAME
 C1071 'Q_CAP_C0201-0.1UF,10V,10%,X7S,CH4102K6E00':;

SECTION_NUMBER 1
 '@T6G_MB_LIB.T6G(SCH_1):PAGE376_I105@PURE_QUANTA.Q_CAP(CHIPS)':
 C_PATH='@t6g_mb_lib.t6g(sch_1):page376_i105@pure_quanta.q_cap(chips)',
 P_PATH='@t6g_mb_lib.t6g(sch_1):page186_i105@pure_quanta.q_cap(chips)',
 PATH='I105',
 DRAWING='@T6G_MB_LIB.T6G(SCH_1):PAGE376',
 TOLERANCE='10%',
 MATERIAL='X7S',
 PHYS_PAGE='186',
 XY='(-1175,1125)',
 ROT='0',
 VER='1',
 PACK_TYPE='C0201',
 LOCATION='C1071',
 CDS_LIB='pure_quanta',
 CDS_PART_NAME='Q_CAP_C0201-0.1UF,10V,10%,X7S,CH4102K6E00',
 VOLTAGE='10V',
 PART_NUMBER='CH4102K6E00',
 VALUE='0.1UF',
 PRIM_FILE='./archive_libs/logical/q_cap/chips/chips.prt';

PART_NAME
 C1072 'Q_CAP_C0201-0.1UF,10V,10%,X7S,CH4102K6E00':;

SECTION_NUMBER 1
 '@T6G_MB_LIB.T6G(SCH_1):PAGE376_I84@PURE_QUANTA.Q_CAP(CHIPS)':
 C_PATH='@t6g_mb_lib.t6g(sch_1):page376_i84@pure_quanta.q_cap(chips)',
 P_PATH='@t6g_mb_lib.t6g(sch_1):page186_i84@pure_quanta.q_cap(chips)',
 PATH='I84',
 DRAWING='@T6G_MB_LIB.T6G(SCH_1):PAGE376',
 TOLERANCE='10%',
 MATERIAL='X7S',
 PHYS_PAGE='186',
 XY='(-1150,4025)',
 ROT='0',
 VER='1',
 PACK_TYPE='C0201',
 LOCATION='C1072',
 CDS_LIB='pure_quanta',
 CDS_PART_NAME='Q_CAP_C0201-0.1UF,10V,10%,X7S,CH4102K6E00',
 VOLTAGE='10V',
 PART_NUMBER='CH4102K6E00',
 VALUE='0.1UF',
 PRIM_FILE='./archive_libs/logical/q_cap/chips/chips.prt';

PART_NAME
 C1073 'Q_CAP_C0201-0.1UF,10V,10%,X7S,CH4102K6E00':;

SECTION_NUMBER 1
 '@T6G_MB_LIB.T6G(SCH_1):PAGE376_I80@PURE_QUANTA.Q_CAP(CHIPS)':
 C_PATH='@t6g_mb_lib.t6g(sch_1):page376_i80@pure_quanta.q_cap(chips)',
 P_PATH='@t6g_mb_lib.t6g(sch_1):page186_i80@pure_quanta.q_cap(chips)',
 PATH='I80',
 DRAWING='@T6G_MB_LIB.T6G(SCH_1):PAGE376',
 TOLERANCE='10%',
 MATERIAL='X7S',
 PHYS_PAGE='186',
 XY='(-1075,5550)',
 ROT='0',
 VER='1',
 PACK_TYPE='C0201',
 LOCATION='C1073',
 CDS_LIB='pure_quanta',
 CDS_PART_NAME='Q_CAP_C0201-0.1UF,10V,10%,X7S,CH4102K6E00',
 VOLTAGE='10V',
 PART_NUMBER='CH4102K6E00',
 VALUE='0.1UF',
 PRIM_FILE='./archive_libs/logical/q_cap/chips/chips.prt';

PART_NAME
 C1074 'Q_CAP_0402-0.1UF,25V,10%,X7R,CH4104K1B00':;

SECTION_NUMBER 1
 '@T6G_MB_LIB.T6G(SCH_1):PAGE263_I115@PURE_QUANTA.Q_CAP(CHIPS)':
 C_PATH='@t6g_mb_lib.t6g(sch_1):page263_i115@pure_quanta.q_cap(chips)',
 P_PATH='@t6g_mb_lib.t6g(sch_1):page258_i115@pure_quanta.q_cap(chips)',
 PATH='I115',
 DRAWING='@T6G_MB_LIB.T6G(SCH_1):PAGE263',
 TOLERANCE='10%',
 MATERIAL='X7R',
 PHYS_PAGE='258',
 XY='(-4150,5200)',
 ROT='2',
 VER='1',
 PACK_TYPE='0402',
 LOCATION='C1074',
 CDS_LIB='pure_quanta',
 CDS_PART_NAME='Q_CAP_0402-0.1UF,25V,10%,X7R,CH4104K1B00',
 VOLTAGE='25V',
 PART_NUMBER='CH4104K1B00',
 VALUE='0.1UF',
 PRIM_FILE='./archive_libs/logical/q_cap/chips/chips.prt';

PART_NAME
 C1075 'Q_CAP_0402-0.1UF,25V,10%,X7R,CH4104K1B00':;

SECTION_NUMBER 1
 '@T6G_MB_LIB.T6G(SCH_1):PAGE263_I165@PURE_QUANTA.Q_CAP(CHIPS)':
 C_PATH='@t6g_mb_lib.t6g(sch_1):page263_i165@pure_quanta.q_cap(chips)',
 P_PATH='@t6g_mb_lib.t6g(sch_1):page258_i165@pure_quanta.q_cap(chips)',
 PATH='I165',
 DRAWING='@T6G_MB_LIB.T6G(SCH_1):PAGE263',
 TOLERANCE='10%',
 MATERIAL='X7R',
 PHYS_PAGE='258',
 XY='(-1450,5175)',
 ROT='2',
 VER='1',
 PACK_TYPE='0402',
 LOCATION='C1075',
 CDS_LIB='pure_quanta',
 CDS_PART_NAME='Q_CAP_0402-0.1UF,25V,10%,X7R,CH4104K1B00',
 VOLTAGE='25V',
 PART_NUMBER='CH4104K1B00',
 VALUE='0.1UF',
 PRIM_FILE='./archive_libs/logical/q_cap/chips/chips.prt';

PART_NAME
 C1076 'Q_CAP_C0805-10UF,16V,10%,X6S,CH6103KEA00':;

SECTION_NUMBER 1
 '@T6G_MB_LIB.T6G(SCH_1):PAGE263_I152@PURE_QUANTA.Q_CAP(CHIPS)':
 C_PATH='@t6g_mb_lib.t6g(sch_1):page263_i152@pure_quanta.q_cap(chips)',
 P_PATH='@t6g_mb_lib.t6g(sch_1):page258_i152@pure_quanta.q_cap(chips)',
 PATH='I152',
 DRAWING='@T6G_MB_LIB.T6G(SCH_1):PAGE263',
 TOLERANCE='10%',
 MATERIAL='X6S',
 PHYS_PAGE='258',
 XY='(-3775,5200)',
 ROT='0',
 VER='1',
 PACK_TYPE='C0805',
 LOCATION='C1076',
 CDS_LIB='pure_quanta',
 CDS_PART_NAME='Q_CAP_C0805-10UF,16V,10%,X6S,CH6103KEA00',
 VOLTAGE='16V',
 PART_NUMBER='CH6103KEA00',
 VALUE='10UF',
 PRIM_FILE='./archive_libs/logical/q_cap/chips/chips.prt';

PART_NAME
 C1077 'Q_CAP_C0805-10UF,16V,10%,X6S,CH6103KEA00':;

SECTION_NUMBER 1
 '@T6G_MB_LIB.T6G(SCH_1):PAGE263_I166@PURE_QUANTA.Q_CAP(CHIPS)':
 C_PATH='@t6g_mb_lib.t6g(sch_1):page263_i166@pure_quanta.q_cap(chips)',
 P_PATH='@t6g_mb_lib.t6g(sch_1):page258_i166@pure_quanta.q_cap(chips)',
 PATH='I166',
 DRAWING='@T6G_MB_LIB.T6G(SCH_1):PAGE263',
 TOLERANCE='10%',
 MATERIAL='X6S',
 PHYS_PAGE='258',
 XY='(-1075,5175)',
 ROT='0',
 VER='1',
 PACK_TYPE='C0805',
 LOCATION='C1077',
 CDS_LIB='pure_quanta',
 CDS_PART_NAME='Q_CAP_C0805-10UF,16V,10%,X6S,CH6103KEA00',
 VOLTAGE='16V',
 PART_NUMBER='CH6103KEA00',
 VALUE='10UF',
 PRIM_FILE='./archive_libs/logical/q_cap/chips/chips.prt';

PART_NAME
 C1078 'Q_CAP_0402-100PF,50V,5%,EMPTY,CH11006JB18':
 ROOM='ADC_MAM_BOM2';

SECTION_NUMBER 1
 '@T6G_MB_LIB.T6G(SCH_1):PAGE263_I173@PURE_QUANTA.Q_CAP(CHIPS)':
 C_PATH='@t6g_mb_lib.t6g(sch_1):page263_i173@pure_quanta.q_cap(chips)',
 P_PATH='@t6g_mb_lib.t6g(sch_1):page258_i173@pure_quanta.q_cap(chips)',
 PATH='I173',
 DRAWING='@T6G_MB_LIB.T6G(SCH_1):PAGE263',
 TOLERANCE='5%',
 MATERIAL='EMPTY',
 PHYS_PAGE='258',
 XY='(-7525,2575)',
 ROT='0',
 VER='1',
 PACK_TYPE='0402',
 LOCATION='C1078',
 CDS_LIB='pure_quanta',
 CDS_PART_NAME='Q_CAP_0402-100PF,50V,5%,EMPTY,CH11006JB18',
 VOLTAGE='50V',
 ROOM='ADC_MAM_BOM2',
 PART_NUMBER='CH11006JB18',
 VALUE='100PF',
 PRIM_FILE='./archive_libs/logical/q_cap/chips/chips.prt';

PART_NAME
 C1079 'Q_CAP_0402-100PF,50V,5%,EMPTY,CH11006JB18':
 ROOM='ADC_MAM_BOM2';

SECTION_NUMBER 1
 '@T6G_MB_LIB.T6G(SCH_1):PAGE263_I185@PURE_QUANTA.Q_CAP(CHIPS)':
 C_PATH='@t6g_mb_lib.t6g(sch_1):page263_i185@pure_quanta.q_cap(chips)',
 P_PATH='@t6g_mb_lib.t6g(sch_1):page258_i185@pure_quanta.q_cap(chips)',
 PATH='I185',
 DRAWING='@T6G_MB_LIB.T6G(SCH_1):PAGE263',
 TOLERANCE='5%',
 MATERIAL='EMPTY',
 PHYS_PAGE='258',
 XY='(-7300,975)',
 ROT='0',
 VER='1',
 PACK_TYPE='0402',
 LOCATION='C1079',
 CDS_LIB='pure_quanta',
 CDS_PART_NAME='Q_CAP_0402-100PF,50V,5%,EMPTY,CH11006JB18',
 VOLTAGE='50V',
 ROOM='ADC_MAM_BOM2',
 PART_NUMBER='CH11006JB18',
 VALUE='100PF',
 PRIM_FILE='./archive_libs/logical/q_cap/chips/chips.prt';

PART_NAME
 C1080 'Q_CAP_0402-100PF,50V,5%,EMPTY,CH11006JB18':
 ROOM='ADC_MAM_BOM2';

SECTION_NUMBER 1
 '@T6G_MB_LIB.T6G(SCH_1):PAGE263_I221@PURE_QUANTA.Q_CAP(CHIPS)':
 C_PATH='@t6g_mb_lib.t6g(sch_1):page263_i221@pure_quanta.q_cap(chips)',
 P_PATH='@t6g_mb_lib.t6g(sch_1):page258_i221@pure_quanta.q_cap(chips)',
 PATH='I221',
 DRAWING='@T6G_MB_LIB.T6G(SCH_1):PAGE263',
 TOLERANCE='5%',
 MATERIAL='EMPTY',
 PHYS_PAGE='258',
 XY='(-5425,2400)',
 ROT='0',
 VER='1',
 PACK_TYPE='0402',
 LOCATION='C1080',
 CDS_LIB='pure_quanta',
 CDS_PART_NAME='Q_CAP_0402-100PF,50V,5%,EMPTY,CH11006JB18',
 VOLTAGE='50V',
 ROOM='ADC_MAM_BOM2',
 PART_NUMBER='CH11006JB18',
 VALUE='100PF',
 PRIM_FILE='./archive_libs/logical/q_cap/chips/chips.prt';

PART_NAME
 C1081 'Q_CAP_0402-100PF,50V,5%,EMPTY,CH11006JB18':
 ROOM='ADC_MAM_BOM2';

SECTION_NUMBER 1
 '@T6G_MB_LIB.T6G(SCH_1):PAGE263_I232@PURE_QUANTA.Q_CAP(CHIPS)':
 C_PATH='@t6g_mb_lib.t6g(sch_1):page263_i232@pure_quanta.q_cap(chips)',
 P_PATH='@t6g_mb_lib.t6g(sch_1):page258_i232@pure_quanta.q_cap(chips)',
 PATH='I232',
 DRAWING='@T6G_MB_LIB.T6G(SCH_1):PAGE263',
 TOLERANCE='5%',
 MATERIAL='EMPTY',
 PHYS_PAGE='258',
 XY='(-5250,875)',
 ROT='0',
 VER='1',
 PACK_TYPE='0402',
 LOCATION='C1081',
 CDS_LIB='pure_quanta',
 CDS_PART_NAME='Q_CAP_0402-100PF,50V,5%,EMPTY,CH11006JB18',
 VOLTAGE='50V',
 ROOM='ADC_MAM_BOM2',
 PART_NUMBER='CH11006JB18',
 VALUE='100PF',
 PRIM_FILE='./archive_libs/logical/q_cap/chips/chips.prt';

PART_NAME
 C1082 'Q_CAP_0402-100PF,50V,5%,EMPTY,CH11006JB18':
 ROOM='ADC_MAM_BOM2';

SECTION_NUMBER 1
 '@T6G_MB_LIB.T6G(SCH_1):PAGE263_I209@PURE_QUANTA.Q_CAP(CHIPS)':
 C_PATH='@t6g_mb_lib.t6g(sch_1):page263_i209@pure_quanta.q_cap(chips)',
 P_PATH='@t6g_mb_lib.t6g(sch_1):page258_i209@pure_quanta.q_cap(chips)',
 PATH='I209',
 DRAWING='@T6G_MB_LIB.T6G(SCH_1):PAGE263',
 TOLERANCE='5%',
 MATERIAL='EMPTY',
 PHYS_PAGE='258',
 XY='(-5200,3825)',
 ROT='0',
 VER='1',
 PACK_TYPE='0402',
 LOCATION='C1082',
 CDS_LIB='pure_quanta',
 CDS_PART_NAME='Q_CAP_0402-100PF,50V,5%,EMPTY,CH11006JB18',
 VOLTAGE='50V',
 ROOM='ADC_MAM_BOM2',
 PART_NUMBER='CH11006JB18',
 VALUE='100PF',
 PRIM_FILE='./archive_libs/logical/q_cap/chips/chips.prt';

PART_NAME
 C1083 'Q_CAP_0402-100PF,50V,5%,EMPTY,CH11006JB18':
 ROOM='ADC_MAM_BOM2';

SECTION_NUMBER 1
 '@T6G_MB_LIB.T6G(SCH_1):PAGE263_I198@PURE_QUANTA.Q_CAP(CHIPS)':
 C_PATH='@t6g_mb_lib.t6g(sch_1):page263_i198@pure_quanta.q_cap(chips)',
 P_PATH='@t6g_mb_lib.t6g(sch_1):page258_i198@pure_quanta.q_cap(chips)',
 PATH='I198',
 DRAWING='@T6G_MB_LIB.T6G(SCH_1):PAGE263',
 TOLERANCE='5%',
 MATERIAL='EMPTY',
 PHYS_PAGE='258',
 XY='(-4950,5375)',
 ROT='0',
 VER='1',
 PACK_TYPE='0402',
 LOCATION='C1083',
 CDS_LIB='pure_quanta',
 CDS_PART_NAME='Q_CAP_0402-100PF,50V,5%,EMPTY,CH11006JB18',
 VOLTAGE='50V',
 ROOM='ADC_MAM_BOM2',
 PART_NUMBER='CH11006JB18',
 VALUE='100PF',
 PRIM_FILE='./archive_libs/logical/q_cap/chips/chips.prt';

PART_NAME
 C1084 'Q_CAP_0402-100PF,50V,5%,EMPTY,CH11006JB18':
 ROOM='ADC_MAM_BOM2';

SECTION_NUMBER 1
 '@T6G_MB_LIB.T6G(SCH_1):PAGE263_I77@PURE_QUANTA.Q_CAP(CHIPS)':
 C_PATH='@t6g_mb_lib.t6g(sch_1):page263_i77@pure_quanta.q_cap(chips)',
 P_PATH='@t6g_mb_lib.t6g(sch_1):page258_i77@pure_quanta.q_cap(chips)',
 PATH='I77',
 DRAWING='@T6G_MB_LIB.T6G(SCH_1):PAGE263',
 TOLERANCE='5%',
 MATERIAL='EMPTY',
 PHYS_PAGE='258',
 XY='(-7625,4025)',
 ROT='0',
 VER='1',
 PACK_TYPE='0402',
 LOCATION='C1084',
 CDS_LIB='pure_quanta',
 CDS_PART_NAME='Q_CAP_0402-100PF,50V,5%,EMPTY,CH11006JB18',
 VOLTAGE='50V',
 ROOM='ADC_MAM_BOM2',
 PART_NUMBER='CH11006JB18',
 VALUE='100PF',
 PRIM_FILE='./archive_libs/logical/q_cap/chips/chips.prt';

PART_NAME
 C1085 'Q_CAP_0402-100PF,50V,5%,EMPTY,CH11006JB18':
 ROOM='ADC_MAM_BOM2';

SECTION_NUMBER 1
 '@T6G_MB_LIB.T6G(SCH_1):PAGE263_I45@PURE_QUANTA.Q_CAP(CHIPS)':
 C_PATH='@t6g_mb_lib.t6g(sch_1):page263_i45@pure_quanta.q_cap(chips)',
 P_PATH='@t6g_mb_lib.t6g(sch_1):page258_i45@pure_quanta.q_cap(chips)',
 PATH='I45',
 DRAWING='@T6G_MB_LIB.T6G(SCH_1):PAGE263',
 TOLERANCE='5%',
 MATERIAL='EMPTY',
 PHYS_PAGE='258',
 XY='(-7700,5350)',
 ROT='0',
 VER='1',
 PACK_TYPE='0402',
 LOCATION='C1085',
 CDS_LIB='pure_quanta',
 CDS_PART_NAME='Q_CAP_0402-100PF,50V,5%,EMPTY,CH11006JB18',
 VOLTAGE='50V',
 ROOM='ADC_MAM_BOM2',
 PART_NUMBER='CH11006JB18',
 VALUE='100PF',
 PRIM_FILE='./archive_libs/logical/q_cap/chips/chips.prt';

PART_NAME
 C1086 'Q_CAP_0402-0.1UF,25V,10%,X7R,CH4104K1B00':
 ROOM='ADC_TI_BOM1';

SECTION_NUMBER 1
 '@T6G_MB_LIB.T6G(SCH_1):PAGE263_I175@PURE_QUANTA.Q_CAP(CHIPS)':
 C_PATH='@t6g_mb_lib.t6g(sch_1):page263_i175@pure_quanta.q_cap(chips)',
 P_PATH='@t6g_mb_lib.t6g(sch_1):page258_i175@pure_quanta.q_cap(chips)',
 PATH='I175',
 DRAWING='@T6G_MB_LIB.T6G(SCH_1):PAGE263',
 TOLERANCE='10%',
 MATERIAL='X7R',
 PHYS_PAGE='258',
 XY='(-7875,2575)',
 ROT='2',
 VER='1',
 PACK_TYPE='0402',
 LOCATION='C1086',
 CDS_LIB='pure_quanta',
 CDS_PART_NAME='Q_CAP_0402-0.1UF,25V,10%,X7R,CH4104K1B00',
 VOLTAGE='25V',
 ROOM='ADC_TI_BOM1',
 PART_NUMBER='CH4104K1B00',
 VALUE='0.1UF',
 PRIM_FILE='./archive_libs/logical/q_cap/chips/chips.prt';

PART_NAME
 C1087 'Q_CAP_0402-0.1UF,25V,10%,X7R,CH4104K1B00':
 ROOM='ADC_TI_BOM1';

SECTION_NUMBER 1
 '@T6G_MB_LIB.T6G(SCH_1):PAGE263_I187@PURE_QUANTA.Q_CAP(CHIPS)':
 C_PATH='@t6g_mb_lib.t6g(sch_1):page263_i187@pure_quanta.q_cap(chips)',
 P_PATH='@t6g_mb_lib.t6g(sch_1):page258_i187@pure_quanta.q_cap(chips)',
 PATH='I187',
 DRAWING='@T6G_MB_LIB.T6G(SCH_1):PAGE263',
 TOLERANCE='10%',
 MATERIAL='X7R',
 PHYS_PAGE='258',
 XY='(-7825,975)',
 ROT='2',
 VER='1',
 PACK_TYPE='0402',
 LOCATION='C1087',
 CDS_LIB='pure_quanta',
 CDS_PART_NAME='Q_CAP_0402-0.1UF,25V,10%,X7R,CH4104K1B00',
 VOLTAGE='25V',
 ROOM='ADC_TI_BOM1',
 PART_NUMBER='CH4104K1B00',
 VALUE='0.1UF',
 PRIM_FILE='./archive_libs/logical/q_cap/chips/chips.prt';

PART_NAME
 C1088 'Q_CAP_0402-0.1UF,25V,10%,X7R,CH4104K1B00':
 ROOM='ADC_TI_BOM1';

SECTION_NUMBER 1
 '@T6G_MB_LIB.T6G(SCH_1):PAGE263_I223@PURE_QUANTA.Q_CAP(CHIPS)':
 C_PATH='@t6g_mb_lib.t6g(sch_1):page263_i223@pure_quanta.q_cap(chips)',
 P_PATH='@t6g_mb_lib.t6g(sch_1):page258_i223@pure_quanta.q_cap(chips)',
 PATH='I223',
 DRAWING='@T6G_MB_LIB.T6G(SCH_1):PAGE263',
 TOLERANCE='10%',
 MATERIAL='X7R',
 PHYS_PAGE='258',
 XY='(-5775,2400)',
 ROT='2',
 VER='1',
 PACK_TYPE='0402',
 LOCATION='C1088',
 CDS_LIB='pure_quanta',
 CDS_PART_NAME='Q_CAP_0402-0.1UF,25V,10%,X7R,CH4104K1B00',
 VOLTAGE='25V',
 ROOM='ADC_TI_BOM1',
 PART_NUMBER='CH4104K1B00',
 VALUE='0.1UF',
 PRIM_FILE='./archive_libs/logical/q_cap/chips/chips.prt';

PART_NAME
 C1089 'Q_CAP_0402-0.1UF,25V,10%,X7R,CH4104K1B00':
 ROOM='ADC_TI_BOM1';

SECTION_NUMBER 1
 '@T6G_MB_LIB.T6G(SCH_1):PAGE263_I211@PURE_QUANTA.Q_CAP(CHIPS)':
 C_PATH='@t6g_mb_lib.t6g(sch_1):page263_i211@pure_quanta.q_cap(chips)',
 P_PATH='@t6g_mb_lib.t6g(sch_1):page258_i211@pure_quanta.q_cap(chips)',
 PATH='I211',
 DRAWING='@T6G_MB_LIB.T6G(SCH_1):PAGE263',
 TOLERANCE='10%',
 MATERIAL='X7R',
 PHYS_PAGE='258',
 XY='(-5675,3825)',
 ROT='2',
 VER='1',
 PACK_TYPE='0402',
 LOCATION='C1089',
 CDS_LIB='pure_quanta',
 CDS_PART_NAME='Q_CAP_0402-0.1UF,25V,10%,X7R,CH4104K1B00',
 VOLTAGE='25V',
 ROOM='ADC_TI_BOM1',
 PART_NUMBER='CH4104K1B00',
 VALUE='0.1UF',
 PRIM_FILE='./archive_libs/logical/q_cap/chips/chips.prt';

PART_NAME
 C1090 'Q_CAP_0402-0.1UF,25V,10%,X7R,CH4104K1B00':
 ROOM='ADC_TI_BOM1';

SECTION_NUMBER 1
 '@T6G_MB_LIB.T6G(SCH_1):PAGE263_I237@PURE_QUANTA.Q_CAP(CHIPS)':
 C_PATH='@t6g_mb_lib.t6g(sch_1):page263_i237@pure_quanta.q_cap(chips)',
 P_PATH='@t6g_mb_lib.t6g(sch_1):page258_i237@pure_quanta.q_cap(chips)',
 PATH='I237',
 DRAWING='@T6G_MB_LIB.T6G(SCH_1):PAGE263',
 TOLERANCE='10%',
 MATERIAL='X7R',
 PHYS_PAGE='258',
 XY='(-5600,875)',
 ROT='2',
 VER='1',
 PACK_TYPE='0402',
 LOCATION='C1090',
 CDS_LIB='pure_quanta',
 CDS_PART_NAME='Q_CAP_0402-0.1UF,25V,10%,X7R,CH4104K1B00',
 VOLTAGE='25V',
 ROOM='ADC_TI_BOM1',
 PART_NUMBER='CH4104K1B00',
 VALUE='0.1UF',
 PRIM_FILE='./archive_libs/logical/q_cap/chips/chips.prt';

PART_NAME
 C1091 'Q_CAP_0402-0.1UF,25V,10%,X7R,CH4104K1B00':
 ROOM='ADC_TI_BOM1';

SECTION_NUMBER 1
 '@T6G_MB_LIB.T6G(SCH_1):PAGE263_I200@PURE_QUANTA.Q_CAP(CHIPS)':
 C_PATH='@t6g_mb_lib.t6g(sch_1):page263_i200@pure_quanta.q_cap(chips)',
 P_PATH='@t6g_mb_lib.t6g(sch_1):page258_i200@pure_quanta.q_cap(chips)',
 PATH='I200',
 DRAWING='@T6G_MB_LIB.T6G(SCH_1):PAGE263',
 TOLERANCE='10%',
 MATERIAL='X7R',
 PHYS_PAGE='258',
 XY='(-5550,5350)',
 ROT='2',
 VER='1',
 PACK_TYPE='0402',
 LOCATION='C1091',
 CDS_LIB='pure_quanta',
 CDS_PART_NAME='Q_CAP_0402-0.1UF,25V,10%,X7R,CH4104K1B00',
 VOLTAGE='25V',
 ROOM='ADC_TI_BOM1',
 PART_NUMBER='CH4104K1B00',
 VALUE='0.1UF',
 PRIM_FILE='./archive_libs/logical/q_cap/chips/chips.prt';

PART_NAME
 C1092 'Q_CAP_0402-0.1UF,25V,10%,X7R,CH4104K1B00':
 ROOM='ADC_TI_BOM1';

SECTION_NUMBER 1
 '@T6G_MB_LIB.T6G(SCH_1):PAGE263_I76@PURE_QUANTA.Q_CAP(CHIPS)':
 C_PATH='@t6g_mb_lib.t6g(sch_1):page263_i76@pure_quanta.q_cap(chips)',
 P_PATH='@t6g_mb_lib.t6g(sch_1):page258_i76@pure_quanta.q_cap(chips)',
 PATH='I76',
 DRAWING='@T6G_MB_LIB.T6G(SCH_1):PAGE263',
 TOLERANCE='10%',
 MATERIAL='X7R',
 PHYS_PAGE='258',
 XY='(-7975,4025)',
 ROT='2',
 VER='1',
 PACK_TYPE='0402',
 LOCATION='C1092',
 CDS_LIB='pure_quanta',
 CDS_PART_NAME='Q_CAP_0402-0.1UF,25V,10%,X7R,CH4104K1B00',
 VOLTAGE='25V',
 ROOM='ADC_TI_BOM1',
 PART_NUMBER='CH4104K1B00',
 VALUE='0.1UF',
 PRIM_FILE='./archive_libs/logical/q_cap/chips/chips.prt';

PART_NAME
 C1093 'Q_CAP_0402-0.1UF,25V,10%,X7R,CH4104K1B00':
 ROOM='ADC_TI_BOM1';

SECTION_NUMBER 1
 '@T6G_MB_LIB.T6G(SCH_1):PAGE263_I43@PURE_QUANTA.Q_CAP(CHIPS)':
 C_PATH='@t6g_mb_lib.t6g(sch_1):page263_i43@pure_quanta.q_cap(chips)',
 P_PATH='@t6g_mb_lib.t6g(sch_1):page258_i43@pure_quanta.q_cap(chips)',
 PATH='I43',
 DRAWING='@T6G_MB_LIB.T6G(SCH_1):PAGE263',
 TOLERANCE='10%',
 MATERIAL='X7R',
 PHYS_PAGE='258',
 XY='(-8050,5350)',
 ROT='2',
 VER='1',
 PACK_TYPE='0402',
 LOCATION='C1093',
 CDS_LIB='pure_quanta',
 CDS_PART_NAME='Q_CAP_0402-0.1UF,25V,10%,X7R,CH4104K1B00',
 VOLTAGE='25V',
 ROOM='ADC_TI_BOM1',
 PART_NUMBER='CH4104K1B00',
 VALUE='0.1UF',
 PRIM_FILE='./archive_libs/logical/q_cap/chips/chips.prt';

PART_NAME
 C1094 'Q_CAP_0402-0.1UF,25V,10%,X7R,CH4104K1B00':
 ROOM='ADC_TI_BOM1';

SECTION_NUMBER 1
 '@T6G_MB_LIB.T6G(SCH_1):PAGE263_I68@PURE_QUANTA.Q_CAP(CHIPS)':
 C_PATH='@t6g_mb_lib.t6g(sch_1):page263_i68@pure_quanta.q_cap(chips)',
 P_PATH='@t6g_mb_lib.t6g(sch_1):page258_i68@pure_quanta.q_cap(chips)',
 PATH='I68',
 DRAWING='@T6G_MB_LIB.T6G(SCH_1):PAGE263',
 TOLERANCE='10%',
 MATERIAL='X7R',
 PHYS_PAGE='258',
 XY='(-4125,2350)',
 ROT='2',
 VER='1',
 PACK_TYPE='0402',
 LOCATION='C1094',
 CDS_LIB='pure_quanta',
 CDS_PART_NAME='Q_CAP_0402-0.1UF,25V,10%,X7R,CH4104K1B00',
 VOLTAGE='25V',
 ROOM='ADC_TI_BOM1',
 PART_NUMBER='CH4104K1B00',
 VALUE='0.1UF',
 PRIM_FILE='./archive_libs/logical/q_cap/chips/chips.prt';

PART_NAME
 C1095 'Q_CAP_0402-0.1UF,25V,10%,X7R,CH4104K1B00':
 ROOM='ADC_TI_BOM1';

SECTION_NUMBER 1
 '@T6G_MB_LIB.T6G(SCH_1):PAGE263_I130@PURE_QUANTA.Q_CAP(CHIPS)':
 C_PATH='@t6g_mb_lib.t6g(sch_1):page263_i130@pure_quanta.q_cap(chips)',
 P_PATH='@t6g_mb_lib.t6g(sch_1):page258_i130@pure_quanta.q_cap(chips)',
 PATH='I130',
 DRAWING='@T6G_MB_LIB.T6G(SCH_1):PAGE263',
 TOLERANCE='10%',
 MATERIAL='X7R',
 PHYS_PAGE='258',
 XY='(-3800,2350)',
 ROT='0',
 VER='1',
 PACK_TYPE='0402',
 LOCATION='C1095',
 CDS_LIB='pure_quanta',
 CDS_PART_NAME='Q_CAP_0402-0.1UF,25V,10%,X7R,CH4104K1B00',
 VOLTAGE='25V',
 ROOM='ADC_TI_BOM1',
 PART_NUMBER='CH4104K1B00',
 VALUE='0.1UF',
 PRIM_FILE='./archive_libs/logical/q_cap/chips/chips.prt';

PART_NAME
 C1096 'Q_CAP_0402-0.1UF,25V,10%,X7R,CH4104K1B00':;

SECTION_NUMBER 1
 '@T6G_MB_LIB.T6G(SCH_1):PAGE466_I66@PURE_QUANTA.Q_CAP(CHIPS)':
 C_PATH='@t6g_mb_lib.t6g(sch_1):page466_i66@pure_quanta.q_cap(chips)',
 P_PATH='@t6g_mb_lib.t6g(sch_1):page357_i66@pure_quanta.q_cap(chips)',
 PATH='I66',
 DRAWING='@T6G_MB_LIB.T6G(SCH_1):PAGE466',
 TOLERANCE='10%',
 MATERIAL='X7R',
 PHYS_PAGE='357',
 XY='(-5500,1750)',
 ROT='0',
 VER='1',
 PACK_TYPE='0402',
 LOCATION='C1096',
 CDS_LIB='pure_quanta',
 CDS_PART_NAME='Q_CAP_0402-0.1UF,25V,10%,X7R,CH4104K1B00',
 VOLTAGE='25V',
 PART_NUMBER='CH4104K1B00',
 VALUE='0.1UF',
 PRIM_FILE='./archive_libs/logical/q_cap/chips/chips.prt';

PART_NAME
 C1097 'Q_CAP_0402-0.1UF,25V,10%,X7R,CH4104K1B00':;

SECTION_NUMBER 1
 '@T6G_MB_LIB.T6G(SCH_1):PAGE466_I19@PURE_QUANTA.Q_CAP(CHIPS)':
 C_PATH='@t6g_mb_lib.t6g(sch_1):page466_i19@pure_quanta.q_cap(chips)',
 P_PATH='@t6g_mb_lib.t6g(sch_1):page357_i19@pure_quanta.q_cap(chips)',
 PATH='I19',
 DRAWING='@T6G_MB_LIB.T6G(SCH_1):PAGE466',
 TOLERANCE='10%',
 MATERIAL='X7R',
 PHYS_PAGE='357',
 XY='(-4950,6075)',
 ROT='0',
 VER='1',
 PACK_TYPE='0402',
 LOCATION='C1097',
 CDS_LIB='pure_quanta',
 CDS_PART_NAME='Q_CAP_0402-0.1UF,25V,10%,X7R,CH4104K1B00',
 VOLTAGE='25V',
 PART_NUMBER='CH4104K1B00',
 VALUE='0.1UF',
 PRIM_FILE='./archive_libs/logical/q_cap/chips/chips.prt';

PART_NAME
 C1098 'Q_CAP_DIFFBUS_C0201-DIFF BUS_0.22UF,6.3V,20%,X6S,SA':;

SECTION_NUMBER 1
 '@T6G_MB_LIB.T6G(SCH_1):PAGE355_I134@PURE_QUANTA.Q_CAP_DIFFBUS(CHIPS)':
 C_PATH='@t6g_mb_lib.t6g(sch_1):page355_i134@pure_quanta.q_cap_diffbus(chips)',
 P_PATH='@t6g_mb_lib.t6g(sch_1):page67_i134@pure_quanta.q_cap_diffbus(chips)',
 PATH='I134',
 DRAWING='@T6G_MB_LIB.T6G(SCH_1):PAGE355',
 PIN_NAMES_ROTATE='TRUE',
 TOLERANCE='20%',
 MATERIAL='X6S',
 PHYS_PAGE='67',
 XY='(3150,-575)',
 ROT='2',
 VER='2',
 PACK_TYPE='C0201',
 LOCATION='C1098',
 CDS_LIB='pure_quanta',
 CDS_PART_NAME='Q_CAP_DIFFBUS_C0201-DIFF BUS_0.22UF,6.3V,20%,X6S,SA',
 VOLTAGE='6.3V',
 PART_NUMBER='SP_CH4221MEE01',
 VALUE='DIFF BUS_0.22UF',
 PRIM_FILE='./archive_libs/logical/q_cap_diffbus/chips/chips.prt';

PART_NAME
 C1099 'Q_CAP_DIFFBUS_C0201-DIFF BUS_0.22UF,6.3V,20%,X6S,SA':;

SECTION_NUMBER 1
 '@T6G_MB_LIB.T6G(SCH_1):PAGE355_I133@PURE_QUANTA.Q_CAP_DIFFBUS(CHIPS)':
 C_PATH='@t6g_mb_lib.t6g(sch_1):page355_i133@pure_quanta.q_cap_diffbus(chips)',
 P_PATH='@t6g_mb_lib.t6g(sch_1):page67_i133@pure_quanta.q_cap_diffbus(chips)',
 PATH='I133',
 DRAWING='@T6G_MB_LIB.T6G(SCH_1):PAGE355',
 PIN_NAMES_ROTATE='TRUE',
 TOLERANCE='20%',
 MATERIAL='X6S',
 PHYS_PAGE='67',
 XY='(3150,-625)',
 ROT='2',
 VER='2',
 PACK_TYPE='C0201',
 LOCATION='C1099',
 CDS_LIB='pure_quanta',
 CDS_PART_NAME='Q_CAP_DIFFBUS_C0201-DIFF BUS_0.22UF,6.3V,20%,X6S,SA',
 VOLTAGE='6.3V',
 PART_NUMBER='SP_CH4221MEE01',
 VALUE='DIFF BUS_0.22UF',
 PRIM_FILE='./archive_libs/logical/q_cap_diffbus/chips/chips.prt';

PART_NAME
 C1100 'Q_CAP_DIFFBUS_C0201-DIFF BUS_0.22UF,6.3V,20%,X6S,SA':;

SECTION_NUMBER 1
 '@T6G_MB_LIB.T6G(SCH_1):PAGE355_I136@PURE_QUANTA.Q_CAP_DIFFBUS(CHIPS)':
 C_PATH='@t6g_mb_lib.t6g(sch_1):page355_i136@pure_quanta.q_cap_diffbus(chips)',
 P_PATH='@t6g_mb_lib.t6g(sch_1):page67_i136@pure_quanta.q_cap_diffbus(chips)',
 PATH='I136',
 DRAWING='@T6G_MB_LIB.T6G(SCH_1):PAGE355',
 PIN_NAMES_ROTATE='TRUE',
 TOLERANCE='20%',
 MATERIAL='X6S',
 PHYS_PAGE='67',
 XY='(3150,-375)',
 ROT='2',
 VER='2',
 PACK_TYPE='C0201',
 LOCATION='C1100',
 CDS_LIB='pure_quanta',
 CDS_PART_NAME='Q_CAP_DIFFBUS_C0201-DIFF BUS_0.22UF,6.3V,20%,X6S,SA',
 VOLTAGE='6.3V',
 PART_NUMBER='SP_CH4221MEE01',
 VALUE='DIFF BUS_0.22UF',
 PRIM_FILE='./archive_libs/logical/q_cap_diffbus/chips/chips.prt';

PART_NAME
 C1101 'Q_CAP_DIFFBUS_C0201-DIFF BUS_0.22UF,6.3V,20%,X6S,SA':;

SECTION_NUMBER 1
 '@T6G_MB_LIB.T6G(SCH_1):PAGE355_I135@PURE_QUANTA.Q_CAP_DIFFBUS(CHIPS)':
 C_PATH='@t6g_mb_lib.t6g(sch_1):page355_i135@pure_quanta.q_cap_diffbus(chips)',
 P_PATH='@t6g_mb_lib.t6g(sch_1):page67_i135@pure_quanta.q_cap_diffbus(chips)',
 PATH='I135',
 DRAWING='@T6G_MB_LIB.T6G(SCH_1):PAGE355',
 PIN_NAMES_ROTATE='TRUE',
 TOLERANCE='20%',
 MATERIAL='X6S',
 PHYS_PAGE='67',
 XY='(3150,-425)',
 ROT='2',
 VER='2',
 PACK_TYPE='C0201',
 LOCATION='C1101',
 CDS_LIB='pure_quanta',
 CDS_PART_NAME='Q_CAP_DIFFBUS_C0201-DIFF BUS_0.22UF,6.3V,20%,X6S,SA',
 VOLTAGE='6.3V',
 PART_NUMBER='SP_CH4221MEE01',
 VALUE='DIFF BUS_0.22UF',
 PRIM_FILE='./archive_libs/logical/q_cap_diffbus/chips/chips.prt';

PART_NAME
 C1102 'Q_CAP_0402-0.1UF,25V,10%,X7R,CH4104K1B00':;

SECTION_NUMBER 1
 '@T6G_MB_LIB.T6G(SCH_1):PAGE76_I53@PURE_QUANTA.Q_CAP(CHIPS)':
 C_PATH='@t6g_mb_lib.t6g(sch_1):page76_i53@pure_quanta.q_cap(chips)',
 P_PATH='@t6g_mb_lib.t6g(sch_1):page77_i53@pure_quanta.q_cap(chips)',
 PATH='I53',
 DRAWING='@T6G_MB_LIB.T6G(SCH_1):PAGE76',
 TOLERANCE='10%',
 MATERIAL='X7R',
 PHYS_PAGE='77',
 XY='(-6100,4750)',
 ROT='2',
 VER='1',
 PACK_TYPE='0402',
 LOCATION='C1102',
 CDS_LIB='pure_quanta',
 CDS_PART_NAME='Q_CAP_0402-0.1UF,25V,10%,X7R,CH4104K1B00',
 VOLTAGE='25V',
 PART_NUMBER='CH4104K1B00',
 VALUE='0.1UF',
 PRIM_FILE='./archive_libs/logical/q_cap/chips/chips.prt';

PART_NAME
 C1103 'Q_CAP_0402-0.1UF,25V,10%,X7R,CH4104K1B00':;

SECTION_NUMBER 1
 '@T6G_MB_LIB.T6G(SCH_1):PAGE76_I65@PURE_QUANTA.Q_CAP(CHIPS)':
 C_PATH='@t6g_mb_lib.t6g(sch_1):page76_i65@pure_quanta.q_cap(chips)',
 P_PATH='@t6g_mb_lib.t6g(sch_1):page77_i65@pure_quanta.q_cap(chips)',
 PATH='I65',
 DRAWING='@T6G_MB_LIB.T6G(SCH_1):PAGE76',
 TOLERANCE='10%',
 MATERIAL='X7R',
 PHYS_PAGE='77',
 XY='(-6200,2675)',
 ROT='2',
 VER='1',
 PACK_TYPE='0402',
 LOCATION='C1103',
 CDS_LIB='pure_quanta',
 CDS_PART_NAME='Q_CAP_0402-0.1UF,25V,10%,X7R,CH4104K1B00',
 VOLTAGE='25V',
 PART_NUMBER='CH4104K1B00',
 VALUE='0.1UF',
 PRIM_FILE='./archive_libs/logical/q_cap/chips/chips.prt';

PART_NAME
 C1104 'Q_CAP_0402-0.1UF,25V,10%,X7R,CH4104K1B00':;

SECTION_NUMBER 1
 '@T6G_MB_LIB.T6G(SCH_1):PAGE76_I50@PURE_QUANTA.Q_CAP(CHIPS)':
 C_PATH='@t6g_mb_lib.t6g(sch_1):page76_i50@pure_quanta.q_cap(chips)',
 P_PATH='@t6g_mb_lib.t6g(sch_1):page77_i50@pure_quanta.q_cap(chips)',
 PATH='I50',
 DRAWING='@T6G_MB_LIB.T6G(SCH_1):PAGE76',
 TOLERANCE='10%',
 MATERIAL='X7R',
 PHYS_PAGE='77',
 XY='(-4750,4750)',
 ROT='0',
 VER='1',
 PACK_TYPE='0402',
 LOCATION='C1104',
 CDS_LIB='pure_quanta',
 CDS_PART_NAME='Q_CAP_0402-0.1UF,25V,10%,X7R,CH4104K1B00',
 VOLTAGE='25V',
 PART_NUMBER='CH4104K1B00',
 VALUE='0.1UF',
 PRIM_FILE='./archive_libs/logical/q_cap/chips/chips.prt';

PART_NAME
 C1105 'Q_CAP_0402-0.1UF,25V,10%,X7R,CH4104K1B00':;

SECTION_NUMBER 1
 '@T6G_MB_LIB.T6G(SCH_1):PAGE76_I59@PURE_QUANTA.Q_CAP(CHIPS)':
 C_PATH='@t6g_mb_lib.t6g(sch_1):page76_i59@pure_quanta.q_cap(chips)',
 P_PATH='@t6g_mb_lib.t6g(sch_1):page77_i59@pure_quanta.q_cap(chips)',
 PATH='I59',
 DRAWING='@T6G_MB_LIB.T6G(SCH_1):PAGE76',
 TOLERANCE='10%',
 MATERIAL='X7R',
 PHYS_PAGE='77',
 XY='(-4725,2650)',
 ROT='0',
 VER='1',
 PACK_TYPE='0402',
 LOCATION='C1105',
 CDS_LIB='pure_quanta',
 CDS_PART_NAME='Q_CAP_0402-0.1UF,25V,10%,X7R,CH4104K1B00',
 VOLTAGE='25V',
 PART_NUMBER='CH4104K1B00',
 VALUE='0.1UF',
 PRIM_FILE='./archive_libs/logical/q_cap/chips/chips.prt';

PART_NAME
 C1106 'Q_CAP_0402-0.1UF,25V,10%,X7R,CH4104K1B00':;

SECTION_NUMBER 1
 '@T6G_MB_LIB.T6G(SCH_1):PAGE466_I36@PURE_QUANTA.Q_CAP(CHIPS)':
 C_PATH='@t6g_mb_lib.t6g(sch_1):page466_i36@pure_quanta.q_cap(chips)',
 P_PATH='@t6g_mb_lib.t6g(sch_1):page357_i36@pure_quanta.q_cap(chips)',
 PATH='I36',
 DRAWING='@T6G_MB_LIB.T6G(SCH_1):PAGE466',
 TOLERANCE='10%',
 MATERIAL='X7R',
 PHYS_PAGE='357',
 XY='(-4300,4025)',
 ROT='0',
 VER='1',
 PACK_TYPE='0402',
 LOCATION='C1106',
 CDS_LIB='pure_quanta',
 CDS_PART_NAME='Q_CAP_0402-0.1UF,25V,10%,X7R,CH4104K1B00',
 VOLTAGE='25V',
 PART_NUMBER='CH4104K1B00',
 VALUE='0.1UF',
 PRIM_FILE='./archive_libs/logical/q_cap/chips/chips.prt';

PART_NAME
 C1107 'Q_CAP_0402-0.1UF,25V,10%,X7R,CH4104K1B00':;

SECTION_NUMBER 1
 '@T6G_MB_LIB.T6G(SCH_1):PAGE466_I81@PURE_QUANTA.Q_CAP(CHIPS)':
 C_PATH='@t6g_mb_lib.t6g(sch_1):page466_i81@pure_quanta.q_cap(chips)',
 P_PATH='@t6g_mb_lib.t6g(sch_1):page357_i81@pure_quanta.q_cap(chips)',
 PATH='I81',
 DRAWING='@T6G_MB_LIB.T6G(SCH_1):PAGE466',
 TOLERANCE='10%',
 MATERIAL='X7R',
 PHYS_PAGE='357',
 XY='(-8175,1325)',
 ROT='0',
 VER='1',
 PACK_TYPE='0402',
 LOCATION='C1107',
 CDS_LIB='pure_quanta',
 CDS_PART_NAME='Q_CAP_0402-0.1UF,25V,10%,X7R,CH4104K1B00',
 VOLTAGE='25V',
 PART_NUMBER='CH4104K1B00',
 VALUE='0.1UF',
 PRIM_FILE='./archive_libs/logical/q_cap/chips/chips.prt';

PART_NAME
 C1108 'Q_CAP_0402-0.1UF,25V,10%,X7R,CH4104K1B00':;

SECTION_NUMBER 1
 '@T6G_MB_LIB.T6G(SCH_1):PAGE466_I5@PURE_QUANTA.Q_CAP(CHIPS)':
 C_PATH='@t6g_mb_lib.t6g(sch_1):page466_i5@pure_quanta.q_cap(chips)',
 P_PATH='@t6g_mb_lib.t6g(sch_1):page357_i5@pure_quanta.q_cap(chips)',
 PATH='I5',
 DRAWING='@T6G_MB_LIB.T6G(SCH_1):PAGE466',
 TOLERANCE='10%',
 MATERIAL='X7R',
 PHYS_PAGE='357',
 XY='(-7625,5650)',
 ROT='0',
 VER='1',
 PACK_TYPE='0402',
 LOCATION='C1108',
 CDS_LIB='pure_quanta',
 CDS_PART_NAME='Q_CAP_0402-0.1UF,25V,10%,X7R,CH4104K1B00',
 VOLTAGE='25V',
 PART_NUMBER='CH4104K1B00',
 VALUE='0.1UF',
 PRIM_FILE='./archive_libs/logical/q_cap/chips/chips.prt';

PART_NAME
 C1109 'Q_CAP_0402-0.1UF,25V,10%,X7R,CH4104K1B00':;

SECTION_NUMBER 1
 '@T6G_MB_LIB.T6G(SCH_1):PAGE466_I51@PURE_QUANTA.Q_CAP(CHIPS)':
 C_PATH='@t6g_mb_lib.t6g(sch_1):page466_i51@pure_quanta.q_cap(chips)',
 P_PATH='@t6g_mb_lib.t6g(sch_1):page357_i51@pure_quanta.q_cap(chips)',
 PATH='I51',
 DRAWING='@T6G_MB_LIB.T6G(SCH_1):PAGE466',
 TOLERANCE='10%',
 MATERIAL='X7R',
 PHYS_PAGE='357',
 XY='(-6975,3600)',
 ROT='0',
 VER='1',
 PACK_TYPE='0402',
 LOCATION='C1109',
 CDS_LIB='pure_quanta',
 CDS_PART_NAME='Q_CAP_0402-0.1UF,25V,10%,X7R,CH4104K1B00',
 VOLTAGE='25V',
 PART_NUMBER='CH4104K1B00',
 VALUE='0.1UF',
 PRIM_FILE='./archive_libs/logical/q_cap/chips/chips.prt';

PART_NAME
 C1110 'Q_CAP_0402-0.1UF,25V,10%,X7R,CH4104K1B00':;

SECTION_NUMBER 1
 '@T6G_MB_LIB.T6G(SCH_1):PAGE466_I68@PURE_QUANTA.Q_CAP(CHIPS)':
 C_PATH='@t6g_mb_lib.t6g(sch_1):page466_i68@pure_quanta.q_cap(chips)',
 P_PATH='@t6g_mb_lib.t6g(sch_1):page357_i68@pure_quanta.q_cap(chips)',
 PATH='I68',
 DRAWING='@T6G_MB_LIB.T6G(SCH_1):PAGE466',
 TOLERANCE='10%',
 MATERIAL='X7R',
 PHYS_PAGE='357',
 XY='(-6025,400)',
 ROT='0',
 VER='1',
 PACK_TYPE='0402',
 LOCATION='C1110',
 CDS_LIB='pure_quanta',
 CDS_PART_NAME='Q_CAP_0402-0.1UF,25V,10%,X7R,CH4104K1B00',
 VOLTAGE='25V',
 PART_NUMBER='CH4104K1B00',
 VALUE='0.1UF',
 PRIM_FILE='./archive_libs/logical/q_cap/chips/chips.prt';

PART_NAME
 C1111 'Q_CAP_0402-0.1UF,25V,10%,X7R,CH4104K1B00':;

SECTION_NUMBER 1
 '@T6G_MB_LIB.T6G(SCH_1):PAGE466_I15@PURE_QUANTA.Q_CAP(CHIPS)':
 C_PATH='@t6g_mb_lib.t6g(sch_1):page466_i15@pure_quanta.q_cap(chips)',
 P_PATH='@t6g_mb_lib.t6g(sch_1):page357_i15@pure_quanta.q_cap(chips)',
 PATH='I15',
 DRAWING='@T6G_MB_LIB.T6G(SCH_1):PAGE466',
 TOLERANCE='10%',
 MATERIAL='X7R',
 PHYS_PAGE='357',
 XY='(-5475,4725)',
 ROT='0',
 VER='1',
 PACK_TYPE='0402',
 LOCATION='C1111',
 CDS_LIB='pure_quanta',
 CDS_PART_NAME='Q_CAP_0402-0.1UF,25V,10%,X7R,CH4104K1B00',
 VOLTAGE='25V',
 PART_NUMBER='CH4104K1B00',
 VALUE='0.1UF',
 PRIM_FILE='./archive_libs/logical/q_cap/chips/chips.prt';

PART_NAME
 C1112 'Q_CAP_0402-0.1UF,25V,10%,X7R,CH4104K1B00':;

SECTION_NUMBER 1
 '@T6G_MB_LIB.T6G(SCH_1):PAGE466_I54@PURE_QUANTA.Q_CAP(CHIPS)':
 C_PATH='@t6g_mb_lib.t6g(sch_1):page466_i54@pure_quanta.q_cap(chips)',
 P_PATH='@t6g_mb_lib.t6g(sch_1):page357_i54@pure_quanta.q_cap(chips)',
 PATH='I54',
 DRAWING='@T6G_MB_LIB.T6G(SCH_1):PAGE466',
 TOLERANCE='10%',
 MATERIAL='X7R',
 PHYS_PAGE='357',
 XY='(-4825,2675)',
 ROT='0',
 VER='1',
 PACK_TYPE='0402',
 LOCATION='C1112',
 CDS_LIB='pure_quanta',
 CDS_PART_NAME='Q_CAP_0402-0.1UF,25V,10%,X7R,CH4104K1B00',
 VOLTAGE='25V',
 PART_NUMBER='CH4104K1B00',
 VALUE='0.1UF',
 PRIM_FILE='./archive_libs/logical/q_cap/chips/chips.prt';

PART_NAME
 C1113 'Q_CAP_C0805-22UF,16V,20%,EMPTY,CH6223MEA00':;

SECTION_NUMBER 1
 '@T6G_MB_LIB.T6G(SCH_1):PAGE146_I6@PURE_QUANTA.Q_CAP(CHIPS)':
 C_PATH='@t6g_mb_lib.t6g(sch_1):page146_i6@pure_quanta.q_cap(chips)',
 P_PATH='@t6g_mb_lib.t6g(sch_1):page169_i6@pure_quanta.q_cap(chips)',
 PATH='I6',
 DRAWING='@T6G_MB_LIB.T6G(SCH_1):PAGE146',
 TOLERANCE='20%',
 MATERIAL='EMPTY',
 PHYS_PAGE='169',
 XY='(-6875,3825)',
 ROT='0',
 VER='1',
 PACK_TYPE='C0805',
 LOCATION='C1113',
 CDS_LIB='pure_quanta',
 CDS_PART_NAME='Q_CAP_C0805-22UF,16V,20%,EMPTY,CH6223MEA00',
 VOLTAGE='16V',
 PART_NUMBER='CH6223MEA00',
 VALUE='22UF',
 PRIM_FILE='./archive_libs/logical/q_cap/chips/chips.prt';

PART_NAME
 C1114 'Q_CAP_C0805-22UF,16V,20%,EMPTY,CH6223MEA00':;

SECTION_NUMBER 1
 '@T6G_MB_LIB.T6G(SCH_1):PAGE146_I30@PURE_QUANTA.Q_CAP(CHIPS)':
 C_PATH='@t6g_mb_lib.t6g(sch_1):page146_i30@pure_quanta.q_cap(chips)',
 P_PATH='@t6g_mb_lib.t6g(sch_1):page169_i30@pure_quanta.q_cap(chips)',
 PATH='I30',
 DRAWING='@T6G_MB_LIB.T6G(SCH_1):PAGE146',
 TOLERANCE='20%',
 MATERIAL='EMPTY',
 PHYS_PAGE='169',
 XY='(-6750,950)',
 ROT='0',
 VER='1',
 PACK_TYPE='C0805',
 LOCATION='C1114',
 CDS_LIB='pure_quanta',
 CDS_PART_NAME='Q_CAP_C0805-22UF,16V,20%,EMPTY,CH6223MEA00',
 VOLTAGE='16V',
 PART_NUMBER='CH6223MEA00',
 VALUE='22UF',
 PRIM_FILE='./archive_libs/logical/q_cap/chips/chips.prt';

PART_NAME
 C1115 'Q_CAP_C0805-22UF,16V,20%,EMPTY,CH6223MEA00':;

SECTION_NUMBER 1
 '@T6G_MB_LIB.T6G(SCH_1):PAGE363_I478@PURE_QUANTA.Q_CAP(CHIPS)':
 C_PATH='@t6g_mb_lib.t6g(sch_1):page363_i478@pure_quanta.q_cap(chips)',
 P_PATH='@t6g_mb_lib.t6g(sch_1):page240_i478@pure_quanta.q_cap(chips)',
 PATH='I478',
 DRAWING='@T6G_MB_LIB.T6G(SCH_1):PAGE363',
 TOLERANCE='20%',
 MATERIAL='EMPTY',
 PHYS_PAGE='240',
 XY='(-1700,375)',
 ROT='2',
 VER='1',
 PACK_TYPE='C0805',
 LOCATION='C1115',
 CDS_LIB='pure_quanta',
 CDS_PART_NAME='Q_CAP_C0805-22UF,16V,20%,EMPTY,CH6223MEA00',
 VOLTAGE='16V',
 PART_NUMBER='CH6223MEA00',
 VALUE='22UF',
 PRIM_FILE='./archive_libs/logical/q_cap/chips/chips.prt';

PART_NAME
 C1126 'Q_CAP_C0402-0.1UF,16V,10%,X7R,CH4103K1B08':;

SECTION_NUMBER 1
 '@T6G_MB_LIB.T6G(SCH_1):PAGE82_I86@PURE_QUANTA.Q_CAP(CHIPS)':
 C_PATH='@t6g_mb_lib.t6g(sch_1):page82_i86@pure_quanta.q_cap(chips)',
 P_PATH='@t6g_mb_lib.t6g(sch_1):page83_i86@pure_quanta.q_cap(chips)',
 PATH='I86',
 DRAWING='@T6G_MB_LIB.T6G(SCH_1):PAGE82',
 TOLERANCE='10%',
 MATERIAL='X7R',
 PHYS_PAGE='83',
 XY='(-3450,1975)',
 ROT='0',
 VER='2',
 PACK_TYPE='C0402',
 LOCATION='C1126',
 CDS_LIB='pure_quanta',
 CDS_PART_NAME='Q_CAP_C0402-0.1UF,16V,10%,X7R,CH4103K1B08',
 VOLTAGE='16V',
 PART_NUMBER='CH4103K1B08',
 VALUE='0.1UF',
 PRIM_FILE='./archive_libs/logical/q_cap/chips/chips.prt';

PART_NAME
 C1127 'Q_CAP_C0402-0.1UF,16V,10%,X7R,CH4103K1B08':;

SECTION_NUMBER 1
 '@T6G_MB_LIB.T6G(SCH_1):PAGE82_I87@PURE_QUANTA.Q_CAP(CHIPS)':
 C_PATH='@t6g_mb_lib.t6g(sch_1):page82_i87@pure_quanta.q_cap(chips)',
 P_PATH='@t6g_mb_lib.t6g(sch_1):page83_i87@pure_quanta.q_cap(chips)',
 PATH='I87',
 DRAWING='@T6G_MB_LIB.T6G(SCH_1):PAGE82',
 TOLERANCE='10%',
 MATERIAL='X7R',
 PHYS_PAGE='83',
 XY='(-3450,1875)',
 ROT='0',
 VER='2',
 PACK_TYPE='C0402',
 LOCATION='C1127',
 CDS_LIB='pure_quanta',
 CDS_PART_NAME='Q_CAP_C0402-0.1UF,16V,10%,X7R,CH4103K1B08',
 VOLTAGE='16V',
 PART_NUMBER='CH4103K1B08',
 VALUE='0.1UF',
 PRIM_FILE='./archive_libs/logical/q_cap/chips/chips.prt';

PART_NAME
 C1128 'Q_CAP_C0402-0.1UF,16V,10%,X7R,CH4103K1B08':;

SECTION_NUMBER 1
 '@T6G_MB_LIB.T6G(SCH_1):PAGE82_I84@PURE_QUANTA.Q_CAP(CHIPS)':
 C_PATH='@t6g_mb_lib.t6g(sch_1):page82_i84@pure_quanta.q_cap(chips)',
 P_PATH='@t6g_mb_lib.t6g(sch_1):page83_i84@pure_quanta.q_cap(chips)',
 PATH='I84',
 DRAWING='@T6G_MB_LIB.T6G(SCH_1):PAGE82',
 TOLERANCE='10%',
 MATERIAL='X7R',
 PHYS_PAGE='83',
 XY='(-3450,1775)',
 ROT='0',
 VER='2',
 PACK_TYPE='C0402',
 LOCATION='C1128',
 CDS_LIB='pure_quanta',
 CDS_PART_NAME='Q_CAP_C0402-0.1UF,16V,10%,X7R,CH4103K1B08',
 VOLTAGE='16V',
 PART_NUMBER='CH4103K1B08',
 VALUE='0.1UF',
 PRIM_FILE='./archive_libs/logical/q_cap/chips/chips.prt';

PART_NAME
 C1129 'Q_CAP_C0402-0.1UF,16V,10%,X7R,CH4103K1B08':;

SECTION_NUMBER 1
 '@T6G_MB_LIB.T6G(SCH_1):PAGE82_I85@PURE_QUANTA.Q_CAP(CHIPS)':
 C_PATH='@t6g_mb_lib.t6g(sch_1):page82_i85@pure_quanta.q_cap(chips)',
 P_PATH='@t6g_mb_lib.t6g(sch_1):page83_i85@pure_quanta.q_cap(chips)',
 PATH='I85',
 DRAWING='@T6G_MB_LIB.T6G(SCH_1):PAGE82',
 TOLERANCE='10%',
 MATERIAL='X7R',
 PHYS_PAGE='83',
 XY='(-3450,1675)',
 ROT='0',
 VER='2',
 PACK_TYPE='C0402',
 LOCATION='C1129',
 CDS_LIB='pure_quanta',
 CDS_PART_NAME='Q_CAP_C0402-0.1UF,16V,10%,X7R,CH4103K1B08',
 VOLTAGE='16V',
 PART_NUMBER='CH4103K1B08',
 VALUE='0.1UF',
 PRIM_FILE='./archive_libs/logical/q_cap/chips/chips.prt';

PART_NAME
 C1131 'Q_CAP_C0402-0.1UF,16V,10%,X7R,CH4103K1B08':;

SECTION_NUMBER 1
 '@T6G_MB_LIB.T6G(SCH_1):PAGE82_I82@PURE_QUANTA.Q_CAP(CHIPS)':
 C_PATH='@t6g_mb_lib.t6g(sch_1):page82_i82@pure_quanta.q_cap(chips)',
 P_PATH='@t6g_mb_lib.t6g(sch_1):page83_i82@pure_quanta.q_cap(chips)',
 PATH='I82',
 DRAWING='@T6G_MB_LIB.T6G(SCH_1):PAGE82',
 TOLERANCE='10%',
 MATERIAL='X7R',
 PHYS_PAGE='83',
 XY='(-3450,1375)',
 ROT='0',
 VER='2',
 PACK_TYPE='C0402',
 LOCATION='C1131',
 CDS_LIB='pure_quanta',
 CDS_PART_NAME='Q_CAP_C0402-0.1UF,16V,10%,X7R,CH4103K1B08',
 VOLTAGE='16V',
 PART_NUMBER='CH4103K1B08',
 VALUE='0.1UF',
 PRIM_FILE='./archive_libs/logical/q_cap/chips/chips.prt';

PART_NAME
 C1132 'Q_CAP_C0402-0.1UF,16V,10%,X7R,CH4103K1B08':;

SECTION_NUMBER 1
 '@T6G_MB_LIB.T6G(SCH_1):PAGE82_I80@PURE_QUANTA.Q_CAP(CHIPS)':
 C_PATH='@t6g_mb_lib.t6g(sch_1):page82_i80@pure_quanta.q_cap(chips)',
 P_PATH='@t6g_mb_lib.t6g(sch_1):page83_i80@pure_quanta.q_cap(chips)',
 PATH='I80',
 DRAWING='@T6G_MB_LIB.T6G(SCH_1):PAGE82',
 TOLERANCE='10%',
 MATERIAL='X7R',
 PHYS_PAGE='83',
 XY='(-3450,1275)',
 ROT='0',
 VER='2',
 PACK_TYPE='C0402',
 LOCATION='C1132',
 CDS_LIB='pure_quanta',
 CDS_PART_NAME='Q_CAP_C0402-0.1UF,16V,10%,X7R,CH4103K1B08',
 VOLTAGE='16V',
 PART_NUMBER='CH4103K1B08',
 VALUE='0.1UF',
 PRIM_FILE='./archive_libs/logical/q_cap/chips/chips.prt';

PART_NAME
 C1133 'Q_CAP_C0402-0.1UF,16V,10%,X7R,CH4103K1B08':;

SECTION_NUMBER 1
 '@T6G_MB_LIB.T6G(SCH_1):PAGE82_I81@PURE_QUANTA.Q_CAP(CHIPS)':
 C_PATH='@t6g_mb_lib.t6g(sch_1):page82_i81@pure_quanta.q_cap(chips)',
 P_PATH='@t6g_mb_lib.t6g(sch_1):page83_i81@pure_quanta.q_cap(chips)',
 PATH='I81',
 DRAWING='@T6G_MB_LIB.T6G(SCH_1):PAGE82',
 TOLERANCE='10%',
 MATERIAL='X7R',
 PHYS_PAGE='83',
 XY='(-3450,1175)',
 ROT='0',
 VER='2',
 PACK_TYPE='C0402',
 LOCATION='C1133',
 CDS_LIB='pure_quanta',
 CDS_PART_NAME='Q_CAP_C0402-0.1UF,16V,10%,X7R,CH4103K1B08',
 VOLTAGE='16V',
 PART_NUMBER='CH4103K1B08',
 VALUE='0.1UF',
 PRIM_FILE='./archive_libs/logical/q_cap/chips/chips.prt';

PART_NAME
 C1134 'Q_CAP_C0402-0.1UF,16V,10%,X7R,CH4103K1B08':;

SECTION_NUMBER 1
 '@T6G_MB_LIB.T6G(SCH_1):PAGE82_I79@PURE_QUANTA.Q_CAP(CHIPS)':
 C_PATH='@t6g_mb_lib.t6g(sch_1):page82_i79@pure_quanta.q_cap(chips)',
 P_PATH='@t6g_mb_lib.t6g(sch_1):page83_i79@pure_quanta.q_cap(chips)',
 PATH='I79',
 DRAWING='@T6G_MB_LIB.T6G(SCH_1):PAGE82',
 TOLERANCE='10%',
 MATERIAL='X7R',
 PHYS_PAGE='83',
 XY='(-3450,1075)',
 ROT='0',
 VER='2',
 PACK_TYPE='C0402',
 LOCATION='C1134',
 CDS_LIB='pure_quanta',
 CDS_PART_NAME='Q_CAP_C0402-0.1UF,16V,10%,X7R,CH4103K1B08',
 VOLTAGE='16V',
 PART_NUMBER='CH4103K1B08',
 VALUE='0.1UF',
 PRIM_FILE='./archive_libs/logical/q_cap/chips/chips.prt';

PART_NAME
 C1170 'Q_CAP_C0805-10UF,16V,10%,X6S,CH6103KEA00':
 REUSE_ID='6';

SECTION_NUMBER 1
 '@T6G_MB_LIB.T6G(SCH_1):PAGE273_I19@PURE_QUANTA.Q_CAP(CHIPS)':
 C_PATH='@t6g_mb_lib.t6g(sch_1):page273_i19@pure_quanta.q_cap(chips)',
 P_PATH='@t6g_mb_lib.t6g(sch_1):page188_i19@pure_quanta.q_cap(chips)',
 PATH='I19',
 DRAWING='@T6G_MB_LIB.T6G(SCH_1):PAGE273',
 BOM_COST='VR_SYSTEM ',
 TOLERANCE='10%',
 MATERIAL='X6S',
 PHYS_PAGE='188',
 XY='(-5650,7575)',
 ROT='2',
 VER='1',
 PACK_TYPE='C0805',
 LOCATION='C1170',
 CDS_LIB='pure_quanta',
 CDS_PART_NAME='Q_CAP_C0805-10UF,16V,10%,X6S,CH6103KEA00',
 REUSE_ID='6',
 VOLTAGE='16V',
 PART_NUMBER='CH6103KEA00',
 VALUE='10UF',
 PRIM_FILE='./archive_libs/logical/q_cap/chips/chips.prt';

PART_NAME
 C1171 'Q_CAP_C0402-0.1UF,16V,10%,X7R,CH4103K1B08':;

SECTION_NUMBER 1
 '@T6G_MB_LIB.T6G(SCH_1):PAGE82_I114@PURE_QUANTA.Q_CAP(CHIPS)':
 C_PATH='@t6g_mb_lib.t6g(sch_1):page82_i114@pure_quanta.q_cap(chips)',
 P_PATH='@t6g_mb_lib.t6g(sch_1):page83_i114@pure_quanta.q_cap(chips)',
 PATH='I114',
 DRAWING='@T6G_MB_LIB.T6G(SCH_1):PAGE82',
 TOLERANCE='10%',
 MATERIAL='X7R',
 PHYS_PAGE='83',
 XY='(-1200,1825)',
 ROT='0',
 VER='2',
 PACK_TYPE='C0402',
 LOCATION='C1171',
 CDS_LIB='pure_quanta',
 CDS_PART_NAME='Q_CAP_C0402-0.1UF,16V,10%,X7R,CH4103K1B08',
 VOLTAGE='16V',
 PART_NUMBER='CH4103K1B08',
 VALUE='0.1UF',
 PRIM_FILE='./archive_libs/logical/q_cap/chips/chips.prt';

PART_NAME
 C1172 'Q_CAP_C0402-0.1UF,16V,10%,X7R,CH4103K1B08':;

SECTION_NUMBER 1
 '@T6G_MB_LIB.T6G(SCH_1):PAGE82_I112@PURE_QUANTA.Q_CAP(CHIPS)':
 C_PATH='@t6g_mb_lib.t6g(sch_1):page82_i112@pure_quanta.q_cap(chips)',
 P_PATH='@t6g_mb_lib.t6g(sch_1):page83_i112@pure_quanta.q_cap(chips)',
 PATH='I112',
 DRAWING='@T6G_MB_LIB.T6G(SCH_1):PAGE82',
 TOLERANCE='10%',
 MATERIAL='X7R',
 PHYS_PAGE='83',
 XY='(-1200,1725)',
 ROT='0',
 VER='2',
 PACK_TYPE='C0402',
 LOCATION='C1172',
 CDS_LIB='pure_quanta',
 CDS_PART_NAME='Q_CAP_C0402-0.1UF,16V,10%,X7R,CH4103K1B08',
 VOLTAGE='16V',
 PART_NUMBER='CH4103K1B08',
 VALUE='0.1UF',
 PRIM_FILE='./archive_libs/logical/q_cap/chips/chips.prt';

PART_NAME
 C1173 'Q_CAP_C0402-0.1UF,16V,10%,X7R,CH4103K1B08':;

SECTION_NUMBER 1
 '@T6G_MB_LIB.T6G(SCH_1):PAGE82_I113@PURE_QUANTA.Q_CAP(CHIPS)':
 C_PATH='@t6g_mb_lib.t6g(sch_1):page82_i113@pure_quanta.q_cap(chips)',
 P_PATH='@t6g_mb_lib.t6g(sch_1):page83_i113@pure_quanta.q_cap(chips)',
 PATH='I113',
 DRAWING='@T6G_MB_LIB.T6G(SCH_1):PAGE82',
 TOLERANCE='10%',
 MATERIAL='X7R',
 PHYS_PAGE='83',
 XY='(-1200,1625)',
 ROT='0',
 VER='2',
 PACK_TYPE='C0402',
 LOCATION='C1173',
 CDS_LIB='pure_quanta',
 CDS_PART_NAME='Q_CAP_C0402-0.1UF,16V,10%,X7R,CH4103K1B08',
 VOLTAGE='16V',
 PART_NUMBER='CH4103K1B08',
 VALUE='0.1UF',
 PRIM_FILE='./archive_libs/logical/q_cap/chips/chips.prt';

PART_NAME
 C1174 'Q_CAP_C0402-0.1UF,16V,10%,X7R,CH4103K1B08':;

SECTION_NUMBER 1
 '@T6G_MB_LIB.T6G(SCH_1):PAGE82_I111@PURE_QUANTA.Q_CAP(CHIPS)':
 C_PATH='@t6g_mb_lib.t6g(sch_1):page82_i111@pure_quanta.q_cap(chips)',
 P_PATH='@t6g_mb_lib.t6g(sch_1):page83_i111@pure_quanta.q_cap(chips)',
 PATH='I111',
 DRAWING='@T6G_MB_LIB.T6G(SCH_1):PAGE82',
 TOLERANCE='10%',
 MATERIAL='X7R',
 PHYS_PAGE='83',
 XY='(-1200,1525)',
 ROT='0',
 VER='2',
 PACK_TYPE='C0402',
 LOCATION='C1174',
 CDS_LIB='pure_quanta',
 CDS_PART_NAME='Q_CAP_C0402-0.1UF,16V,10%,X7R,CH4103K1B08',
 VOLTAGE='16V',
 PART_NUMBER='CH4103K1B08',
 VALUE='0.1UF',
 PRIM_FILE='./archive_libs/logical/q_cap/chips/chips.prt';

PART_NAME
 C1175 'Q_CAP_C0402-0.1UF,16V,10%,X7R,CH4103K1B08':;

SECTION_NUMBER 1
 '@T6G_MB_LIB.T6G(SCH_1):PAGE82_I110@PURE_QUANTA.Q_CAP(CHIPS)':
 C_PATH='@t6g_mb_lib.t6g(sch_1):page82_i110@pure_quanta.q_cap(chips)',
 P_PATH='@t6g_mb_lib.t6g(sch_1):page83_i110@pure_quanta.q_cap(chips)',
 PATH='I110',
 DRAWING='@T6G_MB_LIB.T6G(SCH_1):PAGE82',
 TOLERANCE='10%',
 MATERIAL='X7R',
 PHYS_PAGE='83',
 XY='(-1200,1425)',
 ROT='0',
 VER='2',
 PACK_TYPE='C0402',
 LOCATION='C1175',
 CDS_LIB='pure_quanta',
 CDS_PART_NAME='Q_CAP_C0402-0.1UF,16V,10%,X7R,CH4103K1B08',
 VOLTAGE='16V',
 PART_NUMBER='CH4103K1B08',
 VALUE='0.1UF',
 PRIM_FILE='./archive_libs/logical/q_cap/chips/chips.prt';

PART_NAME
 C1176 'Q_CAP_C0402-0.1UF,16V,10%,X7R,CH4103K1B08':;

SECTION_NUMBER 1
 '@T6G_MB_LIB.T6G(SCH_1):PAGE82_I109@PURE_QUANTA.Q_CAP(CHIPS)':
 C_PATH='@t6g_mb_lib.t6g(sch_1):page82_i109@pure_quanta.q_cap(chips)',
 P_PATH='@t6g_mb_lib.t6g(sch_1):page83_i109@pure_quanta.q_cap(chips)',
 PATH='I109',
 DRAWING='@T6G_MB_LIB.T6G(SCH_1):PAGE82',
 TOLERANCE='10%',
 MATERIAL='X7R',
 PHYS_PAGE='83',
 XY='(-1200,1325)',
 ROT='0',
 VER='2',
 PACK_TYPE='C0402',
 LOCATION='C1176',
 CDS_LIB='pure_quanta',
 CDS_PART_NAME='Q_CAP_C0402-0.1UF,16V,10%,X7R,CH4103K1B08',
 VOLTAGE='16V',
 PART_NUMBER='CH4103K1B08',
 VALUE='0.1UF',
 PRIM_FILE='./archive_libs/logical/q_cap/chips/chips.prt';

PART_NAME
 C1209 'Q_CAP_0402-100PF,50V,5%,NPO,CH11006JB00':;

SECTION_NUMBER 1
 '@T6G_MB_LIB.T6G(SCH_1):PAGE84_I88@PURE_QUANTA.Q_CAP(CHIPS)':
 C_PATH='@t6g_mb_lib.t6g(sch_1):page84_i88@pure_quanta.q_cap(chips)',
 P_PATH='@t6g_mb_lib.t6g(sch_1):page85_i88@pure_quanta.q_cap(chips)',
 PATH='I88',
 DRAWING='@T6G_MB_LIB.T6G(SCH_1):PAGE84',
 TOLERANCE='5%',
 MATERIAL='NPO',
 PHYS_PAGE='85',
 XY='(-7150,550)',
 ROT='0',
 VER='1',
 PACK_TYPE='0402',
 LOCATION='C1209',
 CDS_LIB='pure_quanta',
 CDS_PART_NAME='Q_CAP_0402-100PF,50V,5%,NPO,CH11006JB00',
 VOLTAGE='50V',
 PART_NUMBER='CH11006JB00',
 VALUE='100PF',
 PRIM_FILE='./archive_libs/logical/q_cap/chips/chips.prt';

PART_NAME
 C1213 'Q_CAP_C0805-22UF,16V,20%,X6S,CH6223MEA00':;

SECTION_NUMBER 1
 '@T6G_MB_LIB.T6G(SCH_1):PAGE335_I87@PURE_QUANTA.Q_CAP(CHIPS)':
 C_PATH='@t6g_mb_lib.t6g(sch_1):page335_i87@pure_quanta.q_cap(chips)',
 P_PATH='@t6g_mb_lib.t6g(sch_1):page131_i87@pure_quanta.q_cap(chips)',
 PATH='I87',
 DRAWING='@T6G_MB_LIB.T6G(SCH_1):PAGE335',
 TOLERANCE='20%',
 MATERIAL='X6S',
 PHYS_PAGE='131',
 XY='(825,1750)',
 ROT='0',
 VER='1',
 PACK_TYPE='C0805',
 LOCATION='C1213',
 CDS_LIB='pure_quanta',
 CDS_PART_NAME='Q_CAP_C0805-22UF,16V,20%,X6S,CH6223MEA00',
 VOLTAGE='16V',
 PART_NUMBER='CH6223MEA00',
 VALUE='22UF',
 PRIM_FILE='./archive_libs/logical/q_cap/chips/chips.prt';

PART_NAME
 C1227 'Q_CAP_C0402-100NF,50V,10%,X7R,CH4106K1B01':
 REUSE_ID='81';

SECTION_NUMBER 1
 '@T6G_MB_LIB.T6G(SCH_1):PAGE273_I41@PURE_QUANTA.Q_CAP(CHIPS)':
 C_PATH='@t6g_mb_lib.t6g(sch_1):page273_i41@pure_quanta.q_cap(chips)',
 P_PATH='@t6g_mb_lib.t6g(sch_1):page188_i41@pure_quanta.q_cap(chips)',
 PATH='I41',
 DRAWING='@T6G_MB_LIB.T6G(SCH_1):PAGE273',
 BOM_COST='VR_SYSTEM ',
 TOLERANCE='10%',
 MATERIAL='X7R',
 PHYS_PAGE='188',
 XY='(-3375,7425)',
 ROT='0',
 VER='1',
 PACK_TYPE='C0402',
 LOCATION='C1227',
 CDS_LIB='pure_quanta',
 CDS_PART_NAME='Q_CAP_C0402-100NF,50V,10%,X7R,CH4106K1B01',
 REUSE_ID='81',
 VOLTAGE='50V',
 PART_NUMBER='CH4106K1B01',
 VALUE='100NF',
 PRIM_FILE='./archive_libs/logical/q_cap/chips/chips.prt';

PART_NAME
 C1235 'Q_CAP_0402-0.1UF,25V,10%,X7R,CH4104K1B00':;

SECTION_NUMBER 1
 '@T6G_MB_LIB.T6G(SCH_1):PAGE335_I90@PURE_QUANTA.Q_CAP(CHIPS)':
 C_PATH='@t6g_mb_lib.t6g(sch_1):page335_i90@pure_quanta.q_cap(chips)',
 P_PATH='@t6g_mb_lib.t6g(sch_1):page131_i90@pure_quanta.q_cap(chips)',
 PATH='I90',
 DRAWING='@T6G_MB_LIB.T6G(SCH_1):PAGE335',
 TOLERANCE='10%',
 MATERIAL='X7R',
 PHYS_PAGE='131',
 XY='(2050,1750)',
 ROT='0',
 VER='1',
 PACK_TYPE='0402',
 LOCATION='C1235',
 CDS_LIB='pure_quanta',
 CDS_PART_NAME='Q_CAP_0402-0.1UF,25V,10%,X7R,CH4104K1B00',
 VOLTAGE='25V',
 PART_NUMBER='CH4104K1B00',
 VALUE='0.1UF',
 PRIM_FILE='./archive_libs/logical/q_cap/chips/chips.prt';

PART_NAME
 C1236 'Q_CAP_0402-0.1UF,25V,10%,X7R,CH4104K1B00':;

SECTION_NUMBER 1
 '@T6G_MB_LIB.T6G(SCH_1):PAGE335_I164@PURE_QUANTA.Q_CAP(CHIPS)':
 C_PATH='@t6g_mb_lib.t6g(sch_1):page335_i164@pure_quanta.q_cap(chips)',
 P_PATH='@t6g_mb_lib.t6g(sch_1):page131_i164@pure_quanta.q_cap(chips)',
 PATH='I164',
 DRAWING='@T6G_MB_LIB.T6G(SCH_1):PAGE335',
 TOLERANCE='10%',
 MATERIAL='X7R',
 PHYS_PAGE='131',
 XY='(2325,1750)',
 ROT='0',
 VER='1',
 PACK_TYPE='0402',
 LOCATION='C1236',
 CDS_LIB='pure_quanta',
 CDS_PART_NAME='Q_CAP_0402-0.1UF,25V,10%,X7R,CH4104K1B00',
 VOLTAGE='25V',
 PART_NUMBER='CH4104K1B00',
 VALUE='0.1UF',
 PRIM_FILE='./archive_libs/logical/q_cap/chips/chips.prt';

PART_NAME
 C1237 'Q_CAP_0402-0.1UF,25V,10%,X7R,CH4104K1B00':;

SECTION_NUMBER 1
 '@T6G_MB_LIB.T6G(SCH_1):PAGE335_I110@PURE_QUANTA.Q_CAP(CHIPS)':
 C_PATH='@t6g_mb_lib.t6g(sch_1):page335_i110@pure_quanta.q_cap(chips)',
 P_PATH='@t6g_mb_lib.t6g(sch_1):page131_i110@pure_quanta.q_cap(chips)',
 PATH='I110',
 DRAWING='@T6G_MB_LIB.T6G(SCH_1):PAGE335',
 TOLERANCE='10%',
 MATERIAL='X7R',
 PHYS_PAGE='131',
 XY='(2850,1900)',
 ROT='0',
 VER='1',
 PACK_TYPE='0402',
 LOCATION='C1237',
 CDS_LIB='pure_quanta',
 CDS_PART_NAME='Q_CAP_0402-0.1UF,25V,10%,X7R,CH4104K1B00',
 VOLTAGE='25V',
 PART_NUMBER='CH4104K1B00',
 VALUE='0.1UF',
 PRIM_FILE='./archive_libs/logical/q_cap/chips/chips.prt';

PART_NAME
 C1238 'Q_CAP_0402-0.1UF,25V,10%,X7R,CH4104K1B00':;

SECTION_NUMBER 1
 '@T6G_MB_LIB.T6G(SCH_1):PAGE335_I111@PURE_QUANTA.Q_CAP(CHIPS)':
 C_PATH='@t6g_mb_lib.t6g(sch_1):page335_i111@pure_quanta.q_cap(chips)',
 P_PATH='@t6g_mb_lib.t6g(sch_1):page131_i111@pure_quanta.q_cap(chips)',
 PATH='I111',
 DRAWING='@T6G_MB_LIB.T6G(SCH_1):PAGE335',
 TOLERANCE='10%',
 MATERIAL='X7R',
 PHYS_PAGE='131',
 XY='(3100,1900)',
 ROT='0',
 VER='1',
 PACK_TYPE='0402',
 LOCATION='C1238',
 CDS_LIB='pure_quanta',
 CDS_PART_NAME='Q_CAP_0402-0.1UF,25V,10%,X7R,CH4104K1B00',
 VOLTAGE='25V',
 PART_NUMBER='CH4104K1B00',
 VALUE='0.1UF',
 PRIM_FILE='./archive_libs/logical/q_cap/chips/chips.prt';

PART_NAME
 C1239 'Q_CAP_0402-0.1UF,25V,10%,X7R,CH4104K1B00':;

SECTION_NUMBER 1
 '@T6G_MB_LIB.T6G(SCH_1):PAGE335_I112@PURE_QUANTA.Q_CAP(CHIPS)':
 C_PATH='@t6g_mb_lib.t6g(sch_1):page335_i112@pure_quanta.q_cap(chips)',
 P_PATH='@t6g_mb_lib.t6g(sch_1):page131_i112@pure_quanta.q_cap(chips)',
 PATH='I112',
 DRAWING='@T6G_MB_LIB.T6G(SCH_1):PAGE335',
 TOLERANCE='10%',
 MATERIAL='X7R',
 PHYS_PAGE='131',
 XY='(3375,1900)',
 ROT='0',
 VER='1',
 PACK_TYPE='0402',
 LOCATION='C1239',
 CDS_LIB='pure_quanta',
 CDS_PART_NAME='Q_CAP_0402-0.1UF,25V,10%,X7R,CH4104K1B00',
 VOLTAGE='25V',
 PART_NUMBER='CH4104K1B00',
 VALUE='0.1UF',
 PRIM_FILE='./archive_libs/logical/q_cap/chips/chips.prt';

PART_NAME
 C1240 'Q_CAP_0402-0.1UF,25V,10%,X7R,CH4104K1B00':;

SECTION_NUMBER 1
 '@T6G_MB_LIB.T6G(SCH_1):PAGE335_I114@PURE_QUANTA.Q_CAP(CHIPS)':
 C_PATH='@t6g_mb_lib.t6g(sch_1):page335_i114@pure_quanta.q_cap(chips)',
 P_PATH='@t6g_mb_lib.t6g(sch_1):page131_i114@pure_quanta.q_cap(chips)',
 PATH='I114',
 DRAWING='@T6G_MB_LIB.T6G(SCH_1):PAGE335',
 TOLERANCE='10%',
 MATERIAL='X7R',
 PHYS_PAGE='131',
 XY='(3650,1900)',
 ROT='0',
 VER='1',
 PACK_TYPE='0402',
 LOCATION='C1240',
 CDS_LIB='pure_quanta',
 CDS_PART_NAME='Q_CAP_0402-0.1UF,25V,10%,X7R,CH4104K1B00',
 VOLTAGE='25V',
 PART_NUMBER='CH4104K1B00',
 VALUE='0.1UF',
 PRIM_FILE='./archive_libs/logical/q_cap/chips/chips.prt';

PART_NAME
 C1274 'Q_CAP_0402-0.1UF,25V,10%,X7R,CH4104K1B00':;

SECTION_NUMBER 1
 '@T6G_MB_LIB.T6G(SCH_1):PAGE337_I3@PURE_QUANTA.Q_CAP(CHIPS)':
 C_PATH='@t6g_mb_lib.t6g(sch_1):page337_i3@pure_quanta.q_cap(chips)',
 P_PATH='@t6g_mb_lib.t6g(sch_1):page133_i3@pure_quanta.q_cap(chips)',
 PATH='I3',
 DRAWING='@T6G_MB_LIB.T6G(SCH_1):PAGE337',
 TOLERANCE='10%',
 MATERIAL='X7R',
 PHYS_PAGE='133',
 XY='(-9875,2750)',
 ROT='2',
 VER='1',
 PACK_TYPE='0402',
 LOCATION='C1274',
 CDS_LIB='pure_quanta',
 CDS_PART_NAME='Q_CAP_0402-0.1UF,25V,10%,X7R,CH4104K1B00',
 VOLTAGE='25V',
 PART_NUMBER='CH4104K1B00',
 VALUE='0.1UF',
 PRIM_FILE='./archive_libs/logical/q_cap/chips/chips.prt';

PART_NAME
 C1275 'Q_CAP_0402-0.1UF,25V,10%,X7R,CH4104K1B00':;

SECTION_NUMBER 1
 '@T6G_MB_LIB.T6G(SCH_1):PAGE337_I19@PURE_QUANTA.Q_CAP(CHIPS)':
 C_PATH='@t6g_mb_lib.t6g(sch_1):page337_i19@pure_quanta.q_cap(chips)',
 P_PATH='@t6g_mb_lib.t6g(sch_1):page133_i19@pure_quanta.q_cap(chips)',
 PATH='I19',
 DRAWING='@T6G_MB_LIB.T6G(SCH_1):PAGE337',
 TOLERANCE='10%',
 MATERIAL='X7R',
 PHYS_PAGE='133',
 XY='(-6250,2850)',
 ROT='0',
 VER='1',
 PACK_TYPE='0402',
 LOCATION='C1275',
 CDS_LIB='pure_quanta',
 CDS_PART_NAME='Q_CAP_0402-0.1UF,25V,10%,X7R,CH4104K1B00',
 VOLTAGE='25V',
 PART_NUMBER='CH4104K1B00',
 VALUE='0.1UF',
 PRIM_FILE='./archive_libs/logical/q_cap/chips/chips.prt';

PART_NAME
 C1276 'Q_CAP_C0805-22UF,16V,20%,X6S,CH6223MEA01':;

SECTION_NUMBER 1
 '@T6G_MB_LIB.T6G(SCH_1):PAGE297_I66@PURE_QUANTA.Q_CAP(CHIPS)':
 C_PATH='@t6g_mb_lib.t6g(sch_1):page297_i66@pure_quanta.q_cap(chips)',
 P_PATH='@t6g_mb_lib.t6g(sch_1):page145_i66@pure_quanta.q_cap(chips)',
 PATH='I66',
 DRAWING='@T6G_MB_LIB.T6G(SCH_1):PAGE297',
 TOLERANCE='20%',
 MATERIAL='X6S',
 PHYS_PAGE='145',
 XY='(2475,2675)',
 ROT='0',
 VER='1',
 PACK_TYPE='C0805',
 LOCATION='C1276',
 CDS_LIB='pure_quanta',
 CDS_PART_NAME='Q_CAP_C0805-22UF,16V,20%,X6S,CH6223MEA01',
 VOLTAGE='16V',
 PART_NUMBER='CH6223MEA01',
 VALUE='22UF',
 PRIM_FILE='./archive_libs/logical/q_cap/chips/chips.prt';

PART_NAME
 C1277 'Q_CAP_C0805-22UF,16V,20%,X6S,CH6223MEA01':;

SECTION_NUMBER 1
 '@T6G_MB_LIB.T6G(SCH_1):PAGE297_I67@PURE_QUANTA.Q_CAP(CHIPS)':
 C_PATH='@t6g_mb_lib.t6g(sch_1):page297_i67@pure_quanta.q_cap(chips)',
 P_PATH='@t6g_mb_lib.t6g(sch_1):page145_i67@pure_quanta.q_cap(chips)',
 PATH='I67',
 DRAWING='@T6G_MB_LIB.T6G(SCH_1):PAGE297',
 TOLERANCE='20%',
 MATERIAL='X6S',
 PHYS_PAGE='145',
 XY='(2750,2675)',
 ROT='0',
 VER='1',
 PACK_TYPE='C0805',
 LOCATION='C1277',
 CDS_LIB='pure_quanta',
 CDS_PART_NAME='Q_CAP_C0805-22UF,16V,20%,X6S,CH6223MEA01',
 VOLTAGE='16V',
 PART_NUMBER='CH6223MEA01',
 VALUE='22UF',
 PRIM_FILE='./archive_libs/logical/q_cap/chips/chips.prt';

PART_NAME
 C1278 'Q_CAP_0402-0.1UF,25V,10%,X7R,CH4104K1B00':;

SECTION_NUMBER 1
 '@T6G_MB_LIB.T6G(SCH_1):PAGE297_I68@PURE_QUANTA.Q_CAP(CHIPS)':
 C_PATH='@t6g_mb_lib.t6g(sch_1):page297_i68@pure_quanta.q_cap(chips)',
 P_PATH='@t6g_mb_lib.t6g(sch_1):page145_i68@pure_quanta.q_cap(chips)',
 PATH='I68',
 DRAWING='@T6G_MB_LIB.T6G(SCH_1):PAGE297',
 TOLERANCE='10%',
 MATERIAL='X7R',
 PHYS_PAGE='145',
 XY='(3150,2675)',
 ROT='0',
 VER='1',
 PACK_TYPE='0402',
 LOCATION='C1278',
 CDS_LIB='pure_quanta',
 CDS_PART_NAME='Q_CAP_0402-0.1UF,25V,10%,X7R,CH4104K1B00',
 VOLTAGE='25V',
 PART_NUMBER='CH4104K1B00',
 VALUE='0.1UF',
 PRIM_FILE='./archive_libs/logical/q_cap/chips/chips.prt';

PART_NAME
 C1279 'Q_CAP_0402-0.1UF,25V,10%,X7R,CH4104K1B00':;

SECTION_NUMBER 1
 '@T6G_MB_LIB.T6G(SCH_1):PAGE297_I74@PURE_QUANTA.Q_CAP(CHIPS)':
 C_PATH='@t6g_mb_lib.t6g(sch_1):page297_i74@pure_quanta.q_cap(chips)',
 P_PATH='@t6g_mb_lib.t6g(sch_1):page145_i74@pure_quanta.q_cap(chips)',
 PATH='I74',
 DRAWING='@T6G_MB_LIB.T6G(SCH_1):PAGE297',
 TOLERANCE='10%',
 MATERIAL='X7R',
 PHYS_PAGE='145',
 XY='(3425,2675)',
 ROT='0',
 VER='1',
 PACK_TYPE='0402',
 LOCATION='C1279',
 CDS_LIB='pure_quanta',
 CDS_PART_NAME='Q_CAP_0402-0.1UF,25V,10%,X7R,CH4104K1B00',
 VOLTAGE='25V',
 PART_NUMBER='CH4104K1B00',
 VALUE='0.1UF',
 PRIM_FILE='./archive_libs/logical/q_cap/chips/chips.prt';

PART_NAME
 C1282 'Q_CAP_0402-0.1UF,25V,10%,X7R,CH4104K1B00':;

SECTION_NUMBER 1
 '@T6G_MB_LIB.T6G(SCH_1):PAGE297_I87@PURE_QUANTA.Q_CAP(CHIPS)':
 C_PATH='@t6g_mb_lib.t6g(sch_1):page297_i87@pure_quanta.q_cap(chips)',
 P_PATH='@t6g_mb_lib.t6g(sch_1):page145_i87@pure_quanta.q_cap(chips)',
 PATH='I87',
 DRAWING='@T6G_MB_LIB.T6G(SCH_1):PAGE297',
 TOLERANCE='10%',
 MATERIAL='X7R',
 PHYS_PAGE='145',
 XY='(4500,2675)',
 ROT='0',
 VER='1',
 PACK_TYPE='0402',
 LOCATION='C1282',
 CDS_LIB='pure_quanta',
 CDS_PART_NAME='Q_CAP_0402-0.1UF,25V,10%,X7R,CH4104K1B00',
 VOLTAGE='25V',
 PART_NUMBER='CH4104K1B00',
 VALUE='0.1UF',
 PRIM_FILE='./archive_libs/logical/q_cap/chips/chips.prt';

PART_NAME
 C1283 'Q_CAP_0402-0.1UF,25V,10%,X7R,CH4104K1B00':;

SECTION_NUMBER 1
 '@T6G_MB_LIB.T6G(SCH_1):PAGE297_I88@PURE_QUANTA.Q_CAP(CHIPS)':
 C_PATH='@t6g_mb_lib.t6g(sch_1):page297_i88@pure_quanta.q_cap(chips)',
 P_PATH='@t6g_mb_lib.t6g(sch_1):page145_i88@pure_quanta.q_cap(chips)',
 PATH='I88',
 DRAWING='@T6G_MB_LIB.T6G(SCH_1):PAGE297',
 TOLERANCE='10%',
 MATERIAL='X7R',
 PHYS_PAGE='145',
 XY='(4750,2675)',
 ROT='0',
 VER='1',
 PACK_TYPE='0402',
 LOCATION='C1283',
 CDS_LIB='pure_quanta',
 CDS_PART_NAME='Q_CAP_0402-0.1UF,25V,10%,X7R,CH4104K1B00',
 VOLTAGE='25V',
 PART_NUMBER='CH4104K1B00',
 VALUE='0.1UF',
 PRIM_FILE='./archive_libs/logical/q_cap/chips/chips.prt';

PART_NAME
 C1305 'Q_CAP_0402-0.1UF,25V,10%,X7R,CH4104K1B00':;

SECTION_NUMBER 1
 '@T6G_MB_LIB.T6G(SCH_1):PAGE346_I52@PURE_QUANTA.Q_CAP(CHIPS)':
 C_PATH='@t6g_mb_lib.t6g(sch_1):page346_i52@pure_quanta.q_cap(chips)',
 P_PATH='@t6g_mb_lib.t6g(sch_1):page148_i52@pure_quanta.q_cap(chips)',
 PATH='I52',
 DRAWING='@T6G_MB_LIB.T6G(SCH_1):PAGE346',
 TOLERANCE='10%',
 MATERIAL='X7R',
 PHYS_PAGE='148',
 XY='(-425,3775)',
 ROT='2',
 VER='1',
 PACK_TYPE='0402',
 LOCATION='C1305',
 CDS_LIB='pure_quanta',
 CDS_PART_NAME='Q_CAP_0402-0.1UF,25V,10%,X7R,CH4104K1B00',
 VOLTAGE='25V',
 PART_NUMBER='CH4104K1B00',
 VALUE='0.1UF',
 PRIM_FILE='./archive_libs/logical/q_cap/chips/chips.prt';

PART_NAME
 C1323 'Q_CAP_0402-0.1UF,25V,10%,X7R,CH4104K1B00':;

SECTION_NUMBER 1
 '@T6G_MB_LIB.T6G(SCH_1):PAGE346_I28@PURE_QUANTA.Q_CAP(CHIPS)':
 C_PATH='@t6g_mb_lib.t6g(sch_1):page346_i28@pure_quanta.q_cap(chips)',
 P_PATH='@t6g_mb_lib.t6g(sch_1):page148_i28@pure_quanta.q_cap(chips)',
 PATH='I28',
 DRAWING='@T6G_MB_LIB.T6G(SCH_1):PAGE346',
 TOLERANCE='10%',
 MATERIAL='X7R',
 PHYS_PAGE='148',
 XY='(1400,3800)',
 ROT='0',
 VER='1',
 PACK_TYPE='0402',
 LOCATION='C1323',
 CDS_LIB='pure_quanta',
 CDS_PART_NAME='Q_CAP_0402-0.1UF,25V,10%,X7R,CH4104K1B00',
 VOLTAGE='25V',
 PART_NUMBER='CH4104K1B00',
 VALUE='0.1UF',
 PRIM_FILE='./archive_libs/logical/q_cap/chips/chips.prt';

PART_NAME
 C1331 'Q_CAP_C0805-10UF,16V,10%,X6S,CH6103KEA00':
 REUSE_ID='6';

SECTION_NUMBER 1
 '@T6G_MB_LIB.T6G(SCH_1):PAGE273_I43@PURE_QUANTA.Q_CAP(CHIPS)':
 C_PATH='@t6g_mb_lib.t6g(sch_1):page273_i43@pure_quanta.q_cap(chips)',
 P_PATH='@t6g_mb_lib.t6g(sch_1):page188_i43@pure_quanta.q_cap(chips)',
 PATH='I43',
 DRAWING='@T6G_MB_LIB.T6G(SCH_1):PAGE273',
 BOM_COST='VR_SYSTEM ',
 TOLERANCE='10%',
 MATERIAL='X6S',
 PHYS_PAGE='188',
 XY='(-3050,7425)',
 ROT='0',
 VER='1',
 PACK_TYPE='C0805',
 LOCATION='C1331',
 CDS_LIB='pure_quanta',
 CDS_PART_NAME='Q_CAP_C0805-10UF,16V,10%,X6S,CH6103KEA00',
 REUSE_ID='6',
 VOLTAGE='16V',
 PART_NUMBER='CH6103KEA00',
 VALUE='10UF',
 PRIM_FILE='./archive_libs/logical/q_cap/chips/chips.prt';

PART_NAME
 C1332 'Q_CAP_C0402-100NF,50V,10%,X7R,CH4106K1B01':;

SECTION_NUMBER 1
 '@T6G_MB_LIB.T6G(SCH_1):PAGE273_I48@PURE_QUANTA.Q_CAP(CHIPS)':
 C_PATH='@t6g_mb_lib.t6g(sch_1):page273_i48@pure_quanta.q_cap(chips)',
 P_PATH='@t6g_mb_lib.t6g(sch_1):page188_i48@pure_quanta.q_cap(chips)',
 PATH='I48',
 DRAWING='@T6G_MB_LIB.T6G(SCH_1):PAGE273',
 BOM_COST='VR_SYSTEM ',
 TOLERANCE='10%',
 MATERIAL='X7R',
 PHYS_PAGE='188',
 XY='(-1225,5700)',
 ROT='2',
 VER='1',
 PACK_TYPE='C0402',
 LOCATION='C1332',
 CDS_LIB='pure_quanta',
 CDS_PART_NAME='Q_CAP_C0402-100NF,50V,10%,X7R,CH4106K1B01',
 VOLTAGE='50V',
 PART_NUMBER='CH4106K1B01',
 VALUE='100NF',
 PRIM_FILE='./archive_libs/logical/q_cap/chips/chips.prt';

PART_NAME
 C1333 'Q_CAP_C0805-10UF,16V,10%,X6S,CH6103KEA00':;

SECTION_NUMBER 1
 '@T6G_MB_LIB.T6G(SCH_1):PAGE273_I49@PURE_QUANTA.Q_CAP(CHIPS)':
 C_PATH='@t6g_mb_lib.t6g(sch_1):page273_i49@pure_quanta.q_cap(chips)',
 P_PATH='@t6g_mb_lib.t6g(sch_1):page188_i49@pure_quanta.q_cap(chips)',
 PATH='I49',
 DRAWING='@T6G_MB_LIB.T6G(SCH_1):PAGE273',
 BOM_COST='VR_SYSTEM ',
 TOLERANCE='10%',
 MATERIAL='X6S',
 PHYS_PAGE='188',
 XY='(-900,5700)',
 ROT='2',
 VER='1',
 PACK_TYPE='C0805',
 LOCATION='C1333',
 CDS_LIB='pure_quanta',
 CDS_PART_NAME='Q_CAP_C0805-10UF,16V,10%,X6S,CH6103KEA00',
 VOLTAGE='16V',
 PART_NUMBER='CH6103KEA00',
 VALUE='10UF',
 PRIM_FILE='./archive_libs/logical/q_cap/chips/chips.prt';

PART_NAME
 C1336 'Q_CAP_0402-0.1UF,25V,10%,X7R,CH4104K1B00':;

SECTION_NUMBER 1
 '@T6G_MB_LIB.T6G(SCH_1):PAGE136_I50@PURE_QUANTA.Q_CAP(CHIPS)':
 C_PATH='@t6g_mb_lib.t6g(sch_1):page136_i50@pure_quanta.q_cap(chips)',
 P_PATH='@t6g_mb_lib.t6g(sch_1):page159_i50@pure_quanta.q_cap(chips)',
 PATH='I50',
 DRAWING='@T6G_MB_LIB.T6G(SCH_1):PAGE136',
 TOLERANCE='10%',
 MATERIAL='X7R',
 PHYS_PAGE='159',
 XY='(-4275,6200)',
 ROT='0',
 VER='1',
 PACK_TYPE='0402',
 LOCATION='C1336',
 CDS_LIB='pure_quanta',
 CDS_PART_NAME='Q_CAP_0402-0.1UF,25V,10%,X7R,CH4104K1B00',
 VOLTAGE='25V',
 PART_NUMBER='CH4104K1B00',
 VALUE='0.1UF',
 PRIM_FILE='./archive_libs/logical/q_cap/chips/chips.prt';

PART_NAME
 C1337 'Q_CAP_0402-0.1UF,25V,10%,X7R,CH4104K1B00':;

SECTION_NUMBER 1
 '@T6G_MB_LIB.T6G(SCH_1):PAGE136_I56@PURE_QUANTA.Q_CAP(CHIPS)':
 C_PATH='@t6g_mb_lib.t6g(sch_1):page136_i56@pure_quanta.q_cap(chips)',
 P_PATH='@t6g_mb_lib.t6g(sch_1):page159_i56@pure_quanta.q_cap(chips)',
 PATH='I56',
 DRAWING='@T6G_MB_LIB.T6G(SCH_1):PAGE136',
 TOLERANCE='10%',
 MATERIAL='X7R',
 PHYS_PAGE='159',
 XY='(-4250,4800)',
 ROT='0',
 VER='1',
 PACK_TYPE='0402',
 LOCATION='C1337',
 CDS_LIB='pure_quanta',
 CDS_PART_NAME='Q_CAP_0402-0.1UF,25V,10%,X7R,CH4104K1B00',
 VOLTAGE='25V',
 PART_NUMBER='CH4104K1B00',
 VALUE='0.1UF',
 PRIM_FILE='./archive_libs/logical/q_cap/chips/chips.prt';

PART_NAME
 C1338 'Q_CAP_0402-0.1UF,25V,10%,X7R,CH4104K1B00':;

SECTION_NUMBER 1
 '@T6G_MB_LIB.T6G(SCH_1):PAGE136_I61@PURE_QUANTA.Q_CAP(CHIPS)':
 C_PATH='@t6g_mb_lib.t6g(sch_1):page136_i61@pure_quanta.q_cap(chips)',
 P_PATH='@t6g_mb_lib.t6g(sch_1):page159_i61@pure_quanta.q_cap(chips)',
 PATH='I61',
 DRAWING='@T6G_MB_LIB.T6G(SCH_1):PAGE136',
 TOLERANCE='10%',
 MATERIAL='X7R',
 PHYS_PAGE='159',
 XY='(-4250,3275)',
 ROT='0',
 VER='1',
 PACK_TYPE='0402',
 LOCATION='C1338',
 CDS_LIB='pure_quanta',
 CDS_PART_NAME='Q_CAP_0402-0.1UF,25V,10%,X7R,CH4104K1B00',
 VOLTAGE='25V',
 PART_NUMBER='CH4104K1B00',
 VALUE='0.1UF',
 PRIM_FILE='./archive_libs/logical/q_cap/chips/chips.prt';

PART_NAME
 C1339 'Q_CAP_0402-0.1UF,25V,10%,X7R,CH4104K1B00':;

SECTION_NUMBER 1
 '@T6G_MB_LIB.T6G(SCH_1):PAGE136_I66@PURE_QUANTA.Q_CAP(CHIPS)':
 C_PATH='@t6g_mb_lib.t6g(sch_1):page136_i66@pure_quanta.q_cap(chips)',
 P_PATH='@t6g_mb_lib.t6g(sch_1):page159_i66@pure_quanta.q_cap(chips)',
 PATH='I66',
 DRAWING='@T6G_MB_LIB.T6G(SCH_1):PAGE136',
 TOLERANCE='10%',
 MATERIAL='X7R',
 PHYS_PAGE='159',
 XY='(-4200,1825)',
 ROT='0',
 VER='1',
 PACK_TYPE='0402',
 LOCATION='C1339',
 CDS_LIB='pure_quanta',
 CDS_PART_NAME='Q_CAP_0402-0.1UF,25V,10%,X7R,CH4104K1B00',
 VOLTAGE='25V',
 PART_NUMBER='CH4104K1B00',
 VALUE='0.1UF',
 PRIM_FILE='./archive_libs/logical/q_cap/chips/chips.prt';

PART_NAME
 C1340 'Q_CAP_C0805-10UF,16V,10%,X6S,CH6103KEA00':;

SECTION_NUMBER 1
 '@T6G_MB_LIB.T6G(SCH_1):PAGE273_I61@PURE_QUANTA.Q_CAP(CHIPS)':
 C_PATH='@t6g_mb_lib.t6g(sch_1):page273_i61@pure_quanta.q_cap(chips)',
 P_PATH='@t6g_mb_lib.t6g(sch_1):page188_i61@pure_quanta.q_cap(chips)',
 PATH='I61',
 DRAWING='@T6G_MB_LIB.T6G(SCH_1):PAGE273',
 BOM_COST='VR_SYSTEM ',
 TOLERANCE='10%',
 MATERIAL='X6S',
 PHYS_PAGE='188',
 XY='(1100,5700)',
 ROT='0',
 VER='1',
 PACK_TYPE='C0805',
 LOCATION='C1340',
 CDS_LIB='pure_quanta',
 CDS_PART_NAME='Q_CAP_C0805-10UF,16V,10%,X6S,CH6103KEA00',
 VOLTAGE='16V',
 PART_NUMBER='CH6103KEA00',
 VALUE='10UF',
 PRIM_FILE='./archive_libs/logical/q_cap/chips/chips.prt';

PART_NAME
 C1344 'Q_CAP_0402-100PF,50V,5%,EMPTY,CH11006JB18':
 ROOM='ADC_MAM_BOM2';

SECTION_NUMBER 1
 '@T6G_MB_LIB.T6G(SCH_1):PAGE369_I46@PURE_QUANTA.Q_CAP(CHIPS)':
 C_PATH='@t6g_mb_lib.t6g(sch_1):page369_i46@pure_quanta.q_cap(chips)',
 P_PATH='@t6g_mb_lib.t6g(sch_1):page257_i46@pure_quanta.q_cap(chips)',
 PATH='I46',
 DRAWING='@T6G_MB_LIB.T6G(SCH_1):PAGE369',
 TOLERANCE='5%',
 MATERIAL='EMPTY',
 PHYS_PAGE='257',
 XY='(-7200,1775)',
 ROT='0',
 VER='1',
 PACK_TYPE='0402',
 LOCATION='C1344',
 CDS_LIB='pure_quanta',
 CDS_PART_NAME='Q_CAP_0402-100PF,50V,5%,EMPTY,CH11006JB18',
 VOLTAGE='50V',
 ROOM='ADC_MAM_BOM2',
 PART_NUMBER='CH11006JB18',
 VALUE='100PF',
 PRIM_FILE='./archive_libs/logical/q_cap/chips/chips.prt';

PART_NAME
 C1347 'Q_CAP_0402-0.1UF,25V,10%,X7R,CH4104K1B00':;

SECTION_NUMBER 1
 '@T6G_MB_LIB.T6G(SCH_1):PAGE369_I119@PURE_QUANTA.Q_CAP(CHIPS)':
 C_PATH='@t6g_mb_lib.t6g(sch_1):page369_i119@pure_quanta.q_cap(chips)',
 P_PATH='@t6g_mb_lib.t6g(sch_1):page257_i119@pure_quanta.q_cap(chips)',
 PATH='I119',
 DRAWING='@T6G_MB_LIB.T6G(SCH_1):PAGE369',
 TOLERANCE='10%',
 MATERIAL='X7R',
 PHYS_PAGE='257',
 XY='(-4200,5350)',
 ROT='2',
 VER='1',
 PACK_TYPE='0402',
 LOCATION='C1347',
 CDS_LIB='pure_quanta',
 CDS_PART_NAME='Q_CAP_0402-0.1UF,25V,10%,X7R,CH4104K1B00',
 VOLTAGE='25V',
 PART_NUMBER='CH4104K1B00',
 VALUE='0.1UF',
 PRIM_FILE='./archive_libs/logical/q_cap/chips/chips.prt';

PART_NAME
 C1352 'Q_CAP_0402-0.1UF,25V,10%,X7R,CH4104K1B00':;

SECTION_NUMBER 1
 '@T6G_MB_LIB.T6G(SCH_1):PAGE141_I137@PURE_QUANTA.Q_CAP(CHIPS)':
 C_PATH='@t6g_mb_lib.t6g(sch_1):page141_i137@pure_quanta.q_cap(chips)',
 P_PATH='@t6g_mb_lib.t6g(sch_1):page164_i137@pure_quanta.q_cap(chips)',
 PATH='I137',
 DRAWING='@T6G_MB_LIB.T6G(SCH_1):PAGE141',
 TOLERANCE='10%',
 MATERIAL='X7R',
 PHYS_PAGE='164',
 XY='(-5175,3725)',
 ROT='2',
 VER='1',
 PACK_TYPE='0402',
 LOCATION='C1352',
 CDS_LIB='pure_quanta',
 CDS_PART_NAME='Q_CAP_0402-0.1UF,25V,10%,X7R,CH4104K1B00',
 VOLTAGE='25V',
 PART_NUMBER='CH4104K1B00',
 VALUE='0.1UF',
 PRIM_FILE='./archive_libs/logical/q_cap/chips/chips.prt';

PART_NAME
 C1354 'Q_CAP_0402-0.1UF,25V,10%,X7R,CH4104K1B00':;

SECTION_NUMBER 1
 '@T6G_MB_LIB.T6G(SCH_1):PAGE141_I133@PURE_QUANTA.Q_CAP(CHIPS)':
 C_PATH='@t6g_mb_lib.t6g(sch_1):page141_i133@pure_quanta.q_cap(chips)',
 P_PATH='@t6g_mb_lib.t6g(sch_1):page164_i133@pure_quanta.q_cap(chips)',
 PATH='I133',
 DRAWING='@T6G_MB_LIB.T6G(SCH_1):PAGE141',
 TOLERANCE='10%',
 MATERIAL='X7R',
 PHYS_PAGE='164',
 XY='(-3850,3725)',
 ROT='0',
 VER='1',
 PACK_TYPE='0402',
 LOCATION='C1354',
 CDS_LIB='pure_quanta',
 CDS_PART_NAME='Q_CAP_0402-0.1UF,25V,10%,X7R,CH4104K1B00',
 VOLTAGE='25V',
 PART_NUMBER='CH4104K1B00',
 VALUE='0.1UF',
 PRIM_FILE='./archive_libs/logical/q_cap/chips/chips.prt';

PART_NAME
 C1503 'Q_CAP_C0402-0.1UF,16V,10%,X7R,CH4103K1B08':;

SECTION_NUMBER 1
 '@T6G_MB_LIB.T6G(SCH_1):PAGE149_I80@PURE_QUANTA.Q_CAP(CHIPS)':
 C_PATH='@t6g_mb_lib.t6g(sch_1):page149_i80@pure_quanta.q_cap(chips)',
 P_PATH='@t6g_mb_lib.t6g(sch_1):page172_i80@pure_quanta.q_cap(chips)',
 PATH='I80',
 DRAWING='@T6G_MB_LIB.T6G(SCH_1):PAGE149',
 TOLERANCE='10%',
 MATERIAL='X7R',
 PHYS_PAGE='172',
 XY='(-7625,2800)',
 ROT='0',
 VER='1',
 PACK_TYPE='C0402',
 LOCATION='C1503',
 CDS_LIB='pure_quanta',
 CDS_PART_NAME='Q_CAP_C0402-0.1UF,16V,10%,X7R,CH4103K1B08',
 VOLTAGE='16V',
 PART_NUMBER='CH4103K1B08',
 VALUE='0.1UF',
 PRIM_FILE='./archive_libs/logical/q_cap/chips/chips.prt';

PART_NAME
 C1504 'Q_CAP_C0402-0.1UF,16V,10%,X7R,CH4103K1B08':;

SECTION_NUMBER 1
 '@T6G_MB_LIB.T6G(SCH_1):PAGE149_I56@PURE_QUANTA.Q_CAP(CHIPS)':
 C_PATH='@t6g_mb_lib.t6g(sch_1):page149_i56@pure_quanta.q_cap(chips)',
 P_PATH='@t6g_mb_lib.t6g(sch_1):page172_i56@pure_quanta.q_cap(chips)',
 PATH='I56',
 DRAWING='@T6G_MB_LIB.T6G(SCH_1):PAGE149',
 TOLERANCE='10%',
 MATERIAL='X7R',
 PHYS_PAGE='172',
 XY='(-6350,4625)',
 ROT='0',
 VER='1',
 PACK_TYPE='C0402',
 LOCATION='C1504',
 CDS_LIB='pure_quanta',
 CDS_PART_NAME='Q_CAP_C0402-0.1UF,16V,10%,X7R,CH4103K1B08',
 VOLTAGE='16V',
 PART_NUMBER='CH4103K1B08',
 VALUE='0.1UF',
 PRIM_FILE='./archive_libs/logical/q_cap/chips/chips.prt';

PART_NAME
 C1505 'Q_CAP_C0402-0.1UF,16V,10%,X7R,CH4103K1B08':;

SECTION_NUMBER 1
 '@T6G_MB_LIB.T6G(SCH_1):PAGE149_I74@PURE_QUANTA.Q_CAP(CHIPS)':
 C_PATH='@t6g_mb_lib.t6g(sch_1):page149_i74@pure_quanta.q_cap(chips)',
 P_PATH='@t6g_mb_lib.t6g(sch_1):page172_i74@pure_quanta.q_cap(chips)',
 PATH='I74',
 DRAWING='@T6G_MB_LIB.T6G(SCH_1):PAGE149',
 TOLERANCE='10%',
 MATERIAL='X7R',
 PHYS_PAGE='172',
 XY='(-6325,2725)',
 ROT='0',
 VER='1',
 PACK_TYPE='C0402',
 LOCATION='C1505',
 CDS_LIB='pure_quanta',
 CDS_PART_NAME='Q_CAP_C0402-0.1UF,16V,10%,X7R,CH4103K1B08',
 VOLTAGE='16V',
 PART_NUMBER='CH4103K1B08',
 VALUE='0.1UF',
 PRIM_FILE='./archive_libs/logical/q_cap/chips/chips.prt';

PART_NAME
 C1506 'Q_CAP_C0402-0.1UF,16V,10%,X7R,CH4103K1B08':;

SECTION_NUMBER 1
 '@T6G_MB_LIB.T6G(SCH_1):PAGE149_I62@PURE_QUANTA.Q_CAP(CHIPS)':
 C_PATH='@t6g_mb_lib.t6g(sch_1):page149_i62@pure_quanta.q_cap(chips)',
 P_PATH='@t6g_mb_lib.t6g(sch_1):page172_i62@pure_quanta.q_cap(chips)',
 PATH='I62',
 DRAWING='@T6G_MB_LIB.T6G(SCH_1):PAGE149',
 TOLERANCE='10%',
 MATERIAL='X7R',
 PHYS_PAGE='172',
 XY='(-3975,2400)',
 ROT='0',
 VER='1',
 PACK_TYPE='C0402',
 LOCATION='C1506',
 CDS_LIB='pure_quanta',
 CDS_PART_NAME='Q_CAP_C0402-0.1UF,16V,10%,X7R,CH4103K1B08',
 VOLTAGE='16V',
 PART_NUMBER='CH4103K1B08',
 VALUE='0.1UF',
 PRIM_FILE='./archive_libs/logical/q_cap/chips/chips.prt';

PART_NAME
 C1507 'Q_CAP_C0402-0.1UF,16V,10%,X7R,CH4103K1B08':;

SECTION_NUMBER 1
 '@T6G_MB_LIB.T6G(SCH_1):PAGE149_I41@PURE_QUANTA.Q_CAP(CHIPS)':
 C_PATH='@t6g_mb_lib.t6g(sch_1):page149_i41@pure_quanta.q_cap(chips)',
 P_PATH='@t6g_mb_lib.t6g(sch_1):page172_i41@pure_quanta.q_cap(chips)',
 PATH='I41',
 DRAWING='@T6G_MB_LIB.T6G(SCH_1):PAGE149',
 TOLERANCE='10%',
 MATERIAL='X7R',
 PHYS_PAGE='172',
 XY='(-3975,4550)',
 ROT='0',
 VER='1',
 PACK_TYPE='C0402',
 LOCATION='C1507',
 CDS_LIB='pure_quanta',
 CDS_PART_NAME='Q_CAP_C0402-0.1UF,16V,10%,X7R,CH4103K1B08',
 VOLTAGE='16V',
 PART_NUMBER='CH4103K1B08',
 VALUE='0.1UF',
 PRIM_FILE='./archive_libs/logical/q_cap/chips/chips.prt';

PART_NAME
 C1508 'Q_CAP_C0402-0.1UF,16V,10%,X7R,CH4103K1B08':;

SECTION_NUMBER 1
 '@T6G_MB_LIB.T6G(SCH_1):PAGE149_I29@PURE_QUANTA.Q_CAP(CHIPS)':
 C_PATH='@t6g_mb_lib.t6g(sch_1):page149_i29@pure_quanta.q_cap(chips)',
 P_PATH='@t6g_mb_lib.t6g(sch_1):page172_i29@pure_quanta.q_cap(chips)',
 PATH='I29',
 DRAWING='@T6G_MB_LIB.T6G(SCH_1):PAGE149',
 TOLERANCE='10%',
 MATERIAL='X7R',
 PHYS_PAGE='172',
 XY='(-2650,2650)',
 ROT='0',
 VER='1',
 PACK_TYPE='C0402',
 LOCATION='C1508',
 CDS_LIB='pure_quanta',
 CDS_PART_NAME='Q_CAP_C0402-0.1UF,16V,10%,X7R,CH4103K1B08',
 VOLTAGE='16V',
 PART_NUMBER='CH4103K1B08',
 VALUE='0.1UF',
 PRIM_FILE='./archive_libs/logical/q_cap/chips/chips.prt';

PART_NAME
 C1509 'Q_CAP_C0402-0.1UF,16V,10%,X7R,CH4103K1B08':;

SECTION_NUMBER 1
 '@T6G_MB_LIB.T6G(SCH_1):PAGE149_I10@PURE_QUANTA.Q_CAP(CHIPS)':
 C_PATH='@t6g_mb_lib.t6g(sch_1):page149_i10@pure_quanta.q_cap(chips)',
 P_PATH='@t6g_mb_lib.t6g(sch_1):page172_i10@pure_quanta.q_cap(chips)',
 PATH='I10',
 DRAWING='@T6G_MB_LIB.T6G(SCH_1):PAGE149',
 TOLERANCE='10%',
 MATERIAL='X7R',
 PHYS_PAGE='172',
 XY='(-2650,4550)',
 ROT='0',
 VER='1',
 PACK_TYPE='C0402',
 LOCATION='C1509',
 CDS_LIB='pure_quanta',
 CDS_PART_NAME='Q_CAP_C0402-0.1UF,16V,10%,X7R,CH4103K1B08',
 VOLTAGE='16V',
 PART_NUMBER='CH4103K1B08',
 VALUE='0.1UF',
 PRIM_FILE='./archive_libs/logical/q_cap/chips/chips.prt';

PART_NAME
 C1510 'Q_CAP_0402-33PF,50V,5%,NPO,TMP_QCH03306JB04':;

SECTION_NUMBER 1
 '@T6G_MB_LIB.T6G(SCH_1):PAGE149_I25@PURE_QUANTA.Q_CAP(CHIPS)':
 C_PATH='@t6g_mb_lib.t6g(sch_1):page149_i25@pure_quanta.q_cap(chips)',
 P_PATH='@t6g_mb_lib.t6g(sch_1):page172_i25@pure_quanta.q_cap(chips)',
 PATH='I25',
 DRAWING='@T6G_MB_LIB.T6G(SCH_1):PAGE149',
 TOLERANCE='5%',
 MATERIAL='NPO',
 PHYS_PAGE='172',
 XY='(-1500,3775)',
 ROT='0',
 VER='1',
 PACK_TYPE='0402',
 LOCATION='C1510',
 CDS_LIB='pure_quanta',
 CDS_PART_NAME='Q_CAP_0402-33PF,50V,5%,NPO,TMP_QCH03306JB04',
 VOLTAGE='50V',
 PART_NUMBER='TMP_QCH03306JB04',
 VALUE='33PF',
 PRIM_FILE='./archive_libs/logical/q_cap/chips/chips.prt';

PART_NAME
 C1511 'Q_CAP_0402-33PF,50V,5%,NPO,TMP_QCH03306JB04':;

SECTION_NUMBER 1
 '@T6G_MB_LIB.T6G(SCH_1):PAGE149_I23@PURE_QUANTA.Q_CAP(CHIPS)':
 C_PATH='@t6g_mb_lib.t6g(sch_1):page149_i23@pure_quanta.q_cap(chips)',
 P_PATH='@t6g_mb_lib.t6g(sch_1):page172_i23@pure_quanta.q_cap(chips)',
 PATH='I23',
 DRAWING='@T6G_MB_LIB.T6G(SCH_1):PAGE149',
 TOLERANCE='5%',
 MATERIAL='NPO',
 PHYS_PAGE='172',
 XY='(-1125,3775)',
 ROT='0',
 VER='1',
 PACK_TYPE='0402',
 LOCATION='C1511',
 CDS_LIB='pure_quanta',
 CDS_PART_NAME='Q_CAP_0402-33PF,50V,5%,NPO,TMP_QCH03306JB04',
 VOLTAGE='50V',
 PART_NUMBER='TMP_QCH03306JB04',
 VALUE='33PF',
 PRIM_FILE='./archive_libs/logical/q_cap/chips/chips.prt';

PART_NAME
 C1512 'Q_CAP_0402-33PF,50V,5%,NPO,TMP_QCH03306JB04':;

SECTION_NUMBER 1
 '@T6G_MB_LIB.T6G(SCH_1):PAGE149_I21@PURE_QUANTA.Q_CAP(CHIPS)':
 C_PATH='@t6g_mb_lib.t6g(sch_1):page149_i21@pure_quanta.q_cap(chips)',
 P_PATH='@t6g_mb_lib.t6g(sch_1):page172_i21@pure_quanta.q_cap(chips)',
 PATH='I21',
 DRAWING='@T6G_MB_LIB.T6G(SCH_1):PAGE149',
 TOLERANCE='5%',
 MATERIAL='NPO',
 PHYS_PAGE='172',
 XY='(-800,3775)',
 ROT='0',
 VER='1',
 PACK_TYPE='0402',
 LOCATION='C1512',
 CDS_LIB='pure_quanta',
 CDS_PART_NAME='Q_CAP_0402-33PF,50V,5%,NPO,TMP_QCH03306JB04',
 VOLTAGE='50V',
 PART_NUMBER='TMP_QCH03306JB04',
 VALUE='33PF',
 PRIM_FILE='./archive_libs/logical/q_cap/chips/chips.prt';

PART_NAME
 C1513 'Q_CAP_C0402-0.1UF,16V,10%,X7R,CH4103K1B08':;

SECTION_NUMBER 1
 '@T6G_MB_LIB.T6G(SCH_1):PAGE150_I69@PURE_QUANTA.Q_CAP(CHIPS)':
 C_PATH='@t6g_mb_lib.t6g(sch_1):page150_i69@pure_quanta.q_cap(chips)',
 P_PATH='@t6g_mb_lib.t6g(sch_1):page173_i69@pure_quanta.q_cap(chips)',
 PATH='I69',
 DRAWING='@T6G_MB_LIB.T6G(SCH_1):PAGE150',
 TOLERANCE='10%',
 MATERIAL='X7R',
 PHYS_PAGE='173',
 XY='(-6225,2700)',
 ROT='0',
 VER='1',
 PACK_TYPE='C0402',
 LOCATION='C1513',
 CDS_LIB='pure_quanta',
 CDS_PART_NAME='Q_CAP_C0402-0.1UF,16V,10%,X7R,CH4103K1B08',
 VOLTAGE='16V',
 PART_NUMBER='CH4103K1B08',
 VALUE='0.1UF',
 PRIM_FILE='./archive_libs/logical/q_cap/chips/chips.prt';

PART_NAME
 C1514 'Q_CAP_C0402-0.1UF,16V,10%,X7R,CH4103K1B08':;

SECTION_NUMBER 1
 '@T6G_MB_LIB.T6G(SCH_1):PAGE150_I19@PURE_QUANTA.Q_CAP(CHIPS)':
 C_PATH='@t6g_mb_lib.t6g(sch_1):page150_i19@pure_quanta.q_cap(chips)',
 P_PATH='@t6g_mb_lib.t6g(sch_1):page173_i19@pure_quanta.q_cap(chips)',
 PATH='I19',
 DRAWING='@T6G_MB_LIB.T6G(SCH_1):PAGE150',
 TOLERANCE='10%',
 MATERIAL='X7R',
 PHYS_PAGE='173',
 XY='(-6050,6100)',
 ROT='0',
 VER='1',
 PACK_TYPE='C0402',
 LOCATION='C1514',
 CDS_LIB='pure_quanta',
 CDS_PART_NAME='Q_CAP_C0402-0.1UF,16V,10%,X7R,CH4103K1B08',
 VOLTAGE='16V',
 PART_NUMBER='CH4103K1B08',
 VALUE='0.1UF',
 PRIM_FILE='./archive_libs/logical/q_cap/chips/chips.prt';

PART_NAME
 C1515 'Q_CAP_C0402-0.1UF,16V,10%,X7R,CH4103K1B08':;

SECTION_NUMBER 1
 '@T6G_MB_LIB.T6G(SCH_1):PAGE150_I43@PURE_QUANTA.Q_CAP(CHIPS)':
 C_PATH='@t6g_mb_lib.t6g(sch_1):page150_i43@pure_quanta.q_cap(chips)',
 P_PATH='@t6g_mb_lib.t6g(sch_1):page173_i43@pure_quanta.q_cap(chips)',
 PATH='I43',
 DRAWING='@T6G_MB_LIB.T6G(SCH_1):PAGE150',
 TOLERANCE='10%',
 MATERIAL='X7R',
 PHYS_PAGE='173',
 XY='(-6050,4450)',
 ROT='0',
 VER='1',
 PACK_TYPE='C0402',
 LOCATION='C1515',
 CDS_LIB='pure_quanta',
 CDS_PART_NAME='Q_CAP_C0402-0.1UF,16V,10%,X7R,CH4103K1B08',
 VOLTAGE='16V',
 PART_NUMBER='CH4103K1B08',
 VALUE='0.1UF',
 PRIM_FILE='./archive_libs/logical/q_cap/chips/chips.prt';

PART_NAME
 C1516 'Q_CAP_C0402-0.1UF,16V,10%,X7R,CH4103K1B08':;

SECTION_NUMBER 1
 '@T6G_MB_LIB.T6G(SCH_1):PAGE150_I14@PURE_QUANTA.Q_CAP(CHIPS)':
 C_PATH='@t6g_mb_lib.t6g(sch_1):page150_i14@pure_quanta.q_cap(chips)',
 P_PATH='@t6g_mb_lib.t6g(sch_1):page173_i14@pure_quanta.q_cap(chips)',
 PATH='I14',
 DRAWING='@T6G_MB_LIB.T6G(SCH_1):PAGE150',
 TOLERANCE='10%',
 MATERIAL='X7R',
 PHYS_PAGE='173',
 XY='(-4650,6100)',
 ROT='0',
 VER='1',
 PACK_TYPE='C0402',
 LOCATION='C1516',
 CDS_LIB='pure_quanta',
 CDS_PART_NAME='Q_CAP_C0402-0.1UF,16V,10%,X7R,CH4103K1B08',
 VOLTAGE='16V',
 PART_NUMBER='CH4103K1B08',
 VALUE='0.1UF',
 PRIM_FILE='./archive_libs/logical/q_cap/chips/chips.prt';

PART_NAME
 C1517 'Q_CAP_C0402-0.1UF,16V,10%,X7R,CH4103K1B08':;

SECTION_NUMBER 1
 '@T6G_MB_LIB.T6G(SCH_1):PAGE150_I40@PURE_QUANTA.Q_CAP(CHIPS)':
 C_PATH='@t6g_mb_lib.t6g(sch_1):page150_i40@pure_quanta.q_cap(chips)',
 P_PATH='@t6g_mb_lib.t6g(sch_1):page173_i40@pure_quanta.q_cap(chips)',
 PATH='I40',
 DRAWING='@T6G_MB_LIB.T6G(SCH_1):PAGE150',
 TOLERANCE='10%',
 MATERIAL='X7R',
 PHYS_PAGE='173',
 XY='(-4650,4400)',
 ROT='0',
 VER='1',
 PACK_TYPE='C0402',
 LOCATION='C1517',
 CDS_LIB='pure_quanta',
 CDS_PART_NAME='Q_CAP_C0402-0.1UF,16V,10%,X7R,CH4103K1B08',
 VOLTAGE='16V',
 PART_NUMBER='CH4103K1B08',
 VALUE='0.1UF',
 PRIM_FILE='./archive_libs/logical/q_cap/chips/chips.prt';

PART_NAME
 C1518 'Q_CAP_C0402-0.1UF,16V,10%,X7R,CH4103K1B08':;

SECTION_NUMBER 1
 '@T6G_MB_LIB.T6G(SCH_1):PAGE150_I66@PURE_QUANTA.Q_CAP(CHIPS)':
 C_PATH='@t6g_mb_lib.t6g(sch_1):page150_i66@pure_quanta.q_cap(chips)',
 P_PATH='@t6g_mb_lib.t6g(sch_1):page173_i66@pure_quanta.q_cap(chips)',
 PATH='I66',
 DRAWING='@T6G_MB_LIB.T6G(SCH_1):PAGE150',
 TOLERANCE='10%',
 MATERIAL='X7R',
 PHYS_PAGE='173',
 XY='(-4650,2700)',
 ROT='0',
 VER='1',
 PACK_TYPE='C0402',
 LOCATION='C1518',
 CDS_LIB='pure_quanta',
 CDS_PART_NAME='Q_CAP_C0402-0.1UF,16V,10%,X7R,CH4103K1B08',
 VOLTAGE='16V',
 PART_NUMBER='CH4103K1B08',
 VALUE='0.1UF',
 PRIM_FILE='./archive_libs/logical/q_cap/chips/chips.prt';

PART_NAME
 C1519 'Q_CAP_C0402-0.1UF,16V,10%,X7R,CH4103K1B08':;

SECTION_NUMBER 1
 '@T6G_MB_LIB.T6G(SCH_1):PAGE151_I15@PURE_QUANTA.Q_CAP(CHIPS)':
 C_PATH='@t6g_mb_lib.t6g(sch_1):page151_i15@pure_quanta.q_cap(chips)',
 P_PATH='@t6g_mb_lib.t6g(sch_1):page174_i15@pure_quanta.q_cap(chips)',
 PATH='I15',
 DRAWING='@T6G_MB_LIB.T6G(SCH_1):PAGE151',
 TOLERANCE='10%',
 MATERIAL='X7R',
 PHYS_PAGE='174',
 XY='(-5725,6125)',
 ROT='0',
 VER='1',
 PACK_TYPE='C0402',
 LOCATION='C1519',
 CDS_LIB='pure_quanta',
 CDS_PART_NAME='Q_CAP_C0402-0.1UF,16V,10%,X7R,CH4103K1B08',
 VOLTAGE='16V',
 PART_NUMBER='CH4103K1B08',
 VALUE='0.1UF',
 PRIM_FILE='./archive_libs/logical/q_cap/chips/chips.prt';

PART_NAME
 C1520 'Q_CAP_C0402-0.01UF,50V,10%,EMPTY,CH31006KB18':;

SECTION_NUMBER 1
 '@T6G_MB_LIB.T6G(SCH_1):PAGE151_I4@PURE_QUANTA.Q_CAP(CHIPS)':
 C_PATH='@t6g_mb_lib.t6g(sch_1):page151_i4@pure_quanta.q_cap(chips)',
 P_PATH='@t6g_mb_lib.t6g(sch_1):page174_i4@pure_quanta.q_cap(chips)',
 PATH='I4',
 DRAWING='@T6G_MB_LIB.T6G(SCH_1):PAGE151',
 TOLERANCE='10%',
 MATERIAL='EMPTY',
 PHYS_PAGE='174',
 XY='(-4900,5625)',
 ROT='0',
 VER='1',
 PACK_TYPE='C0402',
 LOCATION='C1520',
 CDS_LIB='pure_quanta',
 CDS_PART_NAME='Q_CAP_C0402-0.01UF,50V,10%,EMPTY,CH31006KB18',
 VOLTAGE='50V',
 PART_NUMBER='CH31006KB18',
 VALUE='0.01UF',
 PRIM_FILE='./archive_libs/logical/q_cap/chips/chips.prt';

PART_NAME
 C1521 'Q_CAP_C0402-0.1UF,16V,10%,X7R,CH4103K1B08':;

SECTION_NUMBER 1
 '@T6G_MB_LIB.T6G(SCH_1):PAGE151_I22@PURE_QUANTA.Q_CAP(CHIPS)':
 C_PATH='@t6g_mb_lib.t6g(sch_1):page151_i22@pure_quanta.q_cap(chips)',
 P_PATH='@t6g_mb_lib.t6g(sch_1):page174_i22@pure_quanta.q_cap(chips)',
 PATH='I22',
 DRAWING='@T6G_MB_LIB.T6G(SCH_1):PAGE151',
 TOLERANCE='10%',
 MATERIAL='X7R',
 PHYS_PAGE='174',
 XY='(-4000,4775)',
 ROT='0',
 VER='1',
 PACK_TYPE='C0402',
 LOCATION='C1521',
 CDS_LIB='pure_quanta',
 CDS_PART_NAME='Q_CAP_C0402-0.1UF,16V,10%,X7R,CH4103K1B08',
 VOLTAGE='16V',
 PART_NUMBER='CH4103K1B08',
 VALUE='0.1UF',
 PRIM_FILE='./archive_libs/logical/q_cap/chips/chips.prt';

PART_NAME
 C1522 'Q_CAP_C0402-0.1UF,16V,10%,X7R,CH4103K1B08':;

SECTION_NUMBER 1
 '@T6G_MB_LIB.T6G(SCH_1):PAGE151_I36@PURE_QUANTA.Q_CAP(CHIPS)':
 C_PATH='@t6g_mb_lib.t6g(sch_1):page151_i36@pure_quanta.q_cap(chips)',
 P_PATH='@t6g_mb_lib.t6g(sch_1):page174_i36@pure_quanta.q_cap(chips)',
 PATH='I36',
 DRAWING='@T6G_MB_LIB.T6G(SCH_1):PAGE151',
 TOLERANCE='10%',
 MATERIAL='X7R',
 PHYS_PAGE='174',
 XY='(-2150,4725)',
 ROT='0',
 VER='1',
 PACK_TYPE='C0402',
 LOCATION='C1522',
 CDS_LIB='pure_quanta',
 CDS_PART_NAME='Q_CAP_C0402-0.1UF,16V,10%,X7R,CH4103K1B08',
 VOLTAGE='16V',
 PART_NUMBER='CH4103K1B08',
 VALUE='0.1UF',
 PRIM_FILE='./archive_libs/logical/q_cap/chips/chips.prt';

PART_NAME
 C1523 'Q_CAP_C0402-0.1UF,16V,10%,X7R,CH4103K1B08':;

SECTION_NUMBER 1
 '@T6G_MB_LIB.T6G(SCH_1):PAGE151_I42@PURE_QUANTA.Q_CAP(CHIPS)':
 C_PATH='@t6g_mb_lib.t6g(sch_1):page151_i42@pure_quanta.q_cap(chips)',
 P_PATH='@t6g_mb_lib.t6g(sch_1):page174_i42@pure_quanta.q_cap(chips)',
 PATH='I42',
 DRAWING='@T6G_MB_LIB.T6G(SCH_1):PAGE151',
 TOLERANCE='10%',
 MATERIAL='X7R',
 PHYS_PAGE='174',
 XY='(-1000,3750)',
 ROT='0',
 VER='1',
 PACK_TYPE='C0402',
 LOCATION='C1523',
 CDS_LIB='pure_quanta',
 CDS_PART_NAME='Q_CAP_C0402-0.1UF,16V,10%,X7R,CH4103K1B08',
 VOLTAGE='16V',
 PART_NUMBER='CH4103K1B08',
 VALUE='0.1UF',
 PRIM_FILE='./archive_libs/logical/q_cap/chips/chips.prt';

PART_NAME
 C1524 'Q_CAP_DIFFBUS_C0201-DIFF BUS_0.22UF,6.3V,20%,X6S,SA':;

SECTION_NUMBER 1
 '@T6G_MB_LIB.T6G(SCH_1):PAGE355_I84@PURE_QUANTA.Q_CAP_DIFFBUS(CHIPS)':
 C_PATH='@t6g_mb_lib.t6g(sch_1):page355_i84@pure_quanta.q_cap_diffbus(chips)',
 P_PATH='@t6g_mb_lib.t6g(sch_1):page67_i84@pure_quanta.q_cap_diffbus(chips)',
 PATH='I84',
 DRAWING='@T6G_MB_LIB.T6G(SCH_1):PAGE355',
 PIN_NAMES_ROTATE='TRUE',
 TOLERANCE='20%',
 MATERIAL='X6S',
 PHYS_PAGE='67',
 XY='(-1500,3700)',
 ROT='2',
 VER='2',
 PACK_TYPE='C0201',
 LOCATION='C1524',
 CDS_LIB='pure_quanta',
 CDS_PART_NAME='Q_CAP_DIFFBUS_C0201-DIFF BUS_0.22UF,6.3V,20%,X6S,SA',
 VOLTAGE='6.3V',
 PART_NUMBER='SP_CH4221MEE01',
 VALUE='DIFF BUS_0.22UF',
 PRIM_FILE='./archive_libs/logical/q_cap_diffbus/chips/chips.prt';

PART_NAME
 C1525 'Q_CAP_DIFFBUS_C0201-DIFF BUS_0.22UF,6.3V,20%,X6S,SA':;

SECTION_NUMBER 1
 '@T6G_MB_LIB.T6G(SCH_1):PAGE355_I83@PURE_QUANTA.Q_CAP_DIFFBUS(CHIPS)':
 C_PATH='@t6g_mb_lib.t6g(sch_1):page355_i83@pure_quanta.q_cap_diffbus(chips)',
 P_PATH='@t6g_mb_lib.t6g(sch_1):page67_i83@pure_quanta.q_cap_diffbus(chips)',
 PATH='I83',
 DRAWING='@T6G_MB_LIB.T6G(SCH_1):PAGE355',
 PIN_NAMES_ROTATE='TRUE',
 TOLERANCE='20%',
 MATERIAL='X6S',
 PHYS_PAGE='67',
 XY='(-1500,3650)',
 ROT='2',
 VER='2',
 PACK_TYPE='C0201',
 LOCATION='C1525',
 CDS_LIB='pure_quanta',
 CDS_PART_NAME='Q_CAP_DIFFBUS_C0201-DIFF BUS_0.22UF,6.3V,20%,X6S,SA',
 VOLTAGE='6.3V',
 PART_NUMBER='SP_CH4221MEE01',
 VALUE='DIFF BUS_0.22UF',
 PRIM_FILE='./archive_libs/logical/q_cap_diffbus/chips/chips.prt';

PART_NAME
 C1526 'Q_CAP_DIFFBUS_C0201-DIFF BUS_0.22UF,6.3V,20%,X6S,SA':;

SECTION_NUMBER 1
 '@T6G_MB_LIB.T6G(SCH_1):PAGE355_I81@PURE_QUANTA.Q_CAP_DIFFBUS(CHIPS)':
 C_PATH='@t6g_mb_lib.t6g(sch_1):page355_i81@pure_quanta.q_cap_diffbus(chips)',
 P_PATH='@t6g_mb_lib.t6g(sch_1):page67_i81@pure_quanta.q_cap_diffbus(chips)',
 PATH='I81',
 DRAWING='@T6G_MB_LIB.T6G(SCH_1):PAGE355',
 PIN_NAMES_ROTATE='TRUE',
 TOLERANCE='20%',
 MATERIAL='X6S',
 PHYS_PAGE='67',
 XY='(-1500,3500)',
 ROT='2',
 VER='2',
 PACK_TYPE='C0201',
 LOCATION='C1526',
 CDS_LIB='pure_quanta',
 CDS_PART_NAME='Q_CAP_DIFFBUS_C0201-DIFF BUS_0.22UF,6.3V,20%,X6S,SA',
 VOLTAGE='6.3V',
 PART_NUMBER='SP_CH4221MEE01',
 VALUE='DIFF BUS_0.22UF',
 PRIM_FILE='./archive_libs/logical/q_cap_diffbus/chips/chips.prt';

PART_NAME
 C1527 'Q_CAP_DIFFBUS_C0201-DIFF BUS_0.22UF,6.3V,20%,X6S,SA':;

SECTION_NUMBER 1
 '@T6G_MB_LIB.T6G(SCH_1):PAGE355_I82@PURE_QUANTA.Q_CAP_DIFFBUS(CHIPS)':
 C_PATH='@t6g_mb_lib.t6g(sch_1):page355_i82@pure_quanta.q_cap_diffbus(chips)',
 P_PATH='@t6g_mb_lib.t6g(sch_1):page67_i82@pure_quanta.q_cap_diffbus(chips)',
 PATH='I82',
 DRAWING='@T6G_MB_LIB.T6G(SCH_1):PAGE355',
 PIN_NAMES_ROTATE='TRUE',
 TOLERANCE='20%',
 MATERIAL='X6S',
 PHYS_PAGE='67',
 XY='(-1500,3450)',
 ROT='2',
 VER='2',
 PACK_TYPE='C0201',
 LOCATION='C1527',
 CDS_LIB='pure_quanta',
 CDS_PART_NAME='Q_CAP_DIFFBUS_C0201-DIFF BUS_0.22UF,6.3V,20%,X6S,SA',
 VOLTAGE='6.3V',
 PART_NUMBER='SP_CH4221MEE01',
 VALUE='DIFF BUS_0.22UF',
 PRIM_FILE='./archive_libs/logical/q_cap_diffbus/chips/chips.prt';

PART_NAME
 C1528 'Q_CAP_DIFFBUS_C0201-DIFF BUS_0.22UF,6.3V,20%,X6S,SA':;

SECTION_NUMBER 1
 '@T6G_MB_LIB.T6G(SCH_1):PAGE355_I80@PURE_QUANTA.Q_CAP_DIFFBUS(CHIPS)':
 C_PATH='@t6g_mb_lib.t6g(sch_1):page355_i80@pure_quanta.q_cap_diffbus(chips)',
 P_PATH='@t6g_mb_lib.t6g(sch_1):page67_i80@pure_quanta.q_cap_diffbus(chips)',
 PATH='I80',
 DRAWING='@T6G_MB_LIB.T6G(SCH_1):PAGE355',
 PIN_NAMES_ROTATE='TRUE',
 TOLERANCE='20%',
 MATERIAL='X6S',
 PHYS_PAGE='67',
 XY='(-1500,3300)',
 ROT='2',
 VER='2',
 PACK_TYPE='C0201',
 LOCATION='C1528',
 CDS_LIB='pure_quanta',
 CDS_PART_NAME='Q_CAP_DIFFBUS_C0201-DIFF BUS_0.22UF,6.3V,20%,X6S,SA',
 VOLTAGE='6.3V',
 PART_NUMBER='SP_CH4221MEE01',
 VALUE='DIFF BUS_0.22UF',
 PRIM_FILE='./archive_libs/logical/q_cap_diffbus/chips/chips.prt';

PART_NAME
 C1529 'Q_CAP_DIFFBUS_C0201-DIFF BUS_0.22UF,6.3V,20%,X6S,SA':;

SECTION_NUMBER 1
 '@T6G_MB_LIB.T6G(SCH_1):PAGE355_I79@PURE_QUANTA.Q_CAP_DIFFBUS(CHIPS)':
 C_PATH='@t6g_mb_lib.t6g(sch_1):page355_i79@pure_quanta.q_cap_diffbus(chips)',
 P_PATH='@t6g_mb_lib.t6g(sch_1):page67_i79@pure_quanta.q_cap_diffbus(chips)',
 PATH='I79',
 DRAWING='@T6G_MB_LIB.T6G(SCH_1):PAGE355',
 PIN_NAMES_ROTATE='TRUE',
 TOLERANCE='20%',
 MATERIAL='X6S',
 PHYS_PAGE='67',
 XY='(-1500,3250)',
 ROT='2',
 VER='2',
 PACK_TYPE='C0201',
 LOCATION='C1529',
 CDS_LIB='pure_quanta',
 CDS_PART_NAME='Q_CAP_DIFFBUS_C0201-DIFF BUS_0.22UF,6.3V,20%,X6S,SA',
 VOLTAGE='6.3V',
 PART_NUMBER='SP_CH4221MEE01',
 VALUE='DIFF BUS_0.22UF',
 PRIM_FILE='./archive_libs/logical/q_cap_diffbus/chips/chips.prt';

PART_NAME
 C1530 'Q_CAP_DIFFBUS_C0201-DIFF BUS_0.22UF,6.3V,20%,X6S,SA':;

SECTION_NUMBER 1
 '@T6G_MB_LIB.T6G(SCH_1):PAGE355_I78@PURE_QUANTA.Q_CAP_DIFFBUS(CHIPS)':
 C_PATH='@t6g_mb_lib.t6g(sch_1):page355_i78@pure_quanta.q_cap_diffbus(chips)',
 P_PATH='@t6g_mb_lib.t6g(sch_1):page67_i78@pure_quanta.q_cap_diffbus(chips)',
 PATH='I78',
 DRAWING='@T6G_MB_LIB.T6G(SCH_1):PAGE355',
 PIN_NAMES_ROTATE='TRUE',
 TOLERANCE='20%',
 MATERIAL='X6S',
 PHYS_PAGE='67',
 XY='(-1500,3100)',
 ROT='2',
 VER='2',
 PACK_TYPE='C0201',
 LOCATION='C1530',
 CDS_LIB='pure_quanta',
 CDS_PART_NAME='Q_CAP_DIFFBUS_C0201-DIFF BUS_0.22UF,6.3V,20%,X6S,SA',
 VOLTAGE='6.3V',
 PART_NUMBER='SP_CH4221MEE01',
 VALUE='DIFF BUS_0.22UF',
 PRIM_FILE='./archive_libs/logical/q_cap_diffbus/chips/chips.prt';

PART_NAME
 C1531 'Q_CAP_DIFFBUS_C0201-DIFF BUS_0.22UF,6.3V,20%,X6S,SA':;

SECTION_NUMBER 1
 '@T6G_MB_LIB.T6G(SCH_1):PAGE355_I77@PURE_QUANTA.Q_CAP_DIFFBUS(CHIPS)':
 C_PATH='@t6g_mb_lib.t6g(sch_1):page355_i77@pure_quanta.q_cap_diffbus(chips)',
 P_PATH='@t6g_mb_lib.t6g(sch_1):page67_i77@pure_quanta.q_cap_diffbus(chips)',
 PATH='I77',
 DRAWING='@T6G_MB_LIB.T6G(SCH_1):PAGE355',
 PIN_NAMES_ROTATE='TRUE',
 TOLERANCE='20%',
 MATERIAL='X6S',
 PHYS_PAGE='67',
 XY='(-1500,3050)',
 ROT='2',
 VER='2',
 PACK_TYPE='C0201',
 LOCATION='C1531',
 CDS_LIB='pure_quanta',
 CDS_PART_NAME='Q_CAP_DIFFBUS_C0201-DIFF BUS_0.22UF,6.3V,20%,X6S,SA',
 VOLTAGE='6.3V',
 PART_NUMBER='SP_CH4221MEE01',
 VALUE='DIFF BUS_0.22UF',
 PRIM_FILE='./archive_libs/logical/q_cap_diffbus/chips/chips.prt';

PART_NAME
 C1532 'Q_CAP_DIFFBUS_C0201-DIFF BUS_0.22UF,6.3V,20%,X6S,SA':;

SECTION_NUMBER 1
 '@T6G_MB_LIB.T6G(SCH_1):PAGE355_I76@PURE_QUANTA.Q_CAP_DIFFBUS(CHIPS)':
 C_PATH='@t6g_mb_lib.t6g(sch_1):page355_i76@pure_quanta.q_cap_diffbus(chips)',
 P_PATH='@t6g_mb_lib.t6g(sch_1):page67_i76@pure_quanta.q_cap_diffbus(chips)',
 PATH='I76',
 DRAWING='@T6G_MB_LIB.T6G(SCH_1):PAGE355',
 PIN_NAMES_ROTATE='TRUE',
 TOLERANCE='20%',
 MATERIAL='X6S',
 PHYS_PAGE='67',
 XY='(-1525,2875)',
 ROT='2',
 VER='2',
 PACK_TYPE='C0201',
 LOCATION='C1532',
 CDS_LIB='pure_quanta',
 CDS_PART_NAME='Q_CAP_DIFFBUS_C0201-DIFF BUS_0.22UF,6.3V,20%,X6S,SA',
 VOLTAGE='6.3V',
 PART_NUMBER='SP_CH4221MEE01',
 VALUE='DIFF BUS_0.22UF',
 PRIM_FILE='./archive_libs/logical/q_cap_diffbus/chips/chips.prt';

PART_NAME
 C1533 'Q_CAP_DIFFBUS_C0201-DIFF BUS_0.22UF,6.3V,20%,X6S,SA':;

SECTION_NUMBER 1
 '@T6G_MB_LIB.T6G(SCH_1):PAGE355_I75@PURE_QUANTA.Q_CAP_DIFFBUS(CHIPS)':
 C_PATH='@t6g_mb_lib.t6g(sch_1):page355_i75@pure_quanta.q_cap_diffbus(chips)',
 P_PATH='@t6g_mb_lib.t6g(sch_1):page67_i75@pure_quanta.q_cap_diffbus(chips)',
 PATH='I75',
 DRAWING='@T6G_MB_LIB.T6G(SCH_1):PAGE355',
 PIN_NAMES_ROTATE='TRUE',
 TOLERANCE='20%',
 MATERIAL='X6S',
 PHYS_PAGE='67',
 XY='(-1525,2825)',
 ROT='2',
 VER='2',
 PACK_TYPE='C0201',
 LOCATION='C1533',
 CDS_LIB='pure_quanta',
 CDS_PART_NAME='Q_CAP_DIFFBUS_C0201-DIFF BUS_0.22UF,6.3V,20%,X6S,SA',
 VOLTAGE='6.3V',
 PART_NUMBER='SP_CH4221MEE01',
 VALUE='DIFF BUS_0.22UF',
 PRIM_FILE='./archive_libs/logical/q_cap_diffbus/chips/chips.prt';

PART_NAME
 C1534 'Q_CAP_DIFFBUS_C0201-DIFF BUS_0.22UF,6.3V,20%,X6S,SA':;

SECTION_NUMBER 1
 '@T6G_MB_LIB.T6G(SCH_1):PAGE355_I74@PURE_QUANTA.Q_CAP_DIFFBUS(CHIPS)':
 C_PATH='@t6g_mb_lib.t6g(sch_1):page355_i74@pure_quanta.q_cap_diffbus(chips)',
 P_PATH='@t6g_mb_lib.t6g(sch_1):page67_i74@pure_quanta.q_cap_diffbus(chips)',
 PATH='I74',
 DRAWING='@T6G_MB_LIB.T6G(SCH_1):PAGE355',
 PIN_NAMES_ROTATE='TRUE',
 TOLERANCE='20%',
 MATERIAL='X6S',
 PHYS_PAGE='67',
 XY='(-1525,2675)',
 ROT='2',
 VER='2',
 PACK_TYPE='C0201',
 LOCATION='C1534',
 CDS_LIB='pure_quanta',
 CDS_PART_NAME='Q_CAP_DIFFBUS_C0201-DIFF BUS_0.22UF,6.3V,20%,X6S,SA',
 VOLTAGE='6.3V',
 PART_NUMBER='SP_CH4221MEE01',
 VALUE='DIFF BUS_0.22UF',
 PRIM_FILE='./archive_libs/logical/q_cap_diffbus/chips/chips.prt';

PART_NAME
 C1535 'Q_CAP_DIFFBUS_C0201-DIFF BUS_0.22UF,6.3V,20%,X6S,SA':;

SECTION_NUMBER 1
 '@T6G_MB_LIB.T6G(SCH_1):PAGE355_I73@PURE_QUANTA.Q_CAP_DIFFBUS(CHIPS)':
 C_PATH='@t6g_mb_lib.t6g(sch_1):page355_i73@pure_quanta.q_cap_diffbus(chips)',
 P_PATH='@t6g_mb_lib.t6g(sch_1):page67_i73@pure_quanta.q_cap_diffbus(chips)',
 PATH='I73',
 DRAWING='@T6G_MB_LIB.T6G(SCH_1):PAGE355',
 PIN_NAMES_ROTATE='TRUE',
 TOLERANCE='20%',
 MATERIAL='X6S',
 PHYS_PAGE='67',
 XY='(-1525,2625)',
 ROT='2',
 VER='2',
 PACK_TYPE='C0201',
 LOCATION='C1535',
 CDS_LIB='pure_quanta',
 CDS_PART_NAME='Q_CAP_DIFFBUS_C0201-DIFF BUS_0.22UF,6.3V,20%,X6S,SA',
 VOLTAGE='6.3V',
 PART_NUMBER='SP_CH4221MEE01',
 VALUE='DIFF BUS_0.22UF',
 PRIM_FILE='./archive_libs/logical/q_cap_diffbus/chips/chips.prt';

PART_NAME
 C1536 'Q_CAP_DIFFBUS_C0201-DIFF BUS_0.22UF,6.3V,20%,X6S,SA':;

SECTION_NUMBER 1
 '@T6G_MB_LIB.T6G(SCH_1):PAGE355_I72@PURE_QUANTA.Q_CAP_DIFFBUS(CHIPS)':
 C_PATH='@t6g_mb_lib.t6g(sch_1):page355_i72@pure_quanta.q_cap_diffbus(chips)',
 P_PATH='@t6g_mb_lib.t6g(sch_1):page67_i72@pure_quanta.q_cap_diffbus(chips)',
 PATH='I72',
 DRAWING='@T6G_MB_LIB.T6G(SCH_1):PAGE355',
 PIN_NAMES_ROTATE='TRUE',
 TOLERANCE='20%',
 MATERIAL='X6S',
 PHYS_PAGE='67',
 XY='(-1525,2475)',
 ROT='2',
 VER='2',
 PACK_TYPE='C0201',
 LOCATION='C1536',
 CDS_LIB='pure_quanta',
 CDS_PART_NAME='Q_CAP_DIFFBUS_C0201-DIFF BUS_0.22UF,6.3V,20%,X6S,SA',
 VOLTAGE='6.3V',
 PART_NUMBER='SP_CH4221MEE01',
 VALUE='DIFF BUS_0.22UF',
 PRIM_FILE='./archive_libs/logical/q_cap_diffbus/chips/chips.prt';

PART_NAME
 C1537 'Q_CAP_DIFFBUS_C0201-DIFF BUS_0.22UF,6.3V,20%,X6S,SA':;

SECTION_NUMBER 1
 '@T6G_MB_LIB.T6G(SCH_1):PAGE355_I71@PURE_QUANTA.Q_CAP_DIFFBUS(CHIPS)':
 C_PATH='@t6g_mb_lib.t6g(sch_1):page355_i71@pure_quanta.q_cap_diffbus(chips)',
 P_PATH='@t6g_mb_lib.t6g(sch_1):page67_i71@pure_quanta.q_cap_diffbus(chips)',
 PATH='I71',
 DRAWING='@T6G_MB_LIB.T6G(SCH_1):PAGE355',
 PIN_NAMES_ROTATE='TRUE',
 TOLERANCE='20%',
 MATERIAL='X6S',
 PHYS_PAGE='67',
 XY='(-1525,2425)',
 ROT='2',
 VER='2',
 PACK_TYPE='C0201',
 LOCATION='C1537',
 CDS_LIB='pure_quanta',
 CDS_PART_NAME='Q_CAP_DIFFBUS_C0201-DIFF BUS_0.22UF,6.3V,20%,X6S,SA',
 VOLTAGE='6.3V',
 PART_NUMBER='SP_CH4221MEE01',
 VALUE='DIFF BUS_0.22UF',
 PRIM_FILE='./archive_libs/logical/q_cap_diffbus/chips/chips.prt';

PART_NAME
 C1538 'Q_CAP_DIFFBUS_C0201-DIFF BUS_0.22UF,6.3V,20%,X6S,SA':;

SECTION_NUMBER 1
 '@T6G_MB_LIB.T6G(SCH_1):PAGE355_I70@PURE_QUANTA.Q_CAP_DIFFBUS(CHIPS)':
 C_PATH='@t6g_mb_lib.t6g(sch_1):page355_i70@pure_quanta.q_cap_diffbus(chips)',
 P_PATH='@t6g_mb_lib.t6g(sch_1):page67_i70@pure_quanta.q_cap_diffbus(chips)',
 PATH='I70',
 DRAWING='@T6G_MB_LIB.T6G(SCH_1):PAGE355',
 PIN_NAMES_ROTATE='TRUE',
 TOLERANCE='20%',
 MATERIAL='X6S',
 PHYS_PAGE='67',
 XY='(-1525,2275)',
 ROT='2',
 VER='2',
 PACK_TYPE='C0201',
 LOCATION='C1538',
 CDS_LIB='pure_quanta',
 CDS_PART_NAME='Q_CAP_DIFFBUS_C0201-DIFF BUS_0.22UF,6.3V,20%,X6S,SA',
 VOLTAGE='6.3V',
 PART_NUMBER='SP_CH4221MEE01',
 VALUE='DIFF BUS_0.22UF',
 PRIM_FILE='./archive_libs/logical/q_cap_diffbus/chips/chips.prt';

PART_NAME
 C1539 'Q_CAP_DIFFBUS_C0201-DIFF BUS_0.22UF,6.3V,20%,X6S,SA':;

SECTION_NUMBER 1
 '@T6G_MB_LIB.T6G(SCH_1):PAGE355_I69@PURE_QUANTA.Q_CAP_DIFFBUS(CHIPS)':
 C_PATH='@t6g_mb_lib.t6g(sch_1):page355_i69@pure_quanta.q_cap_diffbus(chips)',
 P_PATH='@t6g_mb_lib.t6g(sch_1):page67_i69@pure_quanta.q_cap_diffbus(chips)',
 PATH='I69',
 DRAWING='@T6G_MB_LIB.T6G(SCH_1):PAGE355',
 PIN_NAMES_ROTATE='TRUE',
 TOLERANCE='20%',
 MATERIAL='X6S',
 PHYS_PAGE='67',
 XY='(-1525,2225)',
 ROT='2',
 VER='2',
 PACK_TYPE='C0201',
 LOCATION='C1539',
 CDS_LIB='pure_quanta',
 CDS_PART_NAME='Q_CAP_DIFFBUS_C0201-DIFF BUS_0.22UF,6.3V,20%,X6S,SA',
 VOLTAGE='6.3V',
 PART_NUMBER='SP_CH4221MEE01',
 VALUE='DIFF BUS_0.22UF',
 PRIM_FILE='./archive_libs/logical/q_cap_diffbus/chips/chips.prt';

PART_NAME
 C1540 'Q_CAP_DIFFBUS_C0201-DIFF BUS_0.22UF,6.3V,20%,X6S,SA':;

SECTION_NUMBER 1
 '@T6G_MB_LIB.T6G(SCH_1):PAGE355_I68@PURE_QUANTA.Q_CAP_DIFFBUS(CHIPS)':
 C_PATH='@t6g_mb_lib.t6g(sch_1):page355_i68@pure_quanta.q_cap_diffbus(chips)',
 P_PATH='@t6g_mb_lib.t6g(sch_1):page67_i68@pure_quanta.q_cap_diffbus(chips)',
 PATH='I68',
 DRAWING='@T6G_MB_LIB.T6G(SCH_1):PAGE355',
 PIN_NAMES_ROTATE='TRUE',
 TOLERANCE='20%',
 MATERIAL='X6S',
 PHYS_PAGE='67',
 XY='(-1525,2075)',
 ROT='2',
 VER='2',
 PACK_TYPE='C0201',
 LOCATION='C1540',
 CDS_LIB='pure_quanta',
 CDS_PART_NAME='Q_CAP_DIFFBUS_C0201-DIFF BUS_0.22UF,6.3V,20%,X6S,SA',
 VOLTAGE='6.3V',
 PART_NUMBER='SP_CH4221MEE01',
 VALUE='DIFF BUS_0.22UF',
 PRIM_FILE='./archive_libs/logical/q_cap_diffbus/chips/chips.prt';

PART_NAME
 C1541 'Q_CAP_DIFFBUS_C0201-DIFF BUS_0.22UF,6.3V,20%,X6S,SA':;

SECTION_NUMBER 1
 '@T6G_MB_LIB.T6G(SCH_1):PAGE355_I67@PURE_QUANTA.Q_CAP_DIFFBUS(CHIPS)':
 C_PATH='@t6g_mb_lib.t6g(sch_1):page355_i67@pure_quanta.q_cap_diffbus(chips)',
 P_PATH='@t6g_mb_lib.t6g(sch_1):page67_i67@pure_quanta.q_cap_diffbus(chips)',
 PATH='I67',
 DRAWING='@T6G_MB_LIB.T6G(SCH_1):PAGE355',
 PIN_NAMES_ROTATE='TRUE',
 TOLERANCE='20%',
 MATERIAL='X6S',
 PHYS_PAGE='67',
 XY='(-1525,2025)',
 ROT='2',
 VER='2',
 PACK_TYPE='C0201',
 LOCATION='C1541',
 CDS_LIB='pure_quanta',
 CDS_PART_NAME='Q_CAP_DIFFBUS_C0201-DIFF BUS_0.22UF,6.3V,20%,X6S,SA',
 VOLTAGE='6.3V',
 PART_NUMBER='SP_CH4221MEE01',
 VALUE='DIFF BUS_0.22UF',
 PRIM_FILE='./archive_libs/logical/q_cap_diffbus/chips/chips.prt';

PART_NAME
 C1542 'Q_CAP_DIFFBUS_C0201-DIFF BUS_0.22UF,6.3V,20%,X6S,SA':;

SECTION_NUMBER 1
 '@T6G_MB_LIB.T6G(SCH_1):PAGE355_I58@PURE_QUANTA.Q_CAP_DIFFBUS(CHIPS)':
 C_PATH='@t6g_mb_lib.t6g(sch_1):page355_i58@pure_quanta.q_cap_diffbus(chips)',
 P_PATH='@t6g_mb_lib.t6g(sch_1):page67_i58@pure_quanta.q_cap_diffbus(chips)',
 PATH='I58',
 DRAWING='@T6G_MB_LIB.T6G(SCH_1):PAGE355',
 PIN_NAMES_ROTATE='TRUE',
 TOLERANCE='20%',
 MATERIAL='X6S',
 PHYS_PAGE='67',
 XY='(-1525,1875)',
 ROT='2',
 VER='2',
 PACK_TYPE='C0201',
 LOCATION='C1542',
 CDS_LIB='pure_quanta',
 CDS_PART_NAME='Q_CAP_DIFFBUS_C0201-DIFF BUS_0.22UF,6.3V,20%,X6S,SA',
 VOLTAGE='6.3V',
 PART_NUMBER='SP_CH4221MEE01',
 VALUE='DIFF BUS_0.22UF',
 PRIM_FILE='./archive_libs/logical/q_cap_diffbus/chips/chips.prt';

PART_NAME
 C1543 'Q_CAP_DIFFBUS_C0201-DIFF BUS_0.22UF,6.3V,20%,X6S,SA':;

SECTION_NUMBER 1
 '@T6G_MB_LIB.T6G(SCH_1):PAGE355_I57@PURE_QUANTA.Q_CAP_DIFFBUS(CHIPS)':
 C_PATH='@t6g_mb_lib.t6g(sch_1):page355_i57@pure_quanta.q_cap_diffbus(chips)',
 P_PATH='@t6g_mb_lib.t6g(sch_1):page67_i57@pure_quanta.q_cap_diffbus(chips)',
 PATH='I57',
 DRAWING='@T6G_MB_LIB.T6G(SCH_1):PAGE355',
 PIN_NAMES_ROTATE='TRUE',
 TOLERANCE='20%',
 MATERIAL='X6S',
 PHYS_PAGE='67',
 XY='(-1525,1825)',
 ROT='2',
 VER='2',
 PACK_TYPE='C0201',
 LOCATION='C1543',
 CDS_LIB='pure_quanta',
 CDS_PART_NAME='Q_CAP_DIFFBUS_C0201-DIFF BUS_0.22UF,6.3V,20%,X6S,SA',
 VOLTAGE='6.3V',
 PART_NUMBER='SP_CH4221MEE01',
 VALUE='DIFF BUS_0.22UF',
 PRIM_FILE='./archive_libs/logical/q_cap_diffbus/chips/chips.prt';

PART_NAME
 C1544 'Q_CAP_DIFFBUS_C0201-DIFF BUS_0.22UF,6.3V,20%,X6S,SA':;

SECTION_NUMBER 1
 '@T6G_MB_LIB.T6G(SCH_1):PAGE355_I55@PURE_QUANTA.Q_CAP_DIFFBUS(CHIPS)':
 C_PATH='@t6g_mb_lib.t6g(sch_1):page355_i55@pure_quanta.q_cap_diffbus(chips)',
 P_PATH='@t6g_mb_lib.t6g(sch_1):page67_i55@pure_quanta.q_cap_diffbus(chips)',
 PATH='I55',
 DRAWING='@T6G_MB_LIB.T6G(SCH_1):PAGE355',
 PIN_NAMES_ROTATE='TRUE',
 TOLERANCE='20%',
 MATERIAL='X6S',
 PHYS_PAGE='67',
 XY='(-1525,1675)',
 ROT='2',
 VER='2',
 PACK_TYPE='C0201',
 LOCATION='C1544',
 CDS_LIB='pure_quanta',
 CDS_PART_NAME='Q_CAP_DIFFBUS_C0201-DIFF BUS_0.22UF,6.3V,20%,X6S,SA',
 VOLTAGE='6.3V',
 PART_NUMBER='SP_CH4221MEE01',
 VALUE='DIFF BUS_0.22UF',
 PRIM_FILE='./archive_libs/logical/q_cap_diffbus/chips/chips.prt';

PART_NAME
 C1545 'Q_CAP_DIFFBUS_C0201-DIFF BUS_0.22UF,6.3V,20%,X6S,SA':;

SECTION_NUMBER 1
 '@T6G_MB_LIB.T6G(SCH_1):PAGE355_I56@PURE_QUANTA.Q_CAP_DIFFBUS(CHIPS)':
 C_PATH='@t6g_mb_lib.t6g(sch_1):page355_i56@pure_quanta.q_cap_diffbus(chips)',
 P_PATH='@t6g_mb_lib.t6g(sch_1):page67_i56@pure_quanta.q_cap_diffbus(chips)',
 PATH='I56',
 DRAWING='@T6G_MB_LIB.T6G(SCH_1):PAGE355',
 PIN_NAMES_ROTATE='TRUE',
 TOLERANCE='20%',
 MATERIAL='X6S',
 PHYS_PAGE='67',
 XY='(-1525,1625)',
 ROT='2',
 VER='2',
 PACK_TYPE='C0201',
 LOCATION='C1545',
 CDS_LIB='pure_quanta',
 CDS_PART_NAME='Q_CAP_DIFFBUS_C0201-DIFF BUS_0.22UF,6.3V,20%,X6S,SA',
 VOLTAGE='6.3V',
 PART_NUMBER='SP_CH4221MEE01',
 VALUE='DIFF BUS_0.22UF',
 PRIM_FILE='./archive_libs/logical/q_cap_diffbus/chips/chips.prt';

PART_NAME
 C1546 'Q_CAP_DIFFBUS_C0201-DIFF BUS_0.22UF,6.3V,20%,X6S,SA':;

SECTION_NUMBER 1
 '@T6G_MB_LIB.T6G(SCH_1):PAGE355_I54@PURE_QUANTA.Q_CAP_DIFFBUS(CHIPS)':
 C_PATH='@t6g_mb_lib.t6g(sch_1):page355_i54@pure_quanta.q_cap_diffbus(chips)',
 P_PATH='@t6g_mb_lib.t6g(sch_1):page67_i54@pure_quanta.q_cap_diffbus(chips)',
 PATH='I54',
 DRAWING='@T6G_MB_LIB.T6G(SCH_1):PAGE355',
 PIN_NAMES_ROTATE='TRUE',
 TOLERANCE='20%',
 MATERIAL='X6S',
 PHYS_PAGE='67',
 XY='(-1525,1475)',
 ROT='2',
 VER='2',
 PACK_TYPE='C0201',
 LOCATION='C1546',
 CDS_LIB='pure_quanta',
 CDS_PART_NAME='Q_CAP_DIFFBUS_C0201-DIFF BUS_0.22UF,6.3V,20%,X6S,SA',
 VOLTAGE='6.3V',
 PART_NUMBER='SP_CH4221MEE01',
 VALUE='DIFF BUS_0.22UF',
 PRIM_FILE='./archive_libs/logical/q_cap_diffbus/chips/chips.prt';

PART_NAME
 C1547 'Q_CAP_DIFFBUS_C0201-DIFF BUS_0.22UF,6.3V,20%,X6S,SA':;

SECTION_NUMBER 1
 '@T6G_MB_LIB.T6G(SCH_1):PAGE355_I53@PURE_QUANTA.Q_CAP_DIFFBUS(CHIPS)':
 C_PATH='@t6g_mb_lib.t6g(sch_1):page355_i53@pure_quanta.q_cap_diffbus(chips)',
 P_PATH='@t6g_mb_lib.t6g(sch_1):page67_i53@pure_quanta.q_cap_diffbus(chips)',
 PATH='I53',
 DRAWING='@T6G_MB_LIB.T6G(SCH_1):PAGE355',
 PIN_NAMES_ROTATE='TRUE',
 TOLERANCE='20%',
 MATERIAL='X6S',
 PHYS_PAGE='67',
 XY='(-1525,1425)',
 ROT='2',
 VER='2',
 PACK_TYPE='C0201',
 LOCATION='C1547',
 CDS_LIB='pure_quanta',
 CDS_PART_NAME='Q_CAP_DIFFBUS_C0201-DIFF BUS_0.22UF,6.3V,20%,X6S,SA',
 VOLTAGE='6.3V',
 PART_NUMBER='SP_CH4221MEE01',
 VALUE='DIFF BUS_0.22UF',
 PRIM_FILE='./archive_libs/logical/q_cap_diffbus/chips/chips.prt';

PART_NAME
 C1548 'Q_CAP_DIFFBUS_C0201-DIFF BUS_0.22UF,6.3V,20%,X6S,SA':;

SECTION_NUMBER 1
 '@T6G_MB_LIB.T6G(SCH_1):PAGE353_I273@PURE_QUANTA.Q_CAP_DIFFBUS(CHIPS)':
 C_PATH='@t6g_mb_lib.t6g(sch_1):page353_i273@pure_quanta.q_cap_diffbus(chips)',
 P_PATH='@t6g_mb_lib.t6g(sch_1):page65_i273@pure_quanta.q_cap_diffbus(chips)',
 PATH='I273',
 DRAWING='@T6G_MB_LIB.T6G(SCH_1):PAGE353',
 PIN_NAMES_ROTATE='TRUE',
 TOLERANCE='20%',
 MATERIAL='X6S',
 PHYS_PAGE='65',
 XY='(-925,3575)',
 ROT='2',
 VER='2',
 PACK_TYPE='C0201',
 LOCATION='C1548',
 CDS_LIB='pure_quanta',
 CDS_PART_NAME='Q_CAP_DIFFBUS_C0201-DIFF BUS_0.22UF,6.3V,20%,X6S,SA',
 VOLTAGE='6.3V',
 PART_NUMBER='SP_CH4221MEE01',
 VALUE='DIFF BUS_0.22UF',
 PRIM_FILE='./archive_libs/logical/q_cap_diffbus/chips/chips.prt';

PART_NAME
 C1549 'Q_CAP_DIFFBUS_C0201-DIFF BUS_0.22UF,6.3V,20%,X6S,SA':;

SECTION_NUMBER 1
 '@T6G_MB_LIB.T6G(SCH_1):PAGE353_I274@PURE_QUANTA.Q_CAP_DIFFBUS(CHIPS)':
 C_PATH='@t6g_mb_lib.t6g(sch_1):page353_i274@pure_quanta.q_cap_diffbus(chips)',
 P_PATH='@t6g_mb_lib.t6g(sch_1):page65_i274@pure_quanta.q_cap_diffbus(chips)',
 PATH='I274',
 DRAWING='@T6G_MB_LIB.T6G(SCH_1):PAGE353',
 PIN_NAMES_ROTATE='TRUE',
 TOLERANCE='20%',
 MATERIAL='X6S',
 PHYS_PAGE='65',
 XY='(-925,3525)',
 ROT='2',
 VER='2',
 PACK_TYPE='C0201',
 LOCATION='C1549',
 CDS_LIB='pure_quanta',
 CDS_PART_NAME='Q_CAP_DIFFBUS_C0201-DIFF BUS_0.22UF,6.3V,20%,X6S,SA',
 VOLTAGE='6.3V',
 PART_NUMBER='SP_CH4221MEE01',
 VALUE='DIFF BUS_0.22UF',
 PRIM_FILE='./archive_libs/logical/q_cap_diffbus/chips/chips.prt';

PART_NAME
 C1550 'Q_CAP_DIFFBUS_C0201-DIFF BUS_0.22UF,6.3V,20%,X6S,SA':;

SECTION_NUMBER 1
 '@T6G_MB_LIB.T6G(SCH_1):PAGE353_I272@PURE_QUANTA.Q_CAP_DIFFBUS(CHIPS)':
 C_PATH='@t6g_mb_lib.t6g(sch_1):page353_i272@pure_quanta.q_cap_diffbus(chips)',
 P_PATH='@t6g_mb_lib.t6g(sch_1):page65_i272@pure_quanta.q_cap_diffbus(chips)',
 PATH='I272',
 DRAWING='@T6G_MB_LIB.T6G(SCH_1):PAGE353',
 PIN_NAMES_ROTATE='TRUE',
 TOLERANCE='20%',
 MATERIAL='X6S',
 PHYS_PAGE='65',
 XY='(-925,3375)',
 ROT='2',
 VER='2',
 PACK_TYPE='C0201',
 LOCATION='C1550',
 CDS_LIB='pure_quanta',
 CDS_PART_NAME='Q_CAP_DIFFBUS_C0201-DIFF BUS_0.22UF,6.3V,20%,X6S,SA',
 VOLTAGE='6.3V',
 PART_NUMBER='SP_CH4221MEE01',
 VALUE='DIFF BUS_0.22UF',
 PRIM_FILE='./archive_libs/logical/q_cap_diffbus/chips/chips.prt';

PART_NAME
 C1552 'Q_CAP_DIFFBUS_C0201-DIFF BUS_0.22UF,6.3V,20%,X6S,SA':;

SECTION_NUMBER 1
 '@T6G_MB_LIB.T6G(SCH_1):PAGE353_I270@PURE_QUANTA.Q_CAP_DIFFBUS(CHIPS)':
 C_PATH='@t6g_mb_lib.t6g(sch_1):page353_i270@pure_quanta.q_cap_diffbus(chips)',
 P_PATH='@t6g_mb_lib.t6g(sch_1):page65_i270@pure_quanta.q_cap_diffbus(chips)',
 PATH='I270',
 DRAWING='@T6G_MB_LIB.T6G(SCH_1):PAGE353',
 PIN_NAMES_ROTATE='TRUE',
 TOLERANCE='20%',
 MATERIAL='X6S',
 PHYS_PAGE='65',
 XY='(-925,3175)',
 ROT='2',
 VER='2',
 PACK_TYPE='C0201',
 LOCATION='C1552',
 CDS_LIB='pure_quanta',
 CDS_PART_NAME='Q_CAP_DIFFBUS_C0201-DIFF BUS_0.22UF,6.3V,20%,X6S,SA',
 VOLTAGE='6.3V',
 PART_NUMBER='SP_CH4221MEE01',
 VALUE='DIFF BUS_0.22UF',
 PRIM_FILE='./archive_libs/logical/q_cap_diffbus/chips/chips.prt';

PART_NAME
 C1553 'Q_CAP_DIFFBUS_C0201-DIFF BUS_0.22UF,6.3V,20%,X6S,SA':;

SECTION_NUMBER 1
 '@T6G_MB_LIB.T6G(SCH_1):PAGE353_I269@PURE_QUANTA.Q_CAP_DIFFBUS(CHIPS)':
 C_PATH='@t6g_mb_lib.t6g(sch_1):page353_i269@pure_quanta.q_cap_diffbus(chips)',
 P_PATH='@t6g_mb_lib.t6g(sch_1):page65_i269@pure_quanta.q_cap_diffbus(chips)',
 PATH='I269',
 DRAWING='@T6G_MB_LIB.T6G(SCH_1):PAGE353',
 PIN_NAMES_ROTATE='TRUE',
 TOLERANCE='20%',
 MATERIAL='X6S',
 PHYS_PAGE='65',
 XY='(-925,3125)',
 ROT='2',
 VER='2',
 PACK_TYPE='C0201',
 LOCATION='C1553',
 CDS_LIB='pure_quanta',
 CDS_PART_NAME='Q_CAP_DIFFBUS_C0201-DIFF BUS_0.22UF,6.3V,20%,X6S,SA',
 VOLTAGE='6.3V',
 PART_NUMBER='SP_CH4221MEE01',
 VALUE='DIFF BUS_0.22UF',
 PRIM_FILE='./archive_libs/logical/q_cap_diffbus/chips/chips.prt';

PART_NAME
 C1554 'Q_CAP_C0402-0.1UF,16V,10%,X7R,CH4103K1B08':;

SECTION_NUMBER 1
 '@T6G_MB_LIB.T6G(SCH_1):PAGE148_I293@PURE_QUANTA.Q_CAP(CHIPS)':
 C_PATH='@t6g_mb_lib.t6g(sch_1):page148_i293@pure_quanta.q_cap(chips)',
 P_PATH='@t6g_mb_lib.t6g(sch_1):page171_i293@pure_quanta.q_cap(chips)',
 PATH='I293',
 DRAWING='@T6G_MB_LIB.T6G(SCH_1):PAGE148',
 TOLERANCE='10%',
 MATERIAL='X7R',
 PHYS_PAGE='171',
 XY='(-5475,4575)',
 ROT='0',
 VER='1',
 PACK_TYPE='C0402',
 LOCATION='C1554',
 CDS_LIB='pure_quanta',
 CDS_PART_NAME='Q_CAP_C0402-0.1UF,16V,10%,X7R,CH4103K1B08',
 VOLTAGE='16V',
 PART_NUMBER='CH4103K1B08',
 VALUE='0.1UF',
 PRIM_FILE='./archive_libs/logical/q_cap/chips/chips.prt';

PART_NAME
 C1555 'Q_CAP_DIFFBUS_C0201-DIFF BUS_0.22UF,6.3V,20%,X6S,SA':;

SECTION_NUMBER 1
 '@T6G_MB_LIB.T6G(SCH_1):PAGE353_I267@PURE_QUANTA.Q_CAP_DIFFBUS(CHIPS)':
 C_PATH='@t6g_mb_lib.t6g(sch_1):page353_i267@pure_quanta.q_cap_diffbus(chips)',
 P_PATH='@t6g_mb_lib.t6g(sch_1):page65_i267@pure_quanta.q_cap_diffbus(chips)',
 PATH='I267',
 DRAWING='@T6G_MB_LIB.T6G(SCH_1):PAGE353',
 PIN_NAMES_ROTATE='TRUE',
 TOLERANCE='20%',
 MATERIAL='X6S',
 PHYS_PAGE='65',
 XY='(-925,2925)',
 ROT='2',
 VER='2',
 PACK_TYPE='C0201',
 LOCATION='C1555',
 CDS_LIB='pure_quanta',
 CDS_PART_NAME='Q_CAP_DIFFBUS_C0201-DIFF BUS_0.22UF,6.3V,20%,X6S,SA',
 VOLTAGE='6.3V',
 PART_NUMBER='SP_CH4221MEE01',
 VALUE='DIFF BUS_0.22UF',
 PRIM_FILE='./archive_libs/logical/q_cap_diffbus/chips/chips.prt';

PART_NAME
 C1556 'Q_CAP_DIFFBUS_C0201-DIFF BUS_0.22UF,6.3V,20%,X6S,SA':;

SECTION_NUMBER 1
 '@T6G_MB_LIB.T6G(SCH_1):PAGE353_I265@PURE_QUANTA.Q_CAP_DIFFBUS(CHIPS)':
 C_PATH='@t6g_mb_lib.t6g(sch_1):page353_i265@pure_quanta.q_cap_diffbus(chips)',
 P_PATH='@t6g_mb_lib.t6g(sch_1):page65_i265@pure_quanta.q_cap_diffbus(chips)',
 PATH='I265',
 DRAWING='@T6G_MB_LIB.T6G(SCH_1):PAGE353',
 PIN_NAMES_ROTATE='TRUE',
 TOLERANCE='20%',
 MATERIAL='X6S',
 PHYS_PAGE='65',
 XY='(-925,2775)',
 ROT='2',
 VER='2',
 PACK_TYPE='C0201',
 LOCATION='C1556',
 CDS_LIB='pure_quanta',
 CDS_PART_NAME='Q_CAP_DIFFBUS_C0201-DIFF BUS_0.22UF,6.3V,20%,X6S,SA',
 VOLTAGE='6.3V',
 PART_NUMBER='SP_CH4221MEE01',
 VALUE='DIFF BUS_0.22UF',
 PRIM_FILE='./archive_libs/logical/q_cap_diffbus/chips/chips.prt';

PART_NAME
 C1557 'Q_CAP_DIFFBUS_C0201-DIFF BUS_0.22UF,6.3V,20%,X6S,SA':;

SECTION_NUMBER 1
 '@T6G_MB_LIB.T6G(SCH_1):PAGE353_I266@PURE_QUANTA.Q_CAP_DIFFBUS(CHIPS)':
 C_PATH='@t6g_mb_lib.t6g(sch_1):page353_i266@pure_quanta.q_cap_diffbus(chips)',
 P_PATH='@t6g_mb_lib.t6g(sch_1):page65_i266@pure_quanta.q_cap_diffbus(chips)',
 PATH='I266',
 DRAWING='@T6G_MB_LIB.T6G(SCH_1):PAGE353',
 PIN_NAMES_ROTATE='TRUE',
 TOLERANCE='20%',
 MATERIAL='X6S',
 PHYS_PAGE='65',
 XY='(-925,2725)',
 ROT='2',
 VER='2',
 PACK_TYPE='C0201',
 LOCATION='C1557',
 CDS_LIB='pure_quanta',
 CDS_PART_NAME='Q_CAP_DIFFBUS_C0201-DIFF BUS_0.22UF,6.3V,20%,X6S,SA',
 VOLTAGE='6.3V',
 PART_NUMBER='SP_CH4221MEE01',
 VALUE='DIFF BUS_0.22UF',
 PRIM_FILE='./archive_libs/logical/q_cap_diffbus/chips/chips.prt';

PART_NAME
 C1558 'Q_CAP_DIFFBUS_C0201-DIFF BUS_0.22UF,6.3V,20%,X6S,SA':;

SECTION_NUMBER 1
 '@T6G_MB_LIB.T6G(SCH_1):PAGE353_I264@PURE_QUANTA.Q_CAP_DIFFBUS(CHIPS)':
 C_PATH='@t6g_mb_lib.t6g(sch_1):page353_i264@pure_quanta.q_cap_diffbus(chips)',
 P_PATH='@t6g_mb_lib.t6g(sch_1):page65_i264@pure_quanta.q_cap_diffbus(chips)',
 PATH='I264',
 DRAWING='@T6G_MB_LIB.T6G(SCH_1):PAGE353',
 PIN_NAMES_ROTATE='TRUE',
 TOLERANCE='20%',
 MATERIAL='X6S',
 PHYS_PAGE='65',
 XY='(-925,2575)',
 ROT='2',
 VER='2',
 PACK_TYPE='C0201',
 LOCATION='C1558',
 CDS_LIB='pure_quanta',
 CDS_PART_NAME='Q_CAP_DIFFBUS_C0201-DIFF BUS_0.22UF,6.3V,20%,X6S,SA',
 VOLTAGE='6.3V',
 PART_NUMBER='SP_CH4221MEE01',
 VALUE='DIFF BUS_0.22UF',
 PRIM_FILE='./archive_libs/logical/q_cap_diffbus/chips/chips.prt';

PART_NAME
 C1559 'Q_CAP_DIFFBUS_C0201-DIFF BUS_0.22UF,6.3V,20%,X6S,SA':;

SECTION_NUMBER 1
 '@T6G_MB_LIB.T6G(SCH_1):PAGE353_I263@PURE_QUANTA.Q_CAP_DIFFBUS(CHIPS)':
 C_PATH='@t6g_mb_lib.t6g(sch_1):page353_i263@pure_quanta.q_cap_diffbus(chips)',
 P_PATH='@t6g_mb_lib.t6g(sch_1):page65_i263@pure_quanta.q_cap_diffbus(chips)',
 PATH='I263',
 DRAWING='@T6G_MB_LIB.T6G(SCH_1):PAGE353',
 PIN_NAMES_ROTATE='TRUE',
 TOLERANCE='20%',
 MATERIAL='X6S',
 PHYS_PAGE='65',
 XY='(-925,2525)',
 ROT='2',
 VER='2',
 PACK_TYPE='C0201',
 LOCATION='C1559',
 CDS_LIB='pure_quanta',
 CDS_PART_NAME='Q_CAP_DIFFBUS_C0201-DIFF BUS_0.22UF,6.3V,20%,X6S,SA',
 VOLTAGE='6.3V',
 PART_NUMBER='SP_CH4221MEE01',
 VALUE='DIFF BUS_0.22UF',
 PRIM_FILE='./archive_libs/logical/q_cap_diffbus/chips/chips.prt';

PART_NAME
 C1560 'Q_CAP_DIFFBUS_C0201-DIFF BUS_0.22UF,6.3V,20%,X6S,SA':;

SECTION_NUMBER 1
 '@T6G_MB_LIB.T6G(SCH_1):PAGE353_I262@PURE_QUANTA.Q_CAP_DIFFBUS(CHIPS)':
 C_PATH='@t6g_mb_lib.t6g(sch_1):page353_i262@pure_quanta.q_cap_diffbus(chips)',
 P_PATH='@t6g_mb_lib.t6g(sch_1):page65_i262@pure_quanta.q_cap_diffbus(chips)',
 PATH='I262',
 DRAWING='@T6G_MB_LIB.T6G(SCH_1):PAGE353',
 PIN_NAMES_ROTATE='TRUE',
 TOLERANCE='20%',
 MATERIAL='X6S',
 PHYS_PAGE='65',
 XY='(-925,2375)',
 ROT='2',
 VER='2',
 PACK_TYPE='C0201',
 LOCATION='C1560',
 CDS_LIB='pure_quanta',
 CDS_PART_NAME='Q_CAP_DIFFBUS_C0201-DIFF BUS_0.22UF,6.3V,20%,X6S,SA',
 VOLTAGE='6.3V',
 PART_NUMBER='SP_CH4221MEE01',
 VALUE='DIFF BUS_0.22UF',
 PRIM_FILE='./archive_libs/logical/q_cap_diffbus/chips/chips.prt';

PART_NAME
 C1561 'Q_CAP_0402-0.1UF,25V,10%,EMPTY,CH4104K1B00':;

SECTION_NUMBER 1
 '@T6G_MB_LIB.T6G(SCH_1):PAGE372_I96@PURE_QUANTA.Q_CAP(CHIPS)':
 C_PATH='@t6g_mb_lib.t6g(sch_1):page372_i96@pure_quanta.q_cap(chips)',
 P_PATH='@t6g_mb_lib.t6g(sch_1):page268_i96@pure_quanta.q_cap(chips)',
 PATH='I96',
 DRAWING='@T6G_MB_LIB.T6G(SCH_1):PAGE372',
 TOLERANCE='10%',
 MATERIAL='EMPTY',
 PHYS_PAGE='268',
 XY='(-5050,5550)',
 ROT='0',
 VER='1',
 PACK_TYPE='0402',
 LOCATION='C1561',
 CDS_LIB='pure_quanta',
 CDS_PART_NAME='Q_CAP_0402-0.1UF,25V,10%,EMPTY,CH4104K1B00',
 VOLTAGE='25V',
 PART_NUMBER='CH4104K1B00',
 VALUE='0.1UF',
 PRIM_FILE='./archive_libs/logical/q_cap/chips/chips.prt';

PART_NAME
 C1563 'Q_CAP_C0402-0.1UF,16V,10%,X7R,CH4103K1B08':;

SECTION_NUMBER 1
 '@T6G_MB_LIB.T6G(SCH_1):PAGE156_I95@PURE_QUANTA.Q_CAP(CHIPS)':
 C_PATH='@t6g_mb_lib.t6g(sch_1):page156_i95@pure_quanta.q_cap(chips)',
 P_PATH='@t6g_mb_lib.t6g(sch_1):page187_i95@pure_quanta.q_cap(chips)',
 PATH='I95',
 DRAWING='@T6G_MB_LIB.T6G(SCH_1):PAGE156',
 TOLERANCE='10%',
 MATERIAL='X7R',
 PHYS_PAGE='187',
 XY='(-6250,4825)',
 ROT='0',
 VER='1',
 PACK_TYPE='C0402',
 LOCATION='C1563',
 CDS_LIB='pure_quanta',
 CDS_PART_NAME='Q_CAP_C0402-0.1UF,16V,10%,X7R,CH4103K1B08',
 VOLTAGE='16V',
 PART_NUMBER='CH4103K1B08',
 VALUE='0.1UF',
 PRIM_FILE='./archive_libs/logical/q_cap/chips/chips.prt';

PART_NAME
 C1564 'Q_CAP_C0402-1UF,25V,10%,X6S,CH5104KEB02':;

SECTION_NUMBER 1
 '@T6G_MB_LIB.T6G(SCH_1):PAGE156_I118@PURE_QUANTA.Q_CAP(CHIPS)':
 C_PATH='@t6g_mb_lib.t6g(sch_1):page156_i118@pure_quanta.q_cap(chips)',
 P_PATH='@t6g_mb_lib.t6g(sch_1):page187_i118@pure_quanta.q_cap(chips)',
 PATH='I118',
 DRAWING='@T6G_MB_LIB.T6G(SCH_1):PAGE156',
 TOLERANCE='10%',
 MATERIAL='X6S',
 PHYS_PAGE='187',
 XY='(-3575,6775)',
 ROT='0',
 VER='1',
 PACK_TYPE='C0402',
 LOCATION='C1564',
 CDS_LIB='pure_quanta',
 CDS_PART_NAME='Q_CAP_C0402-1UF,25V,10%,X6S,CH5104KEB02',
 VOLTAGE='25V',
 PART_NUMBER='CH5104KEB02',
 VALUE='1UF',
 PRIM_FILE='./archive_libs/logical/q_cap/chips/chips.prt';

PART_NAME
 C1565 'Q_CAP_DIFFBUS_C0201-DIFF BUS_0.22UF,6.3V,20%,X6S,SA':;

SECTION_NUMBER 1
 '@T6G_MB_LIB.T6G(SCH_1):PAGE353_I241@PURE_QUANTA.Q_CAP_DIFFBUS(CHIPS)':
 C_PATH='@t6g_mb_lib.t6g(sch_1):page353_i241@pure_quanta.q_cap_diffbus(chips)',
 P_PATH='@t6g_mb_lib.t6g(sch_1):page65_i241@pure_quanta.q_cap_diffbus(chips)',
 PATH='I241',
 DRAWING='@T6G_MB_LIB.T6G(SCH_1):PAGE353',
 PIN_NAMES_ROTATE='TRUE',
 TOLERANCE='20%',
 MATERIAL='X6S',
 PHYS_PAGE='65',
 XY='(-925,1550)',
 ROT='2',
 VER='2',
 PACK_TYPE='C0201',
 LOCATION='C1565',
 CDS_LIB='pure_quanta',
 CDS_PART_NAME='Q_CAP_DIFFBUS_C0201-DIFF BUS_0.22UF,6.3V,20%,X6S,SA',
 VOLTAGE='6.3V',
 PART_NUMBER='SP_CH4221MEE01',
 VALUE='DIFF BUS_0.22UF',
 PRIM_FILE='./archive_libs/logical/q_cap_diffbus/chips/chips.prt';

PART_NAME
 C1566 'Q_CAP_DIFFBUS_C0201-DIFF BUS_0.22UF,6.3V,20%,X6S,SA':;

SECTION_NUMBER 1
 '@T6G_MB_LIB.T6G(SCH_1):PAGE353_I240@PURE_QUANTA.Q_CAP_DIFFBUS(CHIPS)':
 C_PATH='@t6g_mb_lib.t6g(sch_1):page353_i240@pure_quanta.q_cap_diffbus(chips)',
 P_PATH='@t6g_mb_lib.t6g(sch_1):page65_i240@pure_quanta.q_cap_diffbus(chips)',
 PATH='I240',
 DRAWING='@T6G_MB_LIB.T6G(SCH_1):PAGE353',
 PIN_NAMES_ROTATE='TRUE',
 TOLERANCE='20%',
 MATERIAL='X6S',
 PHYS_PAGE='65',
 XY='(-925,1400)',
 ROT='2',
 VER='2',
 PACK_TYPE='C0201',
 LOCATION='C1566',
 CDS_LIB='pure_quanta',
 CDS_PART_NAME='Q_CAP_DIFFBUS_C0201-DIFF BUS_0.22UF,6.3V,20%,X6S,SA',
 VOLTAGE='6.3V',
 PART_NUMBER='SP_CH4221MEE01',
 VALUE='DIFF BUS_0.22UF',
 PRIM_FILE='./archive_libs/logical/q_cap_diffbus/chips/chips.prt';

PART_NAME
 C1567 'Q_CAP_C0402-1UF,25V,10%,X6S,CH5104KEB02':;

SECTION_NUMBER 1
 '@T6G_MB_LIB.T6G(SCH_1):PAGE156_I125@PURE_QUANTA.Q_CAP(CHIPS)':
 C_PATH='@t6g_mb_lib.t6g(sch_1):page156_i125@pure_quanta.q_cap(chips)',
 P_PATH='@t6g_mb_lib.t6g(sch_1):page187_i125@pure_quanta.q_cap(chips)',
 PATH='I125',
 DRAWING='@T6G_MB_LIB.T6G(SCH_1):PAGE156',
 TOLERANCE='10%',
 MATERIAL='X6S',
 PHYS_PAGE='187',
 XY='(-2075,6275)',
 ROT='0',
 VER='1',
 PACK_TYPE='C0402',
 LOCATION='C1567',
 CDS_LIB='pure_quanta',
 CDS_PART_NAME='Q_CAP_C0402-1UF,25V,10%,X6S,CH5104KEB02',
 VOLTAGE='25V',
 PART_NUMBER='CH5104KEB02',
 VALUE='1UF',
 PRIM_FILE='./archive_libs/logical/q_cap/chips/chips.prt';

PART_NAME
 C1568 'Q_CAP_DIFFBUS_C0201-DIFF BUS_0.22UF,6.3V,20%,X6S,SA':;

SECTION_NUMBER 1
 '@T6G_MB_LIB.T6G(SCH_1):PAGE353_I238@PURE_QUANTA.Q_CAP_DIFFBUS(CHIPS)':
 C_PATH='@t6g_mb_lib.t6g(sch_1):page353_i238@pure_quanta.q_cap_diffbus(chips)',
 P_PATH='@t6g_mb_lib.t6g(sch_1):page65_i238@pure_quanta.q_cap_diffbus(chips)',
 PATH='I238',
 DRAWING='@T6G_MB_LIB.T6G(SCH_1):PAGE353',
 PIN_NAMES_ROTATE='TRUE',
 TOLERANCE='20%',
 MATERIAL='X6S',
 PHYS_PAGE='65',
 XY='(-925,1200)',
 ROT='2',
 VER='2',
 PACK_TYPE='C0201',
 LOCATION='C1568',
 CDS_LIB='pure_quanta',
 CDS_PART_NAME='Q_CAP_DIFFBUS_C0201-DIFF BUS_0.22UF,6.3V,20%,X6S,SA',
 VOLTAGE='6.3V',
 PART_NUMBER='SP_CH4221MEE01',
 VALUE='DIFF BUS_0.22UF',
 PRIM_FILE='./archive_libs/logical/q_cap_diffbus/chips/chips.prt';

PART_NAME
 C1569 'Q_CAP_DIFFBUS_C0201-DIFF BUS_0.22UF,6.3V,20%,X6S,SA':;

SECTION_NUMBER 1
 '@T6G_MB_LIB.T6G(SCH_1):PAGE353_I237@PURE_QUANTA.Q_CAP_DIFFBUS(CHIPS)':
 C_PATH='@t6g_mb_lib.t6g(sch_1):page353_i237@pure_quanta.q_cap_diffbus(chips)',
 P_PATH='@t6g_mb_lib.t6g(sch_1):page65_i237@pure_quanta.q_cap_diffbus(chips)',
 PATH='I237',
 DRAWING='@T6G_MB_LIB.T6G(SCH_1):PAGE353',
 PIN_NAMES_ROTATE='TRUE',
 TOLERANCE='20%',
 MATERIAL='X6S',
 PHYS_PAGE='65',
 XY='(-925,1150)',
 ROT='2',
 VER='2',
 PACK_TYPE='C0201',
 LOCATION='C1569',
 CDS_LIB='pure_quanta',
 CDS_PART_NAME='Q_CAP_DIFFBUS_C0201-DIFF BUS_0.22UF,6.3V,20%,X6S,SA',
 VOLTAGE='6.3V',
 PART_NUMBER='SP_CH4221MEE01',
 VALUE='DIFF BUS_0.22UF',
 PRIM_FILE='./archive_libs/logical/q_cap_diffbus/chips/chips.prt';

PART_NAME
 C1570 'Q_CAP_DIFFBUS_C0201-DIFF BUS_0.22UF,6.3V,20%,X6S,SA':;

SECTION_NUMBER 1
 '@T6G_MB_LIB.T6G(SCH_1):PAGE353_I235@PURE_QUANTA.Q_CAP_DIFFBUS(CHIPS)':
 C_PATH='@t6g_mb_lib.t6g(sch_1):page353_i235@pure_quanta.q_cap_diffbus(chips)',
 P_PATH='@t6g_mb_lib.t6g(sch_1):page65_i235@pure_quanta.q_cap_diffbus(chips)',
 PATH='I235',
 DRAWING='@T6G_MB_LIB.T6G(SCH_1):PAGE353',
 PIN_NAMES_ROTATE='TRUE',
 TOLERANCE='20%',
 MATERIAL='X6S',
 PHYS_PAGE='65',
 XY='(-925,1000)',
 ROT='2',
 VER='2',
 PACK_TYPE='C0201',
 LOCATION='C1570',
 CDS_LIB='pure_quanta',
 CDS_PART_NAME='Q_CAP_DIFFBUS_C0201-DIFF BUS_0.22UF,6.3V,20%,X6S,SA',
 VOLTAGE='6.3V',
 PART_NUMBER='SP_CH4221MEE01',
 VALUE='DIFF BUS_0.22UF',
 PRIM_FILE='./archive_libs/logical/q_cap_diffbus/chips/chips.prt';

PART_NAME
 C1571 'Q_CAP_DIFFBUS_C0201-DIFF BUS_0.22UF,6.3V,20%,X6S,SA':;

SECTION_NUMBER 1
 '@T6G_MB_LIB.T6G(SCH_1):PAGE353_I236@PURE_QUANTA.Q_CAP_DIFFBUS(CHIPS)':
 C_PATH='@t6g_mb_lib.t6g(sch_1):page353_i236@pure_quanta.q_cap_diffbus(chips)',
 P_PATH='@t6g_mb_lib.t6g(sch_1):page65_i236@pure_quanta.q_cap_diffbus(chips)',
 PATH='I236',
 DRAWING='@T6G_MB_LIB.T6G(SCH_1):PAGE353',
 PIN_NAMES_ROTATE='TRUE',
 TOLERANCE='20%',
 MATERIAL='X6S',
 PHYS_PAGE='65',
 XY='(-925,950)',
 ROT='2',
 VER='2',
 PACK_TYPE='C0201',
 LOCATION='C1571',
 CDS_LIB='pure_quanta',
 CDS_PART_NAME='Q_CAP_DIFFBUS_C0201-DIFF BUS_0.22UF,6.3V,20%,X6S,SA',
 VOLTAGE='6.3V',
 PART_NUMBER='SP_CH4221MEE01',
 VALUE='DIFF BUS_0.22UF',
 PRIM_FILE='./archive_libs/logical/q_cap_diffbus/chips/chips.prt';

PART_NAME
 C1572 'Q_CAP_DIFFBUS_C0201-DIFF BUS_0.22UF,6.3V,20%,X6S,SA':;

SECTION_NUMBER 1
 '@T6G_MB_LIB.T6G(SCH_1):PAGE353_I234@PURE_QUANTA.Q_CAP_DIFFBUS(CHIPS)':
 C_PATH='@t6g_mb_lib.t6g(sch_1):page353_i234@pure_quanta.q_cap_diffbus(chips)',
 P_PATH='@t6g_mb_lib.t6g(sch_1):page65_i234@pure_quanta.q_cap_diffbus(chips)',
 PATH='I234',
 DRAWING='@T6G_MB_LIB.T6G(SCH_1):PAGE353',
 PIN_NAMES_ROTATE='TRUE',
 TOLERANCE='20%',
 MATERIAL='X6S',
 PHYS_PAGE='65',
 XY='(-925,800)',
 ROT='2',
 VER='2',
 PACK_TYPE='C0201',
 LOCATION='C1572',
 CDS_LIB='pure_quanta',
 CDS_PART_NAME='Q_CAP_DIFFBUS_C0201-DIFF BUS_0.22UF,6.3V,20%,X6S,SA',
 VOLTAGE='6.3V',
 PART_NUMBER='SP_CH4221MEE01',
 VALUE='DIFF BUS_0.22UF',
 PRIM_FILE='./archive_libs/logical/q_cap_diffbus/chips/chips.prt';

PART_NAME
 C1573 'Q_CAP_DIFFBUS_C0201-DIFF BUS_0.22UF,6.3V,20%,X6S,SA':;

SECTION_NUMBER 1
 '@T6G_MB_LIB.T6G(SCH_1):PAGE353_I233@PURE_QUANTA.Q_CAP_DIFFBUS(CHIPS)':
 C_PATH='@t6g_mb_lib.t6g(sch_1):page353_i233@pure_quanta.q_cap_diffbus(chips)',
 P_PATH='@t6g_mb_lib.t6g(sch_1):page65_i233@pure_quanta.q_cap_diffbus(chips)',
 PATH='I233',
 DRAWING='@T6G_MB_LIB.T6G(SCH_1):PAGE353',
 PIN_NAMES_ROTATE='TRUE',
 TOLERANCE='20%',
 MATERIAL='X6S',
 PHYS_PAGE='65',
 XY='(-925,750)',
 ROT='2',
 VER='2',
 PACK_TYPE='C0201',
 LOCATION='C1573',
 CDS_LIB='pure_quanta',
 CDS_PART_NAME='Q_CAP_DIFFBUS_C0201-DIFF BUS_0.22UF,6.3V,20%,X6S,SA',
 VOLTAGE='6.3V',
 PART_NUMBER='SP_CH4221MEE01',
 VALUE='DIFF BUS_0.22UF',
 PRIM_FILE='./archive_libs/logical/q_cap_diffbus/chips/chips.prt';

PART_NAME
 C1574 'Q_CAP_DIFFBUS_C0201-DIFF BUS_0.22UF,6.3V,20%,X6S,SA':;

SECTION_NUMBER 1
 '@T6G_MB_LIB.T6G(SCH_1):PAGE353_I232@PURE_QUANTA.Q_CAP_DIFFBUS(CHIPS)':
 C_PATH='@t6g_mb_lib.t6g(sch_1):page353_i232@pure_quanta.q_cap_diffbus(chips)',
 P_PATH='@t6g_mb_lib.t6g(sch_1):page65_i232@pure_quanta.q_cap_diffbus(chips)',
 PATH='I232',
 DRAWING='@T6G_MB_LIB.T6G(SCH_1):PAGE353',
 PIN_NAMES_ROTATE='TRUE',
 TOLERANCE='20%',
 MATERIAL='X6S',
 PHYS_PAGE='65',
 XY='(-925,600)',
 ROT='2',
 VER='2',
 PACK_TYPE='C0201',
 LOCATION='C1574',
 CDS_LIB='pure_quanta',
 CDS_PART_NAME='Q_CAP_DIFFBUS_C0201-DIFF BUS_0.22UF,6.3V,20%,X6S,SA',
 VOLTAGE='6.3V',
 PART_NUMBER='SP_CH4221MEE01',
 VALUE='DIFF BUS_0.22UF',
 PRIM_FILE='./archive_libs/logical/q_cap_diffbus/chips/chips.prt';

PART_NAME
 C1575 'Q_CAP_DIFFBUS_C0201-DIFF BUS_0.22UF,6.3V,20%,X6S,SA':;

SECTION_NUMBER 1
 '@T6G_MB_LIB.T6G(SCH_1):PAGE353_I231@PURE_QUANTA.Q_CAP_DIFFBUS(CHIPS)':
 C_PATH='@t6g_mb_lib.t6g(sch_1):page353_i231@pure_quanta.q_cap_diffbus(chips)',
 P_PATH='@t6g_mb_lib.t6g(sch_1):page65_i231@pure_quanta.q_cap_diffbus(chips)',
 PATH='I231',
 DRAWING='@T6G_MB_LIB.T6G(SCH_1):PAGE353',
 PIN_NAMES_ROTATE='TRUE',
 TOLERANCE='20%',
 MATERIAL='X6S',
 PHYS_PAGE='65',
 XY='(-925,550)',
 ROT='2',
 VER='2',
 PACK_TYPE='C0201',
 LOCATION='C1575',
 CDS_LIB='pure_quanta',
 CDS_PART_NAME='Q_CAP_DIFFBUS_C0201-DIFF BUS_0.22UF,6.3V,20%,X6S,SA',
 VOLTAGE='6.3V',
 PART_NUMBER='SP_CH4221MEE01',
 VALUE='DIFF BUS_0.22UF',
 PRIM_FILE='./archive_libs/logical/q_cap_diffbus/chips/chips.prt';

PART_NAME
 C1576 'Q_CAP_DIFFBUS_C0201-DIFF BUS_0.22UF,6.3V,20%,X6S,SA':;

SECTION_NUMBER 1
 '@T6G_MB_LIB.T6G(SCH_1):PAGE353_I312@PURE_QUANTA.Q_CAP_DIFFBUS(CHIPS)':
 C_PATH='@t6g_mb_lib.t6g(sch_1):page353_i312@pure_quanta.q_cap_diffbus(chips)',
 P_PATH='@t6g_mb_lib.t6g(sch_1):page65_i312@pure_quanta.q_cap_diffbus(chips)',
 PATH='I312',
 DRAWING='@T6G_MB_LIB.T6G(SCH_1):PAGE353',
 PIN_NAMES_ROTATE='TRUE',
 TOLERANCE='20%',
 MATERIAL='X6S',
 PHYS_PAGE='65',
 XY='(-925,400)',
 ROT='2',
 VER='2',
 PACK_TYPE='C0201',
 LOCATION='C1576',
 CDS_LIB='pure_quanta',
 CDS_PART_NAME='Q_CAP_DIFFBUS_C0201-DIFF BUS_0.22UF,6.3V,20%,X6S,SA',
 VOLTAGE='6.3V',
 PART_NUMBER='SP_CH4221MEE01',
 VALUE='DIFF BUS_0.22UF',
 PRIM_FILE='./archive_libs/logical/q_cap_diffbus/chips/chips.prt';

PART_NAME
 C1577 'Q_CAP_DIFFBUS_C0201-DIFF BUS_0.22UF,6.3V,20%,X6S,SA':;

SECTION_NUMBER 1
 '@T6G_MB_LIB.T6G(SCH_1):PAGE353_I311@PURE_QUANTA.Q_CAP_DIFFBUS(CHIPS)':
 C_PATH='@t6g_mb_lib.t6g(sch_1):page353_i311@pure_quanta.q_cap_diffbus(chips)',
 P_PATH='@t6g_mb_lib.t6g(sch_1):page65_i311@pure_quanta.q_cap_diffbus(chips)',
 PATH='I311',
 DRAWING='@T6G_MB_LIB.T6G(SCH_1):PAGE353',
 PIN_NAMES_ROTATE='TRUE',
 TOLERANCE='20%',
 MATERIAL='X6S',
 PHYS_PAGE='65',
 XY='(-925,350)',
 ROT='2',
 VER='2',
 PACK_TYPE='C0201',
 LOCATION='C1577',
 CDS_LIB='pure_quanta',
 CDS_PART_NAME='Q_CAP_DIFFBUS_C0201-DIFF BUS_0.22UF,6.3V,20%,X6S,SA',
 VOLTAGE='6.3V',
 PART_NUMBER='SP_CH4221MEE01',
 VALUE='DIFF BUS_0.22UF',
 PRIM_FILE='./archive_libs/logical/q_cap_diffbus/chips/chips.prt';

PART_NAME
 C1578 'Q_CAP_DIFFBUS_C0201-DIFF BUS_0.22UF,6.3V,20%,X6S,SA':;

SECTION_NUMBER 1
 '@T6G_MB_LIB.T6G(SCH_1):PAGE353_I230@PURE_QUANTA.Q_CAP_DIFFBUS(CHIPS)':
 C_PATH='@t6g_mb_lib.t6g(sch_1):page353_i230@pure_quanta.q_cap_diffbus(chips)',
 P_PATH='@t6g_mb_lib.t6g(sch_1):page65_i230@pure_quanta.q_cap_diffbus(chips)',
 PATH='I230',
 DRAWING='@T6G_MB_LIB.T6G(SCH_1):PAGE353',
 PIN_NAMES_ROTATE='TRUE',
 TOLERANCE='20%',
 MATERIAL='X6S',
 PHYS_PAGE='65',
 XY='(-925,200)',
 ROT='2',
 VER='2',
 PACK_TYPE='C0201',
 LOCATION='C1578',
 CDS_LIB='pure_quanta',
 CDS_PART_NAME='Q_CAP_DIFFBUS_C0201-DIFF BUS_0.22UF,6.3V,20%,X6S,SA',
 VOLTAGE='6.3V',
 PART_NUMBER='SP_CH4221MEE01',
 VALUE='DIFF BUS_0.22UF',
 PRIM_FILE='./archive_libs/logical/q_cap_diffbus/chips/chips.prt';

PART_NAME
 C1579 'Q_CAP_DIFFBUS_C0201-DIFF BUS_0.22UF,6.3V,20%,X6S,SA':;

SECTION_NUMBER 1
 '@T6G_MB_LIB.T6G(SCH_1):PAGE353_I229@PURE_QUANTA.Q_CAP_DIFFBUS(CHIPS)':
 C_PATH='@t6g_mb_lib.t6g(sch_1):page353_i229@pure_quanta.q_cap_diffbus(chips)',
 P_PATH='@t6g_mb_lib.t6g(sch_1):page65_i229@pure_quanta.q_cap_diffbus(chips)',
 PATH='I229',
 DRAWING='@T6G_MB_LIB.T6G(SCH_1):PAGE353',
 PIN_NAMES_ROTATE='TRUE',
 TOLERANCE='20%',
 MATERIAL='X6S',
 PHYS_PAGE='65',
 XY='(-925,150)',
 ROT='2',
 VER='2',
 PACK_TYPE='C0201',
 LOCATION='C1579',
 CDS_LIB='pure_quanta',
 CDS_PART_NAME='Q_CAP_DIFFBUS_C0201-DIFF BUS_0.22UF,6.3V,20%,X6S,SA',
 VOLTAGE='6.3V',
 PART_NUMBER='SP_CH4221MEE01',
 VALUE='DIFF BUS_0.22UF',
 PRIM_FILE='./archive_libs/logical/q_cap_diffbus/chips/chips.prt';

PART_NAME
 C1592 'Q_CAP_0402-0.1UF,25V,10%,X7R,CH4104K1B00':;

SECTION_NUMBER 1
 '@T6G_MB_LIB.T6G(SCH_1):PAGE297_I36@PURE_QUANTA.Q_CAP(CHIPS)':
 C_PATH='@t6g_mb_lib.t6g(sch_1):page297_i36@pure_quanta.q_cap(chips)',
 P_PATH='@t6g_mb_lib.t6g(sch_1):page145_i36@pure_quanta.q_cap(chips)',
 PATH='I36',
 DRAWING='@T6G_MB_LIB.T6G(SCH_1):PAGE297',
 TOLERANCE='10%',
 MATERIAL='X7R',
 PHYS_PAGE='145',
 XY='(1100,-350)',
 ROT='0',
 VER='1',
 PACK_TYPE='0402',
 LOCATION='C1592',
 CDS_LIB='pure_quanta',
 CDS_PART_NAME='Q_CAP_0402-0.1UF,25V,10%,X7R,CH4104K1B00',
 VOLTAGE='25V',
 PART_NUMBER='CH4104K1B00',
 VALUE='0.1UF',
 PRIM_FILE='./archive_libs/logical/q_cap/chips/chips.prt';

PART_NAME
 C1663 'Q_CAP_0402-0.1UF,25V,10%,X7R,CH4104K1B00':;

SECTION_NUMBER 1
 '@T6G_MB_LIB.T6G(SCH_1):PAGE337_I47@PURE_QUANTA.Q_CAP(CHIPS)':
 C_PATH='@t6g_mb_lib.t6g(sch_1):page337_i47@pure_quanta.q_cap(chips)',
 P_PATH='@t6g_mb_lib.t6g(sch_1):page133_i47@pure_quanta.q_cap(chips)',
 PATH='I47',
 DRAWING='@T6G_MB_LIB.T6G(SCH_1):PAGE337',
 TOLERANCE='10%',
 MATERIAL='X7R',
 PHYS_PAGE='133',
 XY='(-4325,4525)',
 ROT='0',
 VER='1',
 PACK_TYPE='0402',
 LOCATION='C1663',
 CDS_LIB='pure_quanta',
 CDS_PART_NAME='Q_CAP_0402-0.1UF,25V,10%,X7R,CH4104K1B00',
 VOLTAGE='25V',
 PART_NUMBER='CH4104K1B00',
 VALUE='0.1UF',
 PRIM_FILE='./archive_libs/logical/q_cap/chips/chips.prt';

PART_NAME
 C1707 'Q_CAP_0402-0.1UF,25V,10%,X7R,CH4104K1B00':;

SECTION_NUMBER 1
 '@T6G_MB_LIB.T6G(SCH_1):PAGE249_I52@PURE_QUANTA.Q_CAP(CHIPS)':
 C_PATH='@t6g_mb_lib.t6g(sch_1):page249_i52@pure_quanta.q_cap(chips)',
 P_PATH='@t6g_mb_lib.t6g(sch_1):page248_i52@pure_quanta.q_cap(chips)',
 PATH='I52',
 DRAWING='@T6G_MB_LIB.T6G(SCH_1):PAGE249',
 TOLERANCE='10%',
 MATERIAL='X7R',
 PHYS_PAGE='248',
 XY='(-5650,5725)',
 ROT='0',
 VER='1',
 PACK_TYPE='0402',
 LOCATION='C1707',
 CDS_LIB='pure_quanta',
 CDS_PART_NAME='Q_CAP_0402-0.1UF,25V,10%,X7R,CH4104K1B00',
 VOLTAGE='25V',
 PART_NUMBER='CH4104K1B00',
 VALUE='0.1UF',
 PRIM_FILE='./archive_libs/logical/q_cap/chips/chips.prt';

PART_NAME
 C1708 'Q_CAP_0402-0.1UF,25V,10%,X7R,CH4104K1B00':;

SECTION_NUMBER 1
 '@T6G_MB_LIB.T6G(SCH_1):PAGE249_I61@PURE_QUANTA.Q_CAP(CHIPS)':
 C_PATH='@t6g_mb_lib.t6g(sch_1):page249_i61@pure_quanta.q_cap(chips)',
 P_PATH='@t6g_mb_lib.t6g(sch_1):page248_i61@pure_quanta.q_cap(chips)',
 PATH='I61',
 DRAWING='@T6G_MB_LIB.T6G(SCH_1):PAGE249',
 TOLERANCE='10%',
 MATERIAL='X7R',
 PHYS_PAGE='248',
 XY='(-3275,1625)',
 ROT='0',
 VER='1',
 PACK_TYPE='0402',
 LOCATION='C1708',
 CDS_LIB='pure_quanta',
 CDS_PART_NAME='Q_CAP_0402-0.1UF,25V,10%,X7R,CH4104K1B00',
 VOLTAGE='25V',
 PART_NUMBER='CH4104K1B00',
 VALUE='0.1UF',
 PRIM_FILE='./archive_libs/logical/q_cap/chips/chips.prt';

PART_NAME
 C1713 'Q_CAP_0402-0.1UF,25V,10%,X7R,CH4104K1B00':;

SECTION_NUMBER 1
 '@T6G_MB_LIB.T6G(SCH_1):PAGE246_I61@PURE_QUANTA.Q_CAP(CHIPS)':
 C_PATH='@t6g_mb_lib.t6g(sch_1):page246_i61@pure_quanta.q_cap(chips)',
 P_PATH='@t6g_mb_lib.t6g(sch_1):page245_i61@pure_quanta.q_cap(chips)',
 PATH='I61',
 DRAWING='@T6G_MB_LIB.T6G(SCH_1):PAGE246',
 TOLERANCE='10%',
 MATERIAL='X7R',
 PHYS_PAGE='245',
 XY='(-3275,3900)',
 ROT='2',
 VER='1',
 PACK_TYPE='0402',
 LOCATION='C1713',
 CDS_LIB='pure_quanta',
 CDS_PART_NAME='Q_CAP_0402-0.1UF,25V,10%,X7R,CH4104K1B00',
 VOLTAGE='25V',
 PART_NUMBER='CH4104K1B00',
 VALUE='0.1UF',
 PRIM_FILE='./archive_libs/logical/q_cap/chips/chips.prt';

PART_NAME
 C1751 'Q_CAP_0402-0.1UF,25V,10%,X7R,CH4104K1B00':;

SECTION_NUMBER 1
 '@T6G_MB_LIB.T6G(SCH_1):PAGE363_I412@PURE_QUANTA.Q_CAP(CHIPS)':
 C_PATH='@t6g_mb_lib.t6g(sch_1):page363_i412@pure_quanta.q_cap(chips)',
 P_PATH='@t6g_mb_lib.t6g(sch_1):page240_i412@pure_quanta.q_cap(chips)',
 PATH='I412',
 DRAWING='@T6G_MB_LIB.T6G(SCH_1):PAGE363',
 TOLERANCE='10%',
 MATERIAL='X7R',
 PHYS_PAGE='240',
 XY='(-2250,-2825)',
 ROT='2',
 VER='1',
 PACK_TYPE='0402',
 LOCATION='C1751',
 CDS_LIB='pure_quanta',
 CDS_PART_NAME='Q_CAP_0402-0.1UF,25V,10%,X7R,CH4104K1B00',
 VOLTAGE='25V',
 PART_NUMBER='CH4104K1B00',
 VALUE='0.1UF',
 PRIM_FILE='./archive_libs/logical/q_cap/chips/chips.prt';

PART_NAME
 C1754 'Q_CAP_0402-0.1UF,25V,10%,X7R,CH4104K1B00':;

SECTION_NUMBER 1
 '@T6G_MB_LIB.T6G(SCH_1):PAGE333_I92@PURE_QUANTA.Q_CAP(CHIPS)':
 C_PATH='@t6g_mb_lib.t6g(sch_1):page333_i92@pure_quanta.q_cap(chips)',
 P_PATH='@t6g_mb_lib.t6g(sch_1):page127_i92@pure_quanta.q_cap(chips)',
 PATH='I92',
 DRAWING='@T6G_MB_LIB.T6G(SCH_1):PAGE333',
 TOLERANCE='10%',
 MATERIAL='X7R',
 PHYS_PAGE='127',
 XY='(-1600,4925)',
 ROT='0',
 VER='1',
 PACK_TYPE='0402',
 LOCATION='C1754',
 CDS_LIB='pure_quanta',
 CDS_PART_NAME='Q_CAP_0402-0.1UF,25V,10%,X7R,CH4104K1B00',
 VOLTAGE='25V',
 PART_NUMBER='CH4104K1B00',
 VALUE='0.1UF',
 PRIM_FILE='./archive_libs/logical/q_cap/chips/chips.prt';

PART_NAME
 C1756 'Q_CAP_0402-0.1UF,25V,10%,X7R,CH4104K1B00':;

SECTION_NUMBER 1
 '@T6G_MB_LIB.T6G(SCH_1):PAGE333_I105@PURE_QUANTA.Q_CAP(CHIPS)':
 C_PATH='@t6g_mb_lib.t6g(sch_1):page333_i105@pure_quanta.q_cap(chips)',
 P_PATH='@t6g_mb_lib.t6g(sch_1):page127_i105@pure_quanta.q_cap(chips)',
 PATH='I105',
 DRAWING='@T6G_MB_LIB.T6G(SCH_1):PAGE333',
 TOLERANCE='10%',
 MATERIAL='X7R',
 PHYS_PAGE='127',
 XY='(2925,6250)',
 ROT='0',
 VER='1',
 PACK_TYPE='0402',
 LOCATION='C1756',
 CDS_LIB='pure_quanta',
 CDS_PART_NAME='Q_CAP_0402-0.1UF,25V,10%,X7R,CH4104K1B00',
 VOLTAGE='25V',
 PART_NUMBER='CH4104K1B00',
 VALUE='0.1UF',
 PRIM_FILE='./archive_libs/logical/q_cap/chips/chips.prt';

PART_NAME
 C1757 'Q_CAP_0402-0.1UF,25V,10%,X7R,CH4104K1B00':;

SECTION_NUMBER 1
 '@T6G_MB_LIB.T6G(SCH_1):PAGE369_I162@PURE_QUANTA.Q_CAP(CHIPS)':
 C_PATH='@t6g_mb_lib.t6g(sch_1):page369_i162@pure_quanta.q_cap(chips)',
 P_PATH='@t6g_mb_lib.t6g(sch_1):page257_i162@pure_quanta.q_cap(chips)',
 PATH='I162',
 DRAWING='@T6G_MB_LIB.T6G(SCH_1):PAGE369',
 TOLERANCE='10%',
 MATERIAL='X7R',
 PHYS_PAGE='257',
 XY='(-1500,5325)',
 ROT='2',
 VER='1',
 PACK_TYPE='0402',
 LOCATION='C1757',
 CDS_LIB='pure_quanta',
 CDS_PART_NAME='Q_CAP_0402-0.1UF,25V,10%,X7R,CH4104K1B00',
 VOLTAGE='25V',
 PART_NUMBER='CH4104K1B00',
 VALUE='0.1UF',
 PRIM_FILE='./archive_libs/logical/q_cap/chips/chips.prt';

PART_NAME
 C1766 'Q_CAP_0402-0.1UF,25V,10%,X7R,CH4104K1B00':;

SECTION_NUMBER 1
 '@T6G_MB_LIB.T6G(SCH_1):PAGE249_I78@PURE_QUANTA.Q_CAP(CHIPS)':
 C_PATH='@t6g_mb_lib.t6g(sch_1):page249_i78@pure_quanta.q_cap(chips)',
 P_PATH='@t6g_mb_lib.t6g(sch_1):page248_i78@pure_quanta.q_cap(chips)',
 PATH='I78',
 DRAWING='@T6G_MB_LIB.T6G(SCH_1):PAGE249',
 TOLERANCE='10%',
 MATERIAL='X7R',
 PHYS_PAGE='248',
 XY='(-3175,4350)',
 ROT='0',
 VER='1',
 PACK_TYPE='0402',
 LOCATION='C1766',
 CDS_LIB='pure_quanta',
 CDS_PART_NAME='Q_CAP_0402-0.1UF,25V,10%,X7R,CH4104K1B00',
 VOLTAGE='25V',
 PART_NUMBER='CH4104K1B00',
 VALUE='0.1UF',
 PRIM_FILE='./archive_libs/logical/q_cap/chips/chips.prt';

PART_NAME
 C1767 'Q_CAP_C0805-10UF,16V,10%,X6S,CH6103KEA00':;

SECTION_NUMBER 1
 '@T6G_MB_LIB.T6G(SCH_1):PAGE369_I121@PURE_QUANTA.Q_CAP(CHIPS)':
 C_PATH='@t6g_mb_lib.t6g(sch_1):page369_i121@pure_quanta.q_cap(chips)',
 P_PATH='@t6g_mb_lib.t6g(sch_1):page257_i121@pure_quanta.q_cap(chips)',
 PATH='I121',
 DRAWING='@T6G_MB_LIB.T6G(SCH_1):PAGE369',
 TOLERANCE='10%',
 MATERIAL='X6S',
 PHYS_PAGE='257',
 XY='(-3825,5350)',
 ROT='0',
 VER='1',
 PACK_TYPE='C0805',
 LOCATION='C1767',
 CDS_LIB='pure_quanta',
 CDS_PART_NAME='Q_CAP_C0805-10UF,16V,10%,X6S,CH6103KEA00',
 VOLTAGE='16V',
 PART_NUMBER='CH6103KEA00',
 VALUE='10UF',
 PRIM_FILE='./archive_libs/logical/q_cap/chips/chips.prt';

PART_NAME
 C1768 'Q_CAP_C0805-10UF,16V,10%,X6S,CH6103KEA00':;

SECTION_NUMBER 1
 '@T6G_MB_LIB.T6G(SCH_1):PAGE369_I166@PURE_QUANTA.Q_CAP(CHIPS)':
 C_PATH='@t6g_mb_lib.t6g(sch_1):page369_i166@pure_quanta.q_cap(chips)',
 P_PATH='@t6g_mb_lib.t6g(sch_1):page257_i166@pure_quanta.q_cap(chips)',
 PATH='I166',
 DRAWING='@T6G_MB_LIB.T6G(SCH_1):PAGE369',
 TOLERANCE='10%',
 MATERIAL='X6S',
 PHYS_PAGE='257',
 XY='(-1125,5325)',
 ROT='0',
 VER='1',
 PACK_TYPE='C0805',
 LOCATION='C1768',
 CDS_LIB='pure_quanta',
 CDS_PART_NAME='Q_CAP_C0805-10UF,16V,10%,X6S,CH6103KEA00',
 VOLTAGE='16V',
 PART_NUMBER='CH6103KEA00',
 VALUE='10UF',
 PRIM_FILE='./archive_libs/logical/q_cap/chips/chips.prt';

PART_NAME
 C1769 'Q_CAP_0402-0.1UF,25V,10%,X7R,CH4104K1B00':;

SECTION_NUMBER 1
 '@T6G_MB_LIB.T6G(SCH_1):PAGE256_I89@PURE_QUANTA.Q_CAP(CHIPS)':
 C_PATH='@t6g_mb_lib.t6g(sch_1):page256_i89@pure_quanta.q_cap(chips)',
 P_PATH='@t6g_mb_lib.t6g(sch_1):page130_i89@pure_quanta.q_cap(chips)',
 PATH='I89',
 DRAWING='@T6G_MB_LIB.T6G(SCH_1):PAGE256',
 TOLERANCE='10%',
 MATERIAL='X7R',
 PHYS_PAGE='130',
 XY='(1625,3375)',
 ROT='0',
 VER='1',
 PACK_TYPE='0402',
 LOCATION='C1769',
 CDS_LIB='pure_quanta',
 CDS_PART_NAME='Q_CAP_0402-0.1UF,25V,10%,X7R,CH4104K1B00',
 VOLTAGE='25V',
 PART_NUMBER='CH4104K1B00',
 VALUE='0.1UF',
 PRIM_FILE='./archive_libs/logical/q_cap/chips/chips.prt';

PART_NAME
 C1770 'Q_CAP_0402-0.1UF,25V,10%,X7R,CH4104K1B00':;

SECTION_NUMBER 1
 '@T6G_MB_LIB.T6G(SCH_1):PAGE256_I140@PURE_QUANTA.Q_CAP(CHIPS)':
 C_PATH='@t6g_mb_lib.t6g(sch_1):page256_i140@pure_quanta.q_cap(chips)',
 P_PATH='@t6g_mb_lib.t6g(sch_1):page130_i140@pure_quanta.q_cap(chips)',
 PATH='I140',
 DRAWING='@T6G_MB_LIB.T6G(SCH_1):PAGE256',
 TOLERANCE='10%',
 MATERIAL='X7R',
 PHYS_PAGE='130',
 XY='(1625,975)',
 ROT='0',
 VER='1',
 PACK_TYPE='0402',
 LOCATION='C1770',
 CDS_LIB='pure_quanta',
 CDS_PART_NAME='Q_CAP_0402-0.1UF,25V,10%,X7R,CH4104K1B00',
 VOLTAGE='25V',
 PART_NUMBER='CH4104K1B00',
 VALUE='0.1UF',
 PRIM_FILE='./archive_libs/logical/q_cap/chips/chips.prt';

PART_NAME
 C1772 'Q_CAP_0402-0.1UF,25V,10%,X7R,CH4104K1B00':;

SECTION_NUMBER 1
 '@T6G_MB_LIB.T6G(SCH_1):PAGE333_I116@PURE_QUANTA.Q_CAP(CHIPS)':
 C_PATH='@t6g_mb_lib.t6g(sch_1):page333_i116@pure_quanta.q_cap(chips)',
 P_PATH='@t6g_mb_lib.t6g(sch_1):page127_i116@pure_quanta.q_cap(chips)',
 PATH='I116',
 DRAWING='@T6G_MB_LIB.T6G(SCH_1):PAGE333',
 TOLERANCE='10%',
 MATERIAL='X7R',
 PHYS_PAGE='127',
 XY='(-1650,6275)',
 ROT='0',
 VER='1',
 PACK_TYPE='0402',
 LOCATION='C1772',
 CDS_LIB='pure_quanta',
 CDS_PART_NAME='Q_CAP_0402-0.1UF,25V,10%,X7R,CH4104K1B00',
 VOLTAGE='25V',
 PART_NUMBER='CH4104K1B00',
 VALUE='0.1UF',
 PRIM_FILE='./archive_libs/logical/q_cap/chips/chips.prt';

PART_NAME
 C1773 'Q_CAP_0402-0.1UF,25V,10%,X7R,CH4104K1B00':;

SECTION_NUMBER 1
 '@T6G_MB_LIB.T6G(SCH_1):PAGE333_I114@PURE_QUANTA.Q_CAP(CHIPS)':
 C_PATH='@t6g_mb_lib.t6g(sch_1):page333_i114@pure_quanta.q_cap(chips)',
 P_PATH='@t6g_mb_lib.t6g(sch_1):page127_i114@pure_quanta.q_cap(chips)',
 PATH='I114',
 DRAWING='@T6G_MB_LIB.T6G(SCH_1):PAGE333',
 TOLERANCE='10%',
 MATERIAL='X7R',
 PHYS_PAGE='127',
 XY='(-1600,7650)',
 ROT='0',
 VER='1',
 PACK_TYPE='0402',
 LOCATION='C1773',
 CDS_LIB='pure_quanta',
 CDS_PART_NAME='Q_CAP_0402-0.1UF,25V,10%,X7R,CH4104K1B00',
 VOLTAGE='25V',
 PART_NUMBER='CH4104K1B00',
 VALUE='0.1UF',
 PRIM_FILE='./archive_libs/logical/q_cap/chips/chips.prt';

PART_NAME
 C1774 'Q_CAP_0402-0.1UF,25V,10%,X7R,CH4104K1B00':;

SECTION_NUMBER 1
 '@T6G_MB_LIB.T6G(SCH_1):PAGE333_I111@PURE_QUANTA.Q_CAP(CHIPS)':
 C_PATH='@t6g_mb_lib.t6g(sch_1):page333_i111@pure_quanta.q_cap(chips)',
 P_PATH='@t6g_mb_lib.t6g(sch_1):page127_i111@pure_quanta.q_cap(chips)',
 PATH='I111',
 DRAWING='@T6G_MB_LIB.T6G(SCH_1):PAGE333',
 TOLERANCE='10%',
 MATERIAL='X7R',
 PHYS_PAGE='127',
 XY='(2875,7775)',
 ROT='0',
 VER='1',
 PACK_TYPE='0402',
 LOCATION='C1774',
 CDS_LIB='pure_quanta',
 CDS_PART_NAME='Q_CAP_0402-0.1UF,25V,10%,X7R,CH4104K1B00',
 VOLTAGE='25V',
 PART_NUMBER='CH4104K1B00',
 VALUE='0.1UF',
 PRIM_FILE='./archive_libs/logical/q_cap/chips/chips.prt';

PART_NAME
 C1775 'Q_CAP_0402-0.1UF,25V,10%,X7R,CH4104K1B00':;

SECTION_NUMBER 1
 '@T6G_MB_LIB.T6G(SCH_1):PAGE364_I14@PURE_QUANTA.Q_CAP(CHIPS)':
 C_PATH='@t6g_mb_lib.t6g(sch_1):page364_i14@pure_quanta.q_cap(chips)',
 P_PATH='@t6g_mb_lib.t6g(sch_1):page241_i14@pure_quanta.q_cap(chips)',
 PATH='I14',
 DRAWING='@T6G_MB_LIB.T6G(SCH_1):PAGE364',
 TOLERANCE='10%',
 MATERIAL='X7R',
 PHYS_PAGE='241',
 XY='(925,2475)',
 ROT='0',
 VER='1',
 PACK_TYPE='0402',
 LOCATION='C1775',
 CDS_LIB='pure_quanta',
 CDS_PART_NAME='Q_CAP_0402-0.1UF,25V,10%,X7R,CH4104K1B00',
 VOLTAGE='25V',
 PART_NUMBER='CH4104K1B00',
 VALUE='0.1UF',
 PRIM_FILE='./archive_libs/logical/q_cap/chips/chips.prt';

PART_NAME
 C1786 'Q_CAP_0603-1000PF,50V,10%,X7R,TMP_QCH21006K917':
 ROOM='HSC BOM2';

SECTION_NUMBER 1
 '@T6G_MB_LIB.T6G(SCH_1):PAGE371_I4@PURE_QUANTA.Q_CAP(CHIPS)':
 C_PATH='@t6g_mb_lib.t6g(sch_1):page371_i4@pure_quanta.q_cap(chips)',
 P_PATH='@t6g_mb_lib.t6g(sch_1):page267_i4@pure_quanta.q_cap(chips)',
 PATH='I4',
 DRAWING='@T6G_MB_LIB.T6G(SCH_1):PAGE371',
 TOLERANCE='10%',
 MATERIAL='X7R',
 PHYS_PAGE='267',
 XY='(-4975,1975)',
 ROT='2',
 VER='1',
 PACK_TYPE='0603',
 LOCATION='C1786',
 CDS_LIB='pure_quanta',
 CDS_PART_NAME='Q_CAP_0603-1000PF,50V,10%,X7R,TMP_QCH21006K917',
 VOLTAGE='50V',
 ROOM='HSC BOM2',
 PART_NUMBER='TMP_QCH21006K917',
 VALUE='1000PF',
 PRIM_FILE='./archive_libs/logical/q_cap/chips/chips.prt';

PART_NAME
 C1787 'Q_CAP_C0402-0.1UF,16V,10%,X7R,CH4103K1B08':
 ROOM='HSC BOM2';

SECTION_NUMBER 1
 '@T6G_MB_LIB.T6G(SCH_1):PAGE371_I6@PURE_QUANTA.Q_CAP(CHIPS)':
 C_PATH='@t6g_mb_lib.t6g(sch_1):page371_i6@pure_quanta.q_cap(chips)',
 P_PATH='@t6g_mb_lib.t6g(sch_1):page267_i6@pure_quanta.q_cap(chips)',
 PATH='I6',
 DRAWING='@T6G_MB_LIB.T6G(SCH_1):PAGE371',
 TOLERANCE='10%',
 MATERIAL='X7R',
 PHYS_PAGE='267',
 XY='(-4750,2450)',
 ROT='0',
 VER='1',
 PACK_TYPE='C0402',
 LOCATION='C1787',
 CDS_LIB='pure_quanta',
 CDS_PART_NAME='Q_CAP_C0402-0.1UF,16V,10%,X7R,CH4103K1B08',
 VOLTAGE='16V',
 ROOM='HSC BOM2',
 PART_NUMBER='CH4103K1B08',
 VALUE='0.1UF',
 PRIM_FILE='./archive_libs/logical/q_cap/chips/chips.prt';

PART_NAME
 C1792 'Q_CAP_DIFFBUS_C0201-DIFF BUS_0.22UF,6.3V,20%,X6S,SA':;

SECTION_NUMBER 1
 '@T6G_MB_LIB.T6G(SCH_1):PAGE353_I271@PURE_QUANTA.Q_CAP_DIFFBUS(CHIPS)':
 C_PATH='@t6g_mb_lib.t6g(sch_1):page353_i271@pure_quanta.q_cap_diffbus(chips)',
 P_PATH='@t6g_mb_lib.t6g(sch_1):page65_i271@pure_quanta.q_cap_diffbus(chips)',
 PATH='I271',
 DRAWING='@T6G_MB_LIB.T6G(SCH_1):PAGE353',
 PIN_NAMES_ROTATE='TRUE',
 TOLERANCE='20%',
 MATERIAL='X6S',
 PHYS_PAGE='65',
 XY='(-925,3325)',
 ROT='2',
 VER='2',
 PACK_TYPE='C0201',
 LOCATION='C1792',
 CDS_LIB='pure_quanta',
 CDS_PART_NAME='Q_CAP_DIFFBUS_C0201-DIFF BUS_0.22UF,6.3V,20%,X6S,SA',
 VOLTAGE='6.3V',
 PART_NUMBER='SP_CH4221MEE01',
 VALUE='DIFF BUS_0.22UF',
 PRIM_FILE='./archive_libs/logical/q_cap_diffbus/chips/chips.prt';

PART_NAME
 C1793 'Q_CAP_DIFFBUS_C0201-DIFF BUS_0.22UF,6.3V,20%,X6S,SA':;

SECTION_NUMBER 1
 '@T6G_MB_LIB.T6G(SCH_1):PAGE353_I261@PURE_QUANTA.Q_CAP_DIFFBUS(CHIPS)':
 C_PATH='@t6g_mb_lib.t6g(sch_1):page353_i261@pure_quanta.q_cap_diffbus(chips)',
 P_PATH='@t6g_mb_lib.t6g(sch_1):page65_i261@pure_quanta.q_cap_diffbus(chips)',
 PATH='I261',
 DRAWING='@T6G_MB_LIB.T6G(SCH_1):PAGE353',
 PIN_NAMES_ROTATE='TRUE',
 TOLERANCE='20%',
 MATERIAL='X6S',
 PHYS_PAGE='65',
 XY='(-925,2325)',
 ROT='2',
 VER='2',
 PACK_TYPE='C0201',
 LOCATION='C1793',
 CDS_LIB='pure_quanta',
 CDS_PART_NAME='Q_CAP_DIFFBUS_C0201-DIFF BUS_0.22UF,6.3V,20%,X6S,SA',
 VOLTAGE='6.3V',
 PART_NUMBER='SP_CH4221MEE01',
 VALUE='DIFF BUS_0.22UF',
 PRIM_FILE='./archive_libs/logical/q_cap_diffbus/chips/chips.prt';

PART_NAME
 C1794 'Q_CAP_DIFFBUS_C0201-DIFF BUS_0.22UF,6.3V,20%,X6S,SA':;

SECTION_NUMBER 1
 '@T6G_MB_LIB.T6G(SCH_1):PAGE353_I260@PURE_QUANTA.Q_CAP_DIFFBUS(CHIPS)':
 C_PATH='@t6g_mb_lib.t6g(sch_1):page353_i260@pure_quanta.q_cap_diffbus(chips)',
 P_PATH='@t6g_mb_lib.t6g(sch_1):page65_i260@pure_quanta.q_cap_diffbus(chips)',
 PATH='I260',
 DRAWING='@T6G_MB_LIB.T6G(SCH_1):PAGE353',
 PIN_NAMES_ROTATE='TRUE',
 TOLERANCE='20%',
 MATERIAL='X6S',
 PHYS_PAGE='65',
 XY='(-925,2175)',
 ROT='2',
 VER='2',
 PACK_TYPE='C0201',
 LOCATION='C1794',
 CDS_LIB='pure_quanta',
 CDS_PART_NAME='Q_CAP_DIFFBUS_C0201-DIFF BUS_0.22UF,6.3V,20%,X6S,SA',
 VOLTAGE='6.3V',
 PART_NUMBER='SP_CH4221MEE01',
 VALUE='DIFF BUS_0.22UF',
 PRIM_FILE='./archive_libs/logical/q_cap_diffbus/chips/chips.prt';

PART_NAME
 C1796 'Q_CAP_0402-0.1UF,25V,10%,X7R,CH4104K1B00':;

SECTION_NUMBER 1
 '@T6G_MB_LIB.T6G(SCH_1):PAGE249_I32@PURE_QUANTA.Q_CAP(CHIPS)':
 C_PATH='@t6g_mb_lib.t6g(sch_1):page249_i32@pure_quanta.q_cap(chips)',
 P_PATH='@t6g_mb_lib.t6g(sch_1):page248_i32@pure_quanta.q_cap(chips)',
 PATH='I32',
 DRAWING='@T6G_MB_LIB.T6G(SCH_1):PAGE249',
 TOLERANCE='10%',
 MATERIAL='X7R',
 PHYS_PAGE='248',
 XY='(-5775,3000)',
 ROT='0',
 VER='1',
 PACK_TYPE='0402',
 LOCATION='C1796',
 CDS_LIB='pure_quanta',
 CDS_PART_NAME='Q_CAP_0402-0.1UF,25V,10%,X7R,CH4104K1B00',
 VOLTAGE='25V',
 PART_NUMBER='CH4104K1B00',
 VALUE='0.1UF',
 PRIM_FILE='./archive_libs/logical/q_cap/chips/chips.prt';

PART_NAME
 C1797 'Q_CAP_0402-0.1UF,25V,10%,X7R,CH4104K1B00':;

SECTION_NUMBER 1
 '@T6G_MB_LIB.T6G(SCH_1):PAGE372_I9@PURE_QUANTA.Q_CAP(CHIPS)':
 C_PATH='@t6g_mb_lib.t6g(sch_1):page372_i9@pure_quanta.q_cap(chips)',
 P_PATH='@t6g_mb_lib.t6g(sch_1):page268_i9@pure_quanta.q_cap(chips)',
 PATH='I9',
 DRAWING='@T6G_MB_LIB.T6G(SCH_1):PAGE372',
 TOLERANCE='10%',
 MATERIAL='X7R',
 PHYS_PAGE='268',
 XY='(-8650,550)',
 ROT='0',
 VER='1',
 PACK_TYPE='0402',
 LOCATION='C1797',
 CDS_LIB='pure_quanta',
 CDS_PART_NAME='Q_CAP_0402-0.1UF,25V,10%,X7R,CH4104K1B00',
 VOLTAGE='25V',
 PART_NUMBER='CH4104K1B00',
 VALUE='0.1UF',
 PRIM_FILE='./archive_libs/logical/q_cap/chips/chips.prt';

PART_NAME
 C1802 'Q_CAP_0402-0.1UF,25V,10%,X7R,CH4104K1B00':;

SECTION_NUMBER 1
 '@T6G_MB_LIB.T6G(SCH_1):PAGE333_I148@PURE_QUANTA.Q_CAP(CHIPS)':
 C_PATH='@t6g_mb_lib.t6g(sch_1):page333_i148@pure_quanta.q_cap(chips)',
 P_PATH='@t6g_mb_lib.t6g(sch_1):page127_i148@pure_quanta.q_cap(chips)',
 PATH='I148',
 DRAWING='@T6G_MB_LIB.T6G(SCH_1):PAGE333',
 TOLERANCE='10%',
 MATERIAL='X7R',
 PHYS_PAGE='127',
 XY='(-1600,3175)',
 ROT='0',
 VER='1',
 PACK_TYPE='0402',
 LOCATION='C1802',
 CDS_LIB='pure_quanta',
 CDS_PART_NAME='Q_CAP_0402-0.1UF,25V,10%,X7R,CH4104K1B00',
 VOLTAGE='25V',
 PART_NUMBER='CH4104K1B00',
 VALUE='0.1UF',
 PRIM_FILE='./archive_libs/logical/q_cap/chips/chips.prt';

PART_NAME
 C1803 'Q_CAP_0402-0.1UF,25V,10%,X7R,CH4104K1B00':;

SECTION_NUMBER 1
 '@T6G_MB_LIB.T6G(SCH_1):PAGE256_I166@PURE_QUANTA.Q_CAP(CHIPS)':
 C_PATH='@t6g_mb_lib.t6g(sch_1):page256_i166@pure_quanta.q_cap(chips)',
 P_PATH='@t6g_mb_lib.t6g(sch_1):page130_i166@pure_quanta.q_cap(chips)',
 PATH='I166',
 DRAWING='@T6G_MB_LIB.T6G(SCH_1):PAGE256',
 TOLERANCE='10%',
 MATERIAL='X7R',
 PHYS_PAGE='130',
 XY='(2225,-1425)',
 ROT='0',
 VER='1',
 PACK_TYPE='0402',
 LOCATION='C1803',
 CDS_LIB='pure_quanta',
 CDS_PART_NAME='Q_CAP_0402-0.1UF,25V,10%,X7R,CH4104K1B00',
 VOLTAGE='25V',
 PART_NUMBER='CH4104K1B00',
 VALUE='0.1UF',
 PRIM_FILE='./archive_libs/logical/q_cap/chips/chips.prt';

PART_NAME
 C1804 'Q_CAP_0402-0.1UF,25V,10%,X7R,CH4104K1B00':;

SECTION_NUMBER 1
 '@T6G_MB_LIB.T6G(SCH_1):PAGE333_I125@PURE_QUANTA.Q_CAP(CHIPS)':
 C_PATH='@t6g_mb_lib.t6g(sch_1):page333_i125@pure_quanta.q_cap(chips)',
 P_PATH='@t6g_mb_lib.t6g(sch_1):page127_i125@pure_quanta.q_cap(chips)',
 PATH='I125',
 DRAWING='@T6G_MB_LIB.T6G(SCH_1):PAGE333',
 TOLERANCE='10%',
 MATERIAL='X7R',
 PHYS_PAGE='127',
 XY='(2950,4875)',
 ROT='0',
 VER='1',
 PACK_TYPE='0402',
 LOCATION='C1804',
 CDS_LIB='pure_quanta',
 CDS_PART_NAME='Q_CAP_0402-0.1UF,25V,10%,X7R,CH4104K1B00',
 VOLTAGE='25V',
 PART_NUMBER='CH4104K1B00',
 VALUE='0.1UF',
 PRIM_FILE='./archive_libs/logical/q_cap/chips/chips.prt';

PART_NAME
 C1809 'Q_CAP_0402-0.1UF,25V,10%,X7R,CH4104K1B00':;

SECTION_NUMBER 1
 '@T6G_MB_LIB.T6G(SCH_1):PAGE343_I29@PURE_QUANTA.Q_CAP(CHIPS)':
 C_PATH='@t6g_mb_lib.t6g(sch_1):page343_i29@pure_quanta.q_cap(chips)',
 P_PATH='@t6g_mb_lib.t6g(sch_1):page140_i29@pure_quanta.q_cap(chips)',
 PATH='I29',
 DRAWING='@T6G_MB_LIB.T6G(SCH_1):PAGE343',
 TOLERANCE='10%',
 MATERIAL='X7R',
 PHYS_PAGE='140',
 XY='(-475,4900)',
 ROT='0',
 VER='1',
 PACK_TYPE='0402',
 LOCATION='C1809',
 CDS_LIB='pure_quanta',
 CDS_PART_NAME='Q_CAP_0402-0.1UF,25V,10%,X7R,CH4104K1B00',
 VOLTAGE='25V',
 PART_NUMBER='CH4104K1B00',
 VALUE='0.1UF',
 PRIM_FILE='./archive_libs/logical/q_cap/chips/chips.prt';

PART_NAME
 C1810 'Q_CAP_0402-0.1UF,25V,10%,X7R,CH4104K1B00':;

SECTION_NUMBER 1
 '@T6G_MB_LIB.T6G(SCH_1):PAGE343_I23@PURE_QUANTA.Q_CAP(CHIPS)':
 C_PATH='@t6g_mb_lib.t6g(sch_1):page343_i23@pure_quanta.q_cap(chips)',
 P_PATH='@t6g_mb_lib.t6g(sch_1):page140_i23@pure_quanta.q_cap(chips)',
 PATH='I23',
 DRAWING='@T6G_MB_LIB.T6G(SCH_1):PAGE343',
 TOLERANCE='10%',
 MATERIAL='X7R',
 PHYS_PAGE='140',
 XY='(-475,4000)',
 ROT='0',
 VER='1',
 PACK_TYPE='0402',
 LOCATION='C1810',
 CDS_LIB='pure_quanta',
 CDS_PART_NAME='Q_CAP_0402-0.1UF,25V,10%,X7R,CH4104K1B00',
 VOLTAGE='25V',
 PART_NUMBER='CH4104K1B00',
 VALUE='0.1UF',
 PRIM_FILE='./archive_libs/logical/q_cap/chips/chips.prt';

PART_NAME
 C1821 'Q_CAP_0402-0.1UF,25V,10%,X7R,CH4104K1B00':;

SECTION_NUMBER 1
 '@T6G_MB_LIB.T6G(SCH_1):PAGE342_I55@PURE_QUANTA.Q_CAP(CHIPS)':
 C_PATH='@t6g_mb_lib.t6g(sch_1):page342_i55@pure_quanta.q_cap(chips)',
 P_PATH='@t6g_mb_lib.t6g(sch_1):page139_i55@pure_quanta.q_cap(chips)',
 PATH='I55',
 DRAWING='@T6G_MB_LIB.T6G(SCH_1):PAGE342',
 TOLERANCE='10%',
 MATERIAL='X7R',
 PHYS_PAGE='139',
 XY='(4500,1250)',
 ROT='2',
 VER='1',
 PACK_TYPE='0402',
 LOCATION='C1821',
 CDS_LIB='pure_quanta',
 CDS_PART_NAME='Q_CAP_0402-0.1UF,25V,10%,X7R,CH4104K1B00',
 VOLTAGE='25V',
 PART_NUMBER='CH4104K1B00',
 VALUE='0.1UF',
 PRIM_FILE='./archive_libs/logical/q_cap/chips/chips.prt';

PART_NAME
 C1822 'Q_CAP_0402-0.1UF,25V,10%,X7R,CH4104K1B00':;

SECTION_NUMBER 1
 '@T6G_MB_LIB.T6G(SCH_1):PAGE342_I16@PURE_QUANTA.Q_CAP(CHIPS)':
 C_PATH='@t6g_mb_lib.t6g(sch_1):page342_i16@pure_quanta.q_cap(chips)',
 P_PATH='@t6g_mb_lib.t6g(sch_1):page139_i16@pure_quanta.q_cap(chips)',
 PATH='I16',
 DRAWING='@T6G_MB_LIB.T6G(SCH_1):PAGE342',
 TOLERANCE='10%',
 MATERIAL='X7R',
 PHYS_PAGE='139',
 XY='(5150,-1225)',
 ROT='0',
 VER='1',
 PACK_TYPE='0402',
 LOCATION='C1822',
 CDS_LIB='pure_quanta',
 CDS_PART_NAME='Q_CAP_0402-0.1UF,25V,10%,X7R,CH4104K1B00',
 VOLTAGE='25V',
 PART_NUMBER='CH4104K1B00',
 VALUE='0.1UF',
 PRIM_FILE='./archive_libs/logical/q_cap/chips/chips.prt';

PART_NAME
 C1823 'Q_CAP_0402-0.1UF,25V,10%,X7R,CH4104K1B00':;

SECTION_NUMBER 1
 '@T6G_MB_LIB.T6G(SCH_1):PAGE342_I31@PURE_QUANTA.Q_CAP(CHIPS)':
 C_PATH='@t6g_mb_lib.t6g(sch_1):page342_i31@pure_quanta.q_cap(chips)',
 P_PATH='@t6g_mb_lib.t6g(sch_1):page139_i31@pure_quanta.q_cap(chips)',
 PATH='I31',
 DRAWING='@T6G_MB_LIB.T6G(SCH_1):PAGE342',
 TOLERANCE='10%',
 MATERIAL='X7R',
 PHYS_PAGE='139',
 XY='(6450,-25)',
 ROT='0',
 VER='1',
 PACK_TYPE='0402',
 LOCATION='C1823',
 CDS_LIB='pure_quanta',
 CDS_PART_NAME='Q_CAP_0402-0.1UF,25V,10%,X7R,CH4104K1B00',
 VOLTAGE='25V',
 PART_NUMBER='CH4104K1B00',
 VALUE='0.1UF',
 PRIM_FILE='./archive_libs/logical/q_cap/chips/chips.prt';

PART_NAME
 C1824 'Q_CAP_0402-0.1UF,25V,10%,X7R,CH4104K1B00':;

SECTION_NUMBER 1
 '@T6G_MB_LIB.T6G(SCH_1):PAGE342_I41@PURE_QUANTA.Q_CAP(CHIPS)':
 C_PATH='@t6g_mb_lib.t6g(sch_1):page342_i41@pure_quanta.q_cap(chips)',
 P_PATH='@t6g_mb_lib.t6g(sch_1):page139_i41@pure_quanta.q_cap(chips)',
 PATH='I41',
 DRAWING='@T6G_MB_LIB.T6G(SCH_1):PAGE342',
 TOLERANCE='10%',
 MATERIAL='X7R',
 PHYS_PAGE='139',
 XY='(8700,-1450)',
 ROT='0',
 VER='1',
 PACK_TYPE='0402',
 LOCATION='C1824',
 CDS_LIB='pure_quanta',
 CDS_PART_NAME='Q_CAP_0402-0.1UF,25V,10%,X7R,CH4104K1B00',
 VOLTAGE='25V',
 PART_NUMBER='CH4104K1B00',
 VALUE='0.1UF',
 PRIM_FILE='./archive_libs/logical/q_cap/chips/chips.prt';

PART_NAME
 C1825 'Q_CAP_0402-0.1UF,25V,10%,X7R,CH4104K1B00':;

SECTION_NUMBER 1
 '@T6G_MB_LIB.T6G(SCH_1):PAGE307_I17@PURE_QUANTA.Q_CAP(CHIPS)':
 C_PATH='@t6g_mb_lib.t6g(sch_1):page307_i17@pure_quanta.q_cap(chips)',
 P_PATH='@t6g_mb_lib.t6g(sch_1):page138_i17@pure_quanta.q_cap(chips)',
 PATH='I17',
 DRAWING='@T6G_MB_LIB.T6G(SCH_1):PAGE307',
 TOLERANCE='10%',
 MATERIAL='X7R',
 PHYS_PAGE='138',
 XY='(-1600,-25)',
 ROT='2',
 VER='1',
 PACK_TYPE='0402',
 LOCATION='C1825',
 CDS_LIB='pure_quanta',
 CDS_PART_NAME='Q_CAP_0402-0.1UF,25V,10%,X7R,CH4104K1B00',
 VOLTAGE='25V',
 PART_NUMBER='CH4104K1B00',
 VALUE='0.1UF',
 PRIM_FILE='./archive_libs/logical/q_cap/chips/chips.prt';

PART_NAME
 C1826 'Q_CAP_0402-0.1UF,25V,10%,X7R,CH4104K1B00':;

SECTION_NUMBER 1
 '@T6G_MB_LIB.T6G(SCH_1):PAGE307_I33@PURE_QUANTA.Q_CAP(CHIPS)':
 C_PATH='@t6g_mb_lib.t6g(sch_1):page307_i33@pure_quanta.q_cap(chips)',
 P_PATH='@t6g_mb_lib.t6g(sch_1):page138_i33@pure_quanta.q_cap(chips)',
 PATH='I33',
 DRAWING='@T6G_MB_LIB.T6G(SCH_1):PAGE307',
 TOLERANCE='10%',
 MATERIAL='X7R',
 PHYS_PAGE='138',
 XY='(-525,2800)',
 ROT='2',
 VER='1',
 PACK_TYPE='0402',
 LOCATION='C1826',
 CDS_LIB='pure_quanta',
 CDS_PART_NAME='Q_CAP_0402-0.1UF,25V,10%,X7R,CH4104K1B00',
 VOLTAGE='25V',
 PART_NUMBER='CH4104K1B00',
 VALUE='0.1UF',
 PRIM_FILE='./archive_libs/logical/q_cap/chips/chips.prt';

PART_NAME
 C1827 'Q_CAP_0402-0.1UF,25V,10%,X7R,CH4104K1B00':;

SECTION_NUMBER 1
 '@T6G_MB_LIB.T6G(SCH_1):PAGE307_I77@PURE_QUANTA.Q_CAP(CHIPS)':
 C_PATH='@t6g_mb_lib.t6g(sch_1):page307_i77@pure_quanta.q_cap(chips)',
 P_PATH='@t6g_mb_lib.t6g(sch_1):page138_i77@pure_quanta.q_cap(chips)',
 PATH='I77',
 DRAWING='@T6G_MB_LIB.T6G(SCH_1):PAGE307',
 TOLERANCE='10%',
 MATERIAL='X7R',
 PHYS_PAGE='138',
 XY='(-525,1375)',
 ROT='2',
 VER='1',
 PACK_TYPE='0402',
 LOCATION='C1827',
 CDS_LIB='pure_quanta',
 CDS_PART_NAME='Q_CAP_0402-0.1UF,25V,10%,X7R,CH4104K1B00',
 VOLTAGE='25V',
 PART_NUMBER='CH4104K1B00',
 VALUE='0.1UF',
 PRIM_FILE='./archive_libs/logical/q_cap/chips/chips.prt';

PART_NAME
 C1829 'Q_CAP_C0805-22UF,16V,20%,X6S,CH6223MEA00':;

SECTION_NUMBER 1
 '@T6G_MB_LIB.T6G(SCH_1):PAGE341_I13@PURE_QUANTA.Q_CAP(CHIPS)':
 C_PATH='@t6g_mb_lib.t6g(sch_1):page341_i13@pure_quanta.q_cap(chips)',
 P_PATH='@t6g_mb_lib.t6g(sch_1):page137_i13@pure_quanta.q_cap(chips)',
 PATH='I13',
 DRAWING='@T6G_MB_LIB.T6G(SCH_1):PAGE341',
 TOLERANCE='20%',
 MATERIAL='X6S',
 PHYS_PAGE='137',
 XY='(5700,-300)',
 ROT='0',
 VER='1',
 PACK_TYPE='C0805',
 LOCATION='C1829',
 CDS_LIB='pure_quanta',
 CDS_PART_NAME='Q_CAP_C0805-22UF,16V,20%,X6S,CH6223MEA00',
 VOLTAGE='16V',
 PART_NUMBER='CH6223MEA00',
 VALUE='22UF',
 PRIM_FILE='./archive_libs/logical/q_cap/chips/chips.prt';

PART_NAME
 C1830 'Q_CAP_C0805-22UF,16V,20%,X6S,CH6223MEA00':;

SECTION_NUMBER 1
 '@T6G_MB_LIB.T6G(SCH_1):PAGE341_I14@PURE_QUANTA.Q_CAP(CHIPS)':
 C_PATH='@t6g_mb_lib.t6g(sch_1):page341_i14@pure_quanta.q_cap(chips)',
 P_PATH='@t6g_mb_lib.t6g(sch_1):page137_i14@pure_quanta.q_cap(chips)',
 PATH='I14',
 DRAWING='@T6G_MB_LIB.T6G(SCH_1):PAGE341',
 TOLERANCE='20%',
 MATERIAL='X6S',
 PHYS_PAGE='137',
 XY='(5975,-300)',
 ROT='0',
 VER='1',
 PACK_TYPE='C0805',
 LOCATION='C1830',
 CDS_LIB='pure_quanta',
 CDS_PART_NAME='Q_CAP_C0805-22UF,16V,20%,X6S,CH6223MEA00',
 VOLTAGE='16V',
 PART_NUMBER='CH6223MEA00',
 VALUE='22UF',
 PRIM_FILE='./archive_libs/logical/q_cap/chips/chips.prt';

PART_NAME
 C1831 'Q_CAP_0402-0.1UF,25V,10%,X7R,CH4104K1B00':;

SECTION_NUMBER 1
 '@T6G_MB_LIB.T6G(SCH_1):PAGE341_I15@PURE_QUANTA.Q_CAP(CHIPS)':
 C_PATH='@t6g_mb_lib.t6g(sch_1):page341_i15@pure_quanta.q_cap(chips)',
 P_PATH='@t6g_mb_lib.t6g(sch_1):page137_i15@pure_quanta.q_cap(chips)',
 PATH='I15',
 DRAWING='@T6G_MB_LIB.T6G(SCH_1):PAGE341',
 TOLERANCE='10%',
 MATERIAL='X7R',
 PHYS_PAGE='137',
 XY='(6375,-300)',
 ROT='0',
 VER='1',
 PACK_TYPE='0402',
 LOCATION='C1831',
 CDS_LIB='pure_quanta',
 CDS_PART_NAME='Q_CAP_0402-0.1UF,25V,10%,X7R,CH4104K1B00',
 VOLTAGE='25V',
 PART_NUMBER='CH4104K1B00',
 VALUE='0.1UF',
 PRIM_FILE='./archive_libs/logical/q_cap/chips/chips.prt';

PART_NAME
 C1832 'Q_CAP_0402-0.1UF,25V,10%,X7R,CH4104K1B00':;

SECTION_NUMBER 1
 '@T6G_MB_LIB.T6G(SCH_1):PAGE341_I16@PURE_QUANTA.Q_CAP(CHIPS)':
 C_PATH='@t6g_mb_lib.t6g(sch_1):page341_i16@pure_quanta.q_cap(chips)',
 P_PATH='@t6g_mb_lib.t6g(sch_1):page137_i16@pure_quanta.q_cap(chips)',
 PATH='I16',
 DRAWING='@T6G_MB_LIB.T6G(SCH_1):PAGE341',
 TOLERANCE='10%',
 MATERIAL='X7R',
 PHYS_PAGE='137',
 XY='(6650,-300)',
 ROT='0',
 VER='1',
 PACK_TYPE='0402',
 LOCATION='C1832',
 CDS_LIB='pure_quanta',
 CDS_PART_NAME='Q_CAP_0402-0.1UF,25V,10%,X7R,CH4104K1B00',
 VOLTAGE='25V',
 PART_NUMBER='CH4104K1B00',
 VALUE='0.1UF',
 PRIM_FILE='./archive_libs/logical/q_cap/chips/chips.prt';

PART_NAME
 C1833 'Q_CAP_0402-0.1UF,25V,10%,X7R,CH4104K1B00':;

SECTION_NUMBER 1
 '@T6G_MB_LIB.T6G(SCH_1):PAGE341_I17@PURE_QUANTA.Q_CAP(CHIPS)':
 C_PATH='@t6g_mb_lib.t6g(sch_1):page341_i17@pure_quanta.q_cap(chips)',
 P_PATH='@t6g_mb_lib.t6g(sch_1):page137_i17@pure_quanta.q_cap(chips)',
 PATH='I17',
 DRAWING='@T6G_MB_LIB.T6G(SCH_1):PAGE341',
 TOLERANCE='10%',
 MATERIAL='X7R',
 PHYS_PAGE='137',
 XY='(6925,-300)',
 ROT='0',
 VER='1',
 PACK_TYPE='0402',
 LOCATION='C1833',
 CDS_LIB='pure_quanta',
 CDS_PART_NAME='Q_CAP_0402-0.1UF,25V,10%,X7R,CH4104K1B00',
 VOLTAGE='25V',
 PART_NUMBER='CH4104K1B00',
 VALUE='0.1UF',
 PRIM_FILE='./archive_libs/logical/q_cap/chips/chips.prt';

PART_NAME
 C1834 'Q_CAP_0402-0.1UF,25V,10%,X7R,CH4104K1B00':;

SECTION_NUMBER 1
 '@T6G_MB_LIB.T6G(SCH_1):PAGE341_I20@PURE_QUANTA.Q_CAP(CHIPS)':
 C_PATH='@t6g_mb_lib.t6g(sch_1):page341_i20@pure_quanta.q_cap(chips)',
 P_PATH='@t6g_mb_lib.t6g(sch_1):page137_i20@pure_quanta.q_cap(chips)',
 PATH='I20',
 DRAWING='@T6G_MB_LIB.T6G(SCH_1):PAGE341',
 TOLERANCE='10%',
 MATERIAL='X7R',
 PHYS_PAGE='137',
 XY='(7400,-300)',
 ROT='0',
 VER='1',
 PACK_TYPE='0402',
 LOCATION='C1834',
 CDS_LIB='pure_quanta',
 CDS_PART_NAME='Q_CAP_0402-0.1UF,25V,10%,X7R,CH4104K1B00',
 VOLTAGE='25V',
 PART_NUMBER='CH4104K1B00',
 VALUE='0.1UF',
 PRIM_FILE='./archive_libs/logical/q_cap/chips/chips.prt';

PART_NAME
 C1835 'Q_CAP_0402-0.1UF,25V,10%,X7R,CH4104K1B00':;

SECTION_NUMBER 1
 '@T6G_MB_LIB.T6G(SCH_1):PAGE341_I21@PURE_QUANTA.Q_CAP(CHIPS)':
 C_PATH='@t6g_mb_lib.t6g(sch_1):page341_i21@pure_quanta.q_cap(chips)',
 P_PATH='@t6g_mb_lib.t6g(sch_1):page137_i21@pure_quanta.q_cap(chips)',
 PATH='I21',
 DRAWING='@T6G_MB_LIB.T6G(SCH_1):PAGE341',
 TOLERANCE='10%',
 MATERIAL='X7R',
 PHYS_PAGE='137',
 XY='(7900,-300)',
 ROT='0',
 VER='1',
 PACK_TYPE='0402',
 LOCATION='C1835',
 CDS_LIB='pure_quanta',
 CDS_PART_NAME='Q_CAP_0402-0.1UF,25V,10%,X7R,CH4104K1B00',
 VOLTAGE='25V',
 PART_NUMBER='CH4104K1B00',
 VALUE='0.1UF',
 PRIM_FILE='./archive_libs/logical/q_cap/chips/chips.prt';

PART_NAME
 C1836 'Q_CAP_0402-0.1UF,25V,10%,X7R,CH4104K1B00':;

SECTION_NUMBER 1
 '@T6G_MB_LIB.T6G(SCH_1):PAGE341_I22@PURE_QUANTA.Q_CAP(CHIPS)':
 C_PATH='@t6g_mb_lib.t6g(sch_1):page341_i22@pure_quanta.q_cap(chips)',
 P_PATH='@t6g_mb_lib.t6g(sch_1):page137_i22@pure_quanta.q_cap(chips)',
 PATH='I22',
 DRAWING='@T6G_MB_LIB.T6G(SCH_1):PAGE341',
 TOLERANCE='10%',
 MATERIAL='X7R',
 PHYS_PAGE='137',
 XY='(8150,-300)',
 ROT='0',
 VER='1',
 PACK_TYPE='0402',
 LOCATION='C1836',
 CDS_LIB='pure_quanta',
 CDS_PART_NAME='Q_CAP_0402-0.1UF,25V,10%,X7R,CH4104K1B00',
 VOLTAGE='25V',
 PART_NUMBER='CH4104K1B00',
 VALUE='0.1UF',
 PRIM_FILE='./archive_libs/logical/q_cap/chips/chips.prt';

PART_NAME
 C1837 'Q_CAP_0402-0.1UF,25V,10%,X7R,CH4104K1B00':;

SECTION_NUMBER 1
 '@T6G_MB_LIB.T6G(SCH_1):PAGE341_I23@PURE_QUANTA.Q_CAP(CHIPS)':
 C_PATH='@t6g_mb_lib.t6g(sch_1):page341_i23@pure_quanta.q_cap(chips)',
 P_PATH='@t6g_mb_lib.t6g(sch_1):page137_i23@pure_quanta.q_cap(chips)',
 PATH='I23',
 DRAWING='@T6G_MB_LIB.T6G(SCH_1):PAGE341',
 TOLERANCE='10%',
 MATERIAL='X7R',
 PHYS_PAGE='137',
 XY='(8425,-300)',
 ROT='0',
 VER='1',
 PACK_TYPE='0402',
 LOCATION='C1837',
 CDS_LIB='pure_quanta',
 CDS_PART_NAME='Q_CAP_0402-0.1UF,25V,10%,X7R,CH4104K1B00',
 VOLTAGE='25V',
 PART_NUMBER='CH4104K1B00',
 VALUE='0.1UF',
 PRIM_FILE='./archive_libs/logical/q_cap/chips/chips.prt';

PART_NAME
 C1838 'Q_CAP_0402-0.1UF,25V,10%,X7R,CH4104K1B00':;

SECTION_NUMBER 1
 '@T6G_MB_LIB.T6G(SCH_1):PAGE341_I24@PURE_QUANTA.Q_CAP(CHIPS)':
 C_PATH='@t6g_mb_lib.t6g(sch_1):page341_i24@pure_quanta.q_cap(chips)',
 P_PATH='@t6g_mb_lib.t6g(sch_1):page137_i24@pure_quanta.q_cap(chips)',
 PATH='I24',
 DRAWING='@T6G_MB_LIB.T6G(SCH_1):PAGE341',
 TOLERANCE='10%',
 MATERIAL='X7R',
 PHYS_PAGE='137',
 XY='(8700,-300)',
 ROT='0',
 VER='1',
 PACK_TYPE='0402',
 LOCATION='C1838',
 CDS_LIB='pure_quanta',
 CDS_PART_NAME='Q_CAP_0402-0.1UF,25V,10%,X7R,CH4104K1B00',
 VOLTAGE='25V',
 PART_NUMBER='CH4104K1B00',
 VALUE='0.1UF',
 PRIM_FILE='./archive_libs/logical/q_cap/chips/chips.prt';

PART_NAME
 C1839 'Q_CAP_0402-0.1UF,25V,10%,X7R,CH4104K1B00':;

SECTION_NUMBER 1
 '@T6G_MB_LIB.T6G(SCH_1):PAGE341_I18@PURE_QUANTA.Q_CAP(CHIPS)':
 C_PATH='@t6g_mb_lib.t6g(sch_1):page341_i18@pure_quanta.q_cap(chips)',
 P_PATH='@t6g_mb_lib.t6g(sch_1):page137_i18@pure_quanta.q_cap(chips)',
 PATH='I18',
 DRAWING='@T6G_MB_LIB.T6G(SCH_1):PAGE341',
 TOLERANCE='10%',
 MATERIAL='X7R',
 PHYS_PAGE='137',
 XY='(7150,-300)',
 ROT='0',
 VER='1',
 PACK_TYPE='0402',
 LOCATION='C1839',
 CDS_LIB='pure_quanta',
 CDS_PART_NAME='Q_CAP_0402-0.1UF,25V,10%,X7R,CH4104K1B00',
 VOLTAGE='25V',
 PART_NUMBER='CH4104K1B00',
 VALUE='0.1UF',
 PRIM_FILE='./archive_libs/logical/q_cap/chips/chips.prt';

PART_NAME
 C1840 'Q_CAP_0402-0.1UF,25V,10%,X7R,CH4104K1B00':;

SECTION_NUMBER 1
 '@T6G_MB_LIB.T6G(SCH_1):PAGE336_I147@PURE_QUANTA.Q_CAP(CHIPS)':
 C_PATH='@t6g_mb_lib.t6g(sch_1):page336_i147@pure_quanta.q_cap(chips)',
 P_PATH='@t6g_mb_lib.t6g(sch_1):page132_i147@pure_quanta.q_cap(chips)',
 PATH='I147',
 DRAWING='@T6G_MB_LIB.T6G(SCH_1):PAGE336',
 TOLERANCE='10%',
 MATERIAL='X7R',
 PHYS_PAGE='132',
 XY='(-2350,2700)',
 ROT='2',
 VER='1',
 PACK_TYPE='0402',
 LOCATION='C1840',
 CDS_LIB='pure_quanta',
 CDS_PART_NAME='Q_CAP_0402-0.1UF,25V,10%,X7R,CH4104K1B00',
 VOLTAGE='25V',
 PART_NUMBER='CH4104K1B00',
 VALUE='0.1UF',
 PRIM_FILE='./archive_libs/logical/q_cap/chips/chips.prt';

PART_NAME
 C1841 'Q_CAP_0402-0.1UF,25V,10%,X7R,CH4104K1B00':;

SECTION_NUMBER 1
 '@T6G_MB_LIB.T6G(SCH_1):PAGE342_I12@PURE_QUANTA.Q_CAP(CHIPS)':
 C_PATH='@t6g_mb_lib.t6g(sch_1):page342_i12@pure_quanta.q_cap(chips)',
 P_PATH='@t6g_mb_lib.t6g(sch_1):page139_i12@pure_quanta.q_cap(chips)',
 PATH='I12',
 DRAWING='@T6G_MB_LIB.T6G(SCH_1):PAGE342',
 TOLERANCE='10%',
 MATERIAL='X7R',
 PHYS_PAGE='139',
 XY='(5650,-2700)',
 ROT='2',
 VER='1',
 PACK_TYPE='0402',
 LOCATION='C1841',
 CDS_LIB='pure_quanta',
 CDS_PART_NAME='Q_CAP_0402-0.1UF,25V,10%,X7R,CH4104K1B00',
 VOLTAGE='25V',
 PART_NUMBER='CH4104K1B00',
 VALUE='0.1UF',
 PRIM_FILE='./archive_libs/logical/q_cap/chips/chips.prt';

PART_NAME
 C1859 'Q_CAP_0402-0.1UF,25V,10%,X7R,CH4104K1B00':;

SECTION_NUMBER 1
 '@T6G_MB_LIB.T6G(SCH_1):PAGE248_I4@PURE_QUANTA.Q_CAP(CHIPS)':
 C_PATH='@t6g_mb_lib.t6g(sch_1):page248_i4@pure_quanta.q_cap(chips)',
 P_PATH='@t6g_mb_lib.t6g(sch_1):page247_i4@pure_quanta.q_cap(chips)',
 PATH='I4',
 DRAWING='@T6G_MB_LIB.T6G(SCH_1):PAGE248',
 TOLERANCE='10%',
 MATERIAL='X7R',
 PHYS_PAGE='247',
 XY='(-5700,3675)',
 ROT='0',
 VER='1',
 PACK_TYPE='0402',
 LOCATION='C1859',
 CDS_LIB='pure_quanta',
 CDS_PART_NAME='Q_CAP_0402-0.1UF,25V,10%,X7R,CH4104K1B00',
 VOLTAGE='25V',
 PART_NUMBER='CH4104K1B00',
 VALUE='0.1UF',
 PRIM_FILE='./archive_libs/logical/q_cap/chips/chips.prt';

PART_NAME
 C1860 'Q_CAP_0402-0.1UF,25V,10%,X7R,CH4104K1B00':;

SECTION_NUMBER 1
 '@T6G_MB_LIB.T6G(SCH_1):PAGE248_I15@PURE_QUANTA.Q_CAP(CHIPS)':
 C_PATH='@t6g_mb_lib.t6g(sch_1):page248_i15@pure_quanta.q_cap(chips)',
 P_PATH='@t6g_mb_lib.t6g(sch_1):page247_i15@pure_quanta.q_cap(chips)',
 PATH='I15',
 DRAWING='@T6G_MB_LIB.T6G(SCH_1):PAGE248',
 TOLERANCE='10%',
 MATERIAL='X7R',
 PHYS_PAGE='247',
 XY='(-5675,5500)',
 ROT='0',
 VER='1',
 PACK_TYPE='0402',
 LOCATION='C1860',
 CDS_LIB='pure_quanta',
 CDS_PART_NAME='Q_CAP_0402-0.1UF,25V,10%,X7R,CH4104K1B00',
 VOLTAGE='25V',
 PART_NUMBER='CH4104K1B00',
 VALUE='0.1UF',
 PRIM_FILE='./archive_libs/logical/q_cap/chips/chips.prt';

PART_NAME
 C1861 'Q_CAP_0402-0.1UF,25V,10%,X7R,CH4104K1B00':;

SECTION_NUMBER 1
 '@T6G_MB_LIB.T6G(SCH_1):PAGE248_I9@PURE_QUANTA.Q_CAP(CHIPS)':
 C_PATH='@t6g_mb_lib.t6g(sch_1):page248_i9@pure_quanta.q_cap(chips)',
 P_PATH='@t6g_mb_lib.t6g(sch_1):page247_i9@pure_quanta.q_cap(chips)',
 PATH='I9',
 DRAWING='@T6G_MB_LIB.T6G(SCH_1):PAGE248',
 TOLERANCE='10%',
 MATERIAL='X7R',
 PHYS_PAGE='247',
 XY='(-4025,3675)',
 ROT='0',
 VER='1',
 PACK_TYPE='0402',
 LOCATION='C1861',
 CDS_LIB='pure_quanta',
 CDS_PART_NAME='Q_CAP_0402-0.1UF,25V,10%,X7R,CH4104K1B00',
 VOLTAGE='25V',
 PART_NUMBER='CH4104K1B00',
 VALUE='0.1UF',
 PRIM_FILE='./archive_libs/logical/q_cap/chips/chips.prt';

PART_NAME
 C1862 'Q_CAP_0402-0.1UF,25V,10%,X7R,CH4104K1B00':;

SECTION_NUMBER 1
 '@T6G_MB_LIB.T6G(SCH_1):PAGE248_I19@PURE_QUANTA.Q_CAP(CHIPS)':
 C_PATH='@t6g_mb_lib.t6g(sch_1):page248_i19@pure_quanta.q_cap(chips)',
 P_PATH='@t6g_mb_lib.t6g(sch_1):page247_i19@pure_quanta.q_cap(chips)',
 PATH='I19',
 DRAWING='@T6G_MB_LIB.T6G(SCH_1):PAGE248',
 TOLERANCE='10%',
 MATERIAL='X7R',
 PHYS_PAGE='247',
 XY='(-4000,5500)',
 ROT='0',
 VER='1',
 PACK_TYPE='0402',
 LOCATION='C1862',
 CDS_LIB='pure_quanta',
 CDS_PART_NAME='Q_CAP_0402-0.1UF,25V,10%,X7R,CH4104K1B00',
 VOLTAGE='25V',
 PART_NUMBER='CH4104K1B00',
 VALUE='0.1UF',
 PRIM_FILE='./archive_libs/logical/q_cap/chips/chips.prt';

PART_NAME
 C1863 'Q_CAP_0402-0.1UF,25V,10%,X7R,CH4104K1B00':
 ROOM='PCIE REDRIVER BOM1';

SECTION_NUMBER 1
 '@T6G_MB_LIB.T6G(SCH_1):PAGE110_I61@PURE_QUANTA.Q_CAP(CHIPS)':
 C_PATH='@t6g_mb_lib.t6g(sch_1):page110_i61@pure_quanta.q_cap(chips)',
 P_PATH='@t6g_mb_lib.t6g(sch_1):page111_i61@pure_quanta.q_cap(chips)',
 PATH='I61',
 DRAWING='@T6G_MB_LIB.T6G(SCH_1):PAGE110',
 TOLERANCE='10%',
 MATERIAL='X7R',
 PHYS_PAGE='111',
 XY='(2825,5875)',
 ROT='0',
 VER='1',
 PACK_TYPE='0402',
 LOCATION='C1863',
 CDS_LIB='pure_quanta',
 CDS_PART_NAME='Q_CAP_0402-0.1UF,25V,10%,X7R,CH4104K1B00',
 VOLTAGE='25V',
 ROOM='PCIE REDRIVER BOM1',
 PART_NUMBER='CH4104K1B00',
 VALUE='0.1UF',
 PRIM_FILE='./archive_libs/logical/q_cap/chips/chips.prt';

PART_NAME
 C1864 'Q_CAP_0402-0.1UF,25V,10%,X7R,CH4104K1B00':
 ROOM='PCIE REDRIVER BOM1';

SECTION_NUMBER 1
 '@T6G_MB_LIB.T6G(SCH_1):PAGE110_I62@PURE_QUANTA.Q_CAP(CHIPS)':
 C_PATH='@t6g_mb_lib.t6g(sch_1):page110_i62@pure_quanta.q_cap(chips)',
 P_PATH='@t6g_mb_lib.t6g(sch_1):page111_i62@pure_quanta.q_cap(chips)',
 PATH='I62',
 DRAWING='@T6G_MB_LIB.T6G(SCH_1):PAGE110',
 TOLERANCE='10%',
 MATERIAL='X7R',
 PHYS_PAGE='111',
 XY='(3275,5875)',
 ROT='0',
 VER='1',
 PACK_TYPE='0402',
 LOCATION='C1864',
 CDS_LIB='pure_quanta',
 CDS_PART_NAME='Q_CAP_0402-0.1UF,25V,10%,X7R,CH4104K1B00',
 VOLTAGE='25V',
 ROOM='PCIE REDRIVER BOM1',
 PART_NUMBER='CH4104K1B00',
 VALUE='0.1UF',
 PRIM_FILE='./archive_libs/logical/q_cap/chips/chips.prt';

PART_NAME
 C1865 'Q_CAP_0402-0.1UF,25V,10%,X7R,CH4104K1B00':
 ROOM='PCIE REDRIVER BOM1';

SECTION_NUMBER 1
 '@T6G_MB_LIB.T6G(SCH_1):PAGE110_I64@PURE_QUANTA.Q_CAP(CHIPS)':
 C_PATH='@t6g_mb_lib.t6g(sch_1):page110_i64@pure_quanta.q_cap(chips)',
 P_PATH='@t6g_mb_lib.t6g(sch_1):page111_i64@pure_quanta.q_cap(chips)',
 PATH='I64',
 DRAWING='@T6G_MB_LIB.T6G(SCH_1):PAGE110',
 TOLERANCE='10%',
 MATERIAL='X7R',
 PHYS_PAGE='111',
 XY='(3750,5875)',
 ROT='0',
 VER='1',
 PACK_TYPE='0402',
 LOCATION='C1865',
 CDS_LIB='pure_quanta',
 CDS_PART_NAME='Q_CAP_0402-0.1UF,25V,10%,X7R,CH4104K1B00',
 VOLTAGE='25V',
 ROOM='PCIE REDRIVER BOM1',
 PART_NUMBER='CH4104K1B00',
 VALUE='0.1UF',
 PRIM_FILE='./archive_libs/logical/q_cap/chips/chips.prt';

PART_NAME
 C1866 'Q_CAP_0402-0.1UF,25V,10%,X7R,CH4104K1B00':
 ROOM='PCIE REDRIVER BOM1';

SECTION_NUMBER 1
 '@T6G_MB_LIB.T6G(SCH_1):PAGE110_I65@PURE_QUANTA.Q_CAP(CHIPS)':
 C_PATH='@t6g_mb_lib.t6g(sch_1):page110_i65@pure_quanta.q_cap(chips)',
 P_PATH='@t6g_mb_lib.t6g(sch_1):page111_i65@pure_quanta.q_cap(chips)',
 PATH='I65',
 DRAWING='@T6G_MB_LIB.T6G(SCH_1):PAGE110',
 TOLERANCE='10%',
 MATERIAL='X7R',
 PHYS_PAGE='111',
 XY='(4225,5875)',
 ROT='0',
 VER='1',
 PACK_TYPE='0402',
 LOCATION='C1866',
 CDS_LIB='pure_quanta',
 CDS_PART_NAME='Q_CAP_0402-0.1UF,25V,10%,X7R,CH4104K1B00',
 VOLTAGE='25V',
 ROOM='PCIE REDRIVER BOM1',
 PART_NUMBER='CH4104K1B00',
 VALUE='0.1UF',
 PRIM_FILE='./archive_libs/logical/q_cap/chips/chips.prt';

PART_NAME
 C1867 'Q_CAP_C0805-10UF,25V,10%,X6S,CH6104KEA00':
 ROOM='PCIE REDRIVER BOM1';

SECTION_NUMBER 1
 '@T6G_MB_LIB.T6G(SCH_1):PAGE110_I60@PURE_QUANTA.Q_CAP(CHIPS)':
 C_PATH='@t6g_mb_lib.t6g(sch_1):page110_i60@pure_quanta.q_cap(chips)',
 P_PATH='@t6g_mb_lib.t6g(sch_1):page111_i60@pure_quanta.q_cap(chips)',
 PATH='I60',
 DRAWING='@T6G_MB_LIB.T6G(SCH_1):PAGE110',
 TOLERANCE='10%',
 MATERIAL='X6S',
 PHYS_PAGE='111',
 XY='(2275,5875)',
 ROT='0',
 VER='1',
 PACK_TYPE='C0805',
 LOCATION='C1867',
 CDS_LIB='pure_quanta',
 CDS_PART_NAME='Q_CAP_C0805-10UF,25V,10%,X6S,CH6104KEA00',
 VOLTAGE='25V',
 ROOM='PCIE REDRIVER BOM1',
 PART_NUMBER='CH6104KEA00',
 VALUE='10UF',
 PRIM_FILE='./archive_libs/logical/q_cap/chips/chips.prt';

PART_NAME
 C1868 'Q_CAP_0402-0.1UF,25V,10%,X7R,CH4104K1B00':
 ROOM='PCIE REDRIVER BOM1';

SECTION_NUMBER 1
 '@T6G_MB_LIB.T6G(SCH_1):PAGE112_I11@PURE_QUANTA.Q_CAP(CHIPS)':
 C_PATH='@t6g_mb_lib.t6g(sch_1):page112_i11@pure_quanta.q_cap(chips)',
 P_PATH='@t6g_mb_lib.t6g(sch_1):page113_i11@pure_quanta.q_cap(chips)',
 PATH='I11',
 DRAWING='@T6G_MB_LIB.T6G(SCH_1):PAGE112',
 TOLERANCE='10%',
 MATERIAL='X7R',
 PHYS_PAGE='113',
 XY='(-2550,4275)',
 ROT='0',
 VER='2',
 PACK_TYPE='0402',
 LOCATION='C1868',
 CDS_LIB='pure_quanta',
 CDS_PART_NAME='Q_CAP_0402-0.1UF,25V,10%,X7R,CH4104K1B00',
 VOLTAGE='25V',
 ROOM='PCIE REDRIVER BOM1',
 PART_NUMBER='CH4104K1B00',
 VALUE='0.1UF',
 PRIM_FILE='./archive_libs/logical/q_cap/chips/chips.prt';

PART_NAME
 C1869 'Q_CAP_0402-0.1UF,25V,10%,X7R,CH4104K1B00':
 ROOM='PCIE REDRIVER BOM1';

SECTION_NUMBER 1
 '@T6G_MB_LIB.T6G(SCH_1):PAGE112_I12@PURE_QUANTA.Q_CAP(CHIPS)':
 C_PATH='@t6g_mb_lib.t6g(sch_1):page112_i12@pure_quanta.q_cap(chips)',
 P_PATH='@t6g_mb_lib.t6g(sch_1):page113_i12@pure_quanta.q_cap(chips)',
 PATH='I12',
 DRAWING='@T6G_MB_LIB.T6G(SCH_1):PAGE112',
 TOLERANCE='10%',
 MATERIAL='X7R',
 PHYS_PAGE='113',
 XY='(-2550,4225)',
 ROT='0',
 VER='2',
 PACK_TYPE='0402',
 LOCATION='C1869',
 CDS_LIB='pure_quanta',
 CDS_PART_NAME='Q_CAP_0402-0.1UF,25V,10%,X7R,CH4104K1B00',
 VOLTAGE='25V',
 ROOM='PCIE REDRIVER BOM1',
 PART_NUMBER='CH4104K1B00',
 VALUE='0.1UF',
 PRIM_FILE='./archive_libs/logical/q_cap/chips/chips.prt';

PART_NAME
 C1870 'Q_CAP_0402-0.1UF,25V,10%,X7R,CH4104K1B00':
 ROOM='PCIE REDRIVER BOM1';

SECTION_NUMBER 1
 '@T6G_MB_LIB.T6G(SCH_1):PAGE112_I13@PURE_QUANTA.Q_CAP(CHIPS)':
 C_PATH='@t6g_mb_lib.t6g(sch_1):page112_i13@pure_quanta.q_cap(chips)',
 P_PATH='@t6g_mb_lib.t6g(sch_1):page113_i13@pure_quanta.q_cap(chips)',
 PATH='I13',
 DRAWING='@T6G_MB_LIB.T6G(SCH_1):PAGE112',
 TOLERANCE='10%',
 MATERIAL='X7R',
 PHYS_PAGE='113',
 XY='(-2700,5250)',
 ROT='0',
 VER='2',
 PACK_TYPE='0402',
 LOCATION='C1870',
 CDS_LIB='pure_quanta',
 CDS_PART_NAME='Q_CAP_0402-0.1UF,25V,10%,X7R,CH4104K1B00',
 VOLTAGE='25V',
 ROOM='PCIE REDRIVER BOM1',
 PART_NUMBER='CH4104K1B00',
 VALUE='0.1UF',
 PRIM_FILE='./archive_libs/logical/q_cap/chips/chips.prt';

PART_NAME
 C1871 'Q_CAP_0402-0.1UF,25V,10%,X7R,CH4104K1B00':
 ROOM='PCIE REDRIVER BOM1';

SECTION_NUMBER 1
 '@T6G_MB_LIB.T6G(SCH_1):PAGE112_I14@PURE_QUANTA.Q_CAP(CHIPS)':
 C_PATH='@t6g_mb_lib.t6g(sch_1):page112_i14@pure_quanta.q_cap(chips)',
 P_PATH='@t6g_mb_lib.t6g(sch_1):page113_i14@pure_quanta.q_cap(chips)',
 PATH='I14',
 DRAWING='@T6G_MB_LIB.T6G(SCH_1):PAGE112',
 TOLERANCE='10%',
 MATERIAL='X7R',
 PHYS_PAGE='113',
 XY='(-2700,5200)',
 ROT='0',
 VER='2',
 PACK_TYPE='0402',
 LOCATION='C1871',
 CDS_LIB='pure_quanta',
 CDS_PART_NAME='Q_CAP_0402-0.1UF,25V,10%,X7R,CH4104K1B00',
 VOLTAGE='25V',
 ROOM='PCIE REDRIVER BOM1',
 PART_NUMBER='CH4104K1B00',
 VALUE='0.1UF',
 PRIM_FILE='./archive_libs/logical/q_cap/chips/chips.prt';

PART_NAME
 C1873 'Q_CAP_0402-0.1UF,25V,10%,X7R,CH4104K1B00':;

SECTION_NUMBER 1
 '@T6G_MB_LIB.T6G(SCH_1):PAGE345_I56@PURE_QUANTA.Q_CAP(CHIPS)':
 C_PATH='@t6g_mb_lib.t6g(sch_1):page345_i56@pure_quanta.q_cap(chips)',
 P_PATH='@t6g_mb_lib.t6g(sch_1):page144_i56@pure_quanta.q_cap(chips)',
 PATH='I56',
 DRAWING='@T6G_MB_LIB.T6G(SCH_1):PAGE345',
 BOM_COST='VR_SYSTEM ',
 TOLERANCE='10%',
 MATERIAL='X7R',
 PHYS_PAGE='144',
 XY='(9550,1450)',
 ROT='0',
 VER='1',
 PACK_TYPE='0402',
 LOCATION='C1873',
 CDS_LIB='pure_quanta',
 CDS_PART_NAME='Q_CAP_0402-0.1UF,25V,10%,X7R,CH4104K1B00',
 VOLTAGE='25V',
 PART_NUMBER='CH4104K1B00',
 VALUE='0.1UF',
 PRIM_FILE='./archive_libs/logical/q_cap/chips/chips.prt';

PART_NAME
 C1874 'Q_CAP_0402-0.1UF,25V,10%,X7R,CH4104K1B00':;

SECTION_NUMBER 1
 '@T6G_MB_LIB.T6G(SCH_1):PAGE258_I22@PURE_QUANTA.Q_CAP(CHIPS)':
 C_PATH='@t6g_mb_lib.t6g(sch_1):page258_i22@pure_quanta.q_cap(chips)',
 P_PATH='@t6g_mb_lib.t6g(sch_1):page143_i22@pure_quanta.q_cap(chips)',
 PATH='I22',
 DRAWING='@T6G_MB_LIB.T6G(SCH_1):PAGE258',
 TOLERANCE='10%',
 MATERIAL='X7R',
 PHYS_PAGE='143',
 XY='(-2475,3250)',
 ROT='0',
 VER='1',
 PACK_TYPE='0402',
 LOCATION='C1874',
 CDS_LIB='pure_quanta',
 CDS_PART_NAME='Q_CAP_0402-0.1UF,25V,10%,X7R,CH4104K1B00',
 VOLTAGE='25V',
 PART_NUMBER='CH4104K1B00',
 VALUE='0.1UF',
 PRIM_FILE='./archive_libs/logical/q_cap/chips/chips.prt';

PART_NAME
 C1875 'Q_CAP_0402-0.1UF,25V,10%,X7R,CH4104K1B00':;

SECTION_NUMBER 1
 '@T6G_MB_LIB.T6G(SCH_1):PAGE258_I21@PURE_QUANTA.Q_CAP(CHIPS)':
 C_PATH='@t6g_mb_lib.t6g(sch_1):page258_i21@pure_quanta.q_cap(chips)',
 P_PATH='@t6g_mb_lib.t6g(sch_1):page143_i21@pure_quanta.q_cap(chips)',
 PATH='I21',
 DRAWING='@T6G_MB_LIB.T6G(SCH_1):PAGE258',
 TOLERANCE='10%',
 MATERIAL='X7R',
 PHYS_PAGE='143',
 XY='(-2375,1175)',
 ROT='0',
 VER='1',
 PACK_TYPE='0402',
 LOCATION='C1875',
 CDS_LIB='pure_quanta',
 CDS_PART_NAME='Q_CAP_0402-0.1UF,25V,10%,X7R,CH4104K1B00',
 VOLTAGE='25V',
 PART_NUMBER='CH4104K1B00',
 VALUE='0.1UF',
 PRIM_FILE='./archive_libs/logical/q_cap/chips/chips.prt';

PART_NAME
 C1876 'Q_CAP_0402-0.1UF,25V,10%,X7R,CH4104K1B00':;

SECTION_NUMBER 1
 '@T6G_MB_LIB.T6G(SCH_1):PAGE258_I41@PURE_QUANTA.Q_CAP(CHIPS)':
 C_PATH='@t6g_mb_lib.t6g(sch_1):page258_i41@pure_quanta.q_cap(chips)',
 P_PATH='@t6g_mb_lib.t6g(sch_1):page143_i41@pure_quanta.q_cap(chips)',
 PATH='I41',
 DRAWING='@T6G_MB_LIB.T6G(SCH_1):PAGE258',
 TOLERANCE='10%',
 MATERIAL='X7R',
 PHYS_PAGE='143',
 XY='(-325,2850)',
 ROT='0',
 VER='1',
 PACK_TYPE='0402',
 LOCATION='C1876',
 CDS_LIB='pure_quanta',
 CDS_PART_NAME='Q_CAP_0402-0.1UF,25V,10%,X7R,CH4104K1B00',
 VOLTAGE='25V',
 PART_NUMBER='CH4104K1B00',
 VALUE='0.1UF',
 PRIM_FILE='./archive_libs/logical/q_cap/chips/chips.prt';

PART_NAME
 C1877 'Q_CAP_0402-0.1UF,25V,10%,X7R,CH4104K1B00':;

SECTION_NUMBER 1
 '@T6G_MB_LIB.T6G(SCH_1):PAGE258_I34@PURE_QUANTA.Q_CAP(CHIPS)':
 C_PATH='@t6g_mb_lib.t6g(sch_1):page258_i34@pure_quanta.q_cap(chips)',
 P_PATH='@t6g_mb_lib.t6g(sch_1):page143_i34@pure_quanta.q_cap(chips)',
 PATH='I34',
 DRAWING='@T6G_MB_LIB.T6G(SCH_1):PAGE258',
 TOLERANCE='10%',
 MATERIAL='X7R',
 PHYS_PAGE='143',
 XY='(1325,2775)',
 ROT='0',
 VER='1',
 PACK_TYPE='0402',
 LOCATION='C1877',
 CDS_LIB='pure_quanta',
 CDS_PART_NAME='Q_CAP_0402-0.1UF,25V,10%,X7R,CH4104K1B00',
 VOLTAGE='25V',
 PART_NUMBER='CH4104K1B00',
 VALUE='0.1UF',
 PRIM_FILE='./archive_libs/logical/q_cap/chips/chips.prt';

PART_NAME
 C1878 'Q_CAP_0402-0.1UF,25V,10%,X7R,CH4104K1B00':;

SECTION_NUMBER 1
 '@T6G_MB_LIB.T6G(SCH_1):PAGE258_I37@PURE_QUANTA.Q_CAP(CHIPS)':
 C_PATH='@t6g_mb_lib.t6g(sch_1):page258_i37@pure_quanta.q_cap(chips)',
 P_PATH='@t6g_mb_lib.t6g(sch_1):page143_i37@pure_quanta.q_cap(chips)',
 PATH='I37',
 DRAWING='@T6G_MB_LIB.T6G(SCH_1):PAGE258',
 TOLERANCE='10%',
 MATERIAL='X7R',
 PHYS_PAGE='143',
 XY='(1350,1925)',
 ROT='0',
 VER='1',
 PACK_TYPE='0402',
 LOCATION='C1878',
 CDS_LIB='pure_quanta',
 CDS_PART_NAME='Q_CAP_0402-0.1UF,25V,10%,X7R,CH4104K1B00',
 VOLTAGE='25V',
 PART_NUMBER='CH4104K1B00',
 VALUE='0.1UF',
 PRIM_FILE='./archive_libs/logical/q_cap/chips/chips.prt';

PART_NAME
 C1879 'Q_CAP_0402-0.1UF,25V,10%,X7R,CH4104K1B00':;

SECTION_NUMBER 1
 '@T6G_MB_LIB.T6G(SCH_1):PAGE258_I31@PURE_QUANTA.Q_CAP(CHIPS)':
 C_PATH='@t6g_mb_lib.t6g(sch_1):page258_i31@pure_quanta.q_cap(chips)',
 P_PATH='@t6g_mb_lib.t6g(sch_1):page143_i31@pure_quanta.q_cap(chips)',
 PATH='I31',
 DRAWING='@T6G_MB_LIB.T6G(SCH_1):PAGE258',
 TOLERANCE='10%',
 MATERIAL='X7R',
 PHYS_PAGE='143',
 XY='(1525,-250)',
 ROT='0',
 VER='1',
 PACK_TYPE='0402',
 LOCATION='C1879',
 CDS_LIB='pure_quanta',
 CDS_PART_NAME='Q_CAP_0402-0.1UF,25V,10%,X7R,CH4104K1B00',
 VOLTAGE='25V',
 PART_NUMBER='CH4104K1B00',
 VALUE='0.1UF',
 PRIM_FILE='./archive_libs/logical/q_cap/chips/chips.prt';

PART_NAME
 C1880 'Q_CAP_0402-0.1UF,25V,10%,X7R,CH4104K1B00':;

SECTION_NUMBER 1
 '@T6G_MB_LIB.T6G(SCH_1):PAGE258_I27@PURE_QUANTA.Q_CAP(CHIPS)':
 C_PATH='@t6g_mb_lib.t6g(sch_1):page258_i27@pure_quanta.q_cap(chips)',
 P_PATH='@t6g_mb_lib.t6g(sch_1):page143_i27@pure_quanta.q_cap(chips)',
 PATH='I27',
 DRAWING='@T6G_MB_LIB.T6G(SCH_1):PAGE258',
 TOLERANCE='10%',
 MATERIAL='X7R',
 PHYS_PAGE='143',
 XY='(1525,575)',
 ROT='0',
 VER='1',
 PACK_TYPE='0402',
 LOCATION='C1880',
 CDS_LIB='pure_quanta',
 CDS_PART_NAME='Q_CAP_0402-0.1UF,25V,10%,X7R,CH4104K1B00',
 VOLTAGE='25V',
 PART_NUMBER='CH4104K1B00',
 VALUE='0.1UF',
 PRIM_FILE='./archive_libs/logical/q_cap/chips/chips.prt';

PART_NAME
 C1881 'Q_CAP_0402-0.1UF,25V,10%,X7R,CH4104K1B00':;

SECTION_NUMBER 1
 '@T6G_MB_LIB.T6G(SCH_1):PAGE333_I156@PURE_QUANTA.Q_CAP(CHIPS)':
 C_PATH='@t6g_mb_lib.t6g(sch_1):page333_i156@pure_quanta.q_cap(chips)',
 P_PATH='@t6g_mb_lib.t6g(sch_1):page127_i156@pure_quanta.q_cap(chips)',
 PATH='I156',
 DRAWING='@T6G_MB_LIB.T6G(SCH_1):PAGE333',
 TOLERANCE='10%',
 MATERIAL='X7R',
 PHYS_PAGE='127',
 XY='(2900,3325)',
 ROT='0',
 VER='1',
 PACK_TYPE='0402',
 LOCATION='C1881',
 CDS_LIB='pure_quanta',
 CDS_PART_NAME='Q_CAP_0402-0.1UF,25V,10%,X7R,CH4104K1B00',
 VOLTAGE='25V',
 PART_NUMBER='CH4104K1B00',
 VALUE='0.1UF',
 PRIM_FILE='./archive_libs/logical/q_cap/chips/chips.prt';

PART_NAME
 C1882 'Q_CAP_0402-0.1UF,25V,10%,X7R,CH4104K1B00':;

SECTION_NUMBER 1
 '@T6G_MB_LIB.T6G(SCH_1):PAGE232_I28@PURE_QUANTA.Q_CAP(CHIPS)':
 C_PATH='@t6g_mb_lib.t6g(sch_1):page232_i28@pure_quanta.q_cap(chips)',
 P_PATH='@t6g_mb_lib.t6g(sch_1):page233_i28@pure_quanta.q_cap(chips)',
 PATH='I28',
 DRAWING='@T6G_MB_LIB.T6G(SCH_1):PAGE232',
 TOLERANCE='10%',
 MATERIAL='X7R',
 PHYS_PAGE='233',
 XY='(-5275,2125)',
 ROT='0',
 VER='1',
 PACK_TYPE='0402',
 LOCATION='C1882',
 CDS_LIB='pure_quanta',
 CDS_PART_NAME='Q_CAP_0402-0.1UF,25V,10%,X7R,CH4104K1B00',
 VOLTAGE='25V',
 PART_NUMBER='CH4104K1B00',
 VALUE='0.1UF',
 PRIM_FILE='./archive_libs/logical/q_cap/chips/chips.prt';

PART_NAME
 C1883 'Q_CAP_C0805-10UF,25V,10%,X6S,CH6104KEA00':;

SECTION_NUMBER 1
 '@T6G_MB_LIB.T6G(SCH_1):PAGE232_I36@PURE_QUANTA.Q_CAP(CHIPS)':
 C_PATH='@t6g_mb_lib.t6g(sch_1):page232_i36@pure_quanta.q_cap(chips)',
 P_PATH='@t6g_mb_lib.t6g(sch_1):page233_i36@pure_quanta.q_cap(chips)',
 PATH='I36',
 DRAWING='@T6G_MB_LIB.T6G(SCH_1):PAGE232',
 TOLERANCE='10%',
 MATERIAL='X6S',
 PHYS_PAGE='233',
 XY='(-5700,5200)',
 ROT='0',
 VER='1',
 PACK_TYPE='C0805',
 LOCATION='C1883',
 CDS_LIB='pure_quanta',
 CDS_PART_NAME='Q_CAP_C0805-10UF,25V,10%,X6S,CH6104KEA00',
 VOLTAGE='25V',
 PART_NUMBER='CH6104KEA00',
 VALUE='10UF',
 PRIM_FILE='./archive_libs/logical/q_cap/chips/chips.prt';

PART_NAME
 C1884 'Q_CAP_C0402-1UF,25V,10%,X6S,CH5104KEB02':;

SECTION_NUMBER 1
 '@T6G_MB_LIB.T6G(SCH_1):PAGE232_I68@PURE_QUANTA.Q_CAP(CHIPS)':
 C_PATH='@t6g_mb_lib.t6g(sch_1):page232_i68@pure_quanta.q_cap(chips)',
 P_PATH='@t6g_mb_lib.t6g(sch_1):page233_i68@pure_quanta.q_cap(chips)',
 PATH='I68',
 DRAWING='@T6G_MB_LIB.T6G(SCH_1):PAGE232',
 BOM_COST='VR_SYSTEM ',
 TOLERANCE='10%',
 MATERIAL='X6S',
 PHYS_PAGE='233',
 XY='(-3950,5175)',
 ROT='0',
 VER='1',
 PACK_TYPE='C0402',
 LOCATION='C1884',
 CDS_LIB='pure_quanta',
 CDS_PART_NAME='Q_CAP_C0402-1UF,25V,10%,X6S,CH5104KEB02',
 VOLTAGE='25V',
 PART_NUMBER='CH5104KEB02',
 VALUE='1UF',
 PRIM_FILE='./archive_libs/logical/q_cap/chips/chips.prt';

PART_NAME
 C1886 'Q_CAP_0402-0.1UF,25V,10%,X7R,CH4104K1B00':;

SECTION_NUMBER 1
 '@T6G_MB_LIB.T6G(SCH_1):PAGE232_I40@PURE_QUANTA.Q_CAP(CHIPS)':
 C_PATH='@t6g_mb_lib.t6g(sch_1):page232_i40@pure_quanta.q_cap(chips)',
 P_PATH='@t6g_mb_lib.t6g(sch_1):page233_i40@pure_quanta.q_cap(chips)',
 PATH='I40',
 DRAWING='@T6G_MB_LIB.T6G(SCH_1):PAGE232',
 TOLERANCE='10%',
 MATERIAL='X7R',
 PHYS_PAGE='233',
 XY='(-4975,5200)',
 ROT='0',
 VER='1',
 PACK_TYPE='0402',
 LOCATION='C1886',
 CDS_LIB='pure_quanta',
 CDS_PART_NAME='Q_CAP_0402-0.1UF,25V,10%,X7R,CH4104K1B00',
 VOLTAGE='25V',
 PART_NUMBER='CH4104K1B00',
 VALUE='0.1UF',
 PRIM_FILE='./archive_libs/logical/q_cap/chips/chips.prt';

PART_NAME
 C1889 'Q_CAP_0402-0.1UF,25V,10%,X7R,CH4104K1B00':;

SECTION_NUMBER 1
 '@T6G_MB_LIB.T6G(SCH_1):PAGE232_I41@PURE_QUANTA.Q_CAP(CHIPS)':
 C_PATH='@t6g_mb_lib.t6g(sch_1):page232_i41@pure_quanta.q_cap(chips)',
 P_PATH='@t6g_mb_lib.t6g(sch_1):page233_i41@pure_quanta.q_cap(chips)',
 PATH='I41',
 DRAWING='@T6G_MB_LIB.T6G(SCH_1):PAGE232',
 TOLERANCE='10%',
 MATERIAL='X7R',
 PHYS_PAGE='233',
 XY='(-4750,5200)',
 ROT='0',
 VER='1',
 PACK_TYPE='0402',
 LOCATION='C1889',
 CDS_LIB='pure_quanta',
 CDS_PART_NAME='Q_CAP_0402-0.1UF,25V,10%,X7R,CH4104K1B00',
 VOLTAGE='25V',
 PART_NUMBER='CH4104K1B00',
 VALUE='0.1UF',
 PRIM_FILE='./archive_libs/logical/q_cap/chips/chips.prt';

PART_NAME
 C1920 'Q_CAP_C0603-22UF,6.3V,20%,X6S,CH6221ME900':;

SECTION_NUMBER 1
 '@T6G_MB_LIB.T6G(SCH_1):PAGE345_I77@PURE_QUANTA.Q_CAP(CHIPS)':
 C_PATH='@t6g_mb_lib.t6g(sch_1):page345_i77@pure_quanta.q_cap(chips)',
 P_PATH='@t6g_mb_lib.t6g(sch_1):page144_i77@pure_quanta.q_cap(chips)',
 PATH='I77',
 DRAWING='@T6G_MB_LIB.T6G(SCH_1):PAGE345',
 TOLERANCE='20%',
 MATERIAL='X6S',
 PHYS_PAGE='144',
 XY='(11225,4200)',
 ROT='0',
 VER='1',
 PACK_TYPE='C0603',
 LOCATION='C1920',
 CDS_LIB='pure_quanta',
 CDS_PART_NAME='Q_CAP_C0603-22UF,6.3V,20%,X6S,CH6221ME900',
 VOLTAGE='6.3V',
 PART_NUMBER='CH6221ME900',
 VALUE='22UF',
 PRIM_FILE='./archive_libs/logical/q_cap/chips/chips.prt';

PART_NAME
 C1921 'Q_CAP_C0603-22UF,6.3V,20%,X6S,CH6221ME900':;

SECTION_NUMBER 1
 '@T6G_MB_LIB.T6G(SCH_1):PAGE345_I78@PURE_QUANTA.Q_CAP(CHIPS)':
 C_PATH='@t6g_mb_lib.t6g(sch_1):page345_i78@pure_quanta.q_cap(chips)',
 P_PATH='@t6g_mb_lib.t6g(sch_1):page144_i78@pure_quanta.q_cap(chips)',
 PATH='I78',
 DRAWING='@T6G_MB_LIB.T6G(SCH_1):PAGE345',
 TOLERANCE='20%',
 MATERIAL='X6S',
 PHYS_PAGE='144',
 XY='(11625,4200)',
 ROT='0',
 VER='1',
 PACK_TYPE='C0603',
 LOCATION='C1921',
 CDS_LIB='pure_quanta',
 CDS_PART_NAME='Q_CAP_C0603-22UF,6.3V,20%,X6S,CH6221ME900',
 VOLTAGE='6.3V',
 PART_NUMBER='CH6221ME900',
 VALUE='22UF',
 PRIM_FILE='./archive_libs/logical/q_cap/chips/chips.prt';

PART_NAME
 C1922 'Q_CAP_C0402-22UF,4V,20%,X6S,CH622KMEB02':;

SECTION_NUMBER 1
 '@T6G_MB_LIB.T6G(SCH_1):PAGE68_I45@PURE_QUANTA.Q_CAP(CHIPS)':
 C_PATH='@t6g_mb_lib.t6g(sch_1):page68_i45@pure_quanta.q_cap(chips)',
 P_PATH='@t6g_mb_lib.t6g(sch_1):page69_i45@pure_quanta.q_cap(chips)',
 PATH='I45',
 DRAWING='@T6G_MB_LIB.T6G(SCH_1):PAGE68',
 TOLERANCE='20%',
 MATERIAL='X6S',
 PHYS_PAGE='69',
 XY='(-8100,4475)',
 ROT='0',
 VER='1',
 PACK_TYPE='C0402',
 LOCATION='C1922',
 CDS_LIB='pure_quanta',
 CDS_PART_NAME='Q_CAP_C0402-22UF,4V,20%,X6S,CH622KMEB02',
 VOLTAGE='4V',
 PART_NUMBER='CH622KMEB02',
 VALUE='22UF',
 PRIM_FILE='./archive_libs/logical/q_cap/chips/chips.prt';

PART_NAME
 C1923 'Q_CAP_0402-0.1UF,25V,10%,X7R,CH4104K1B00':;

SECTION_NUMBER 1
 '@T6G_MB_LIB.T6G(SCH_1):PAGE345_I84@PURE_QUANTA.Q_CAP(CHIPS)':
 C_PATH='@t6g_mb_lib.t6g(sch_1):page345_i84@pure_quanta.q_cap(chips)',
 P_PATH='@t6g_mb_lib.t6g(sch_1):page144_i84@pure_quanta.q_cap(chips)',
 PATH='I84',
 DRAWING='@T6G_MB_LIB.T6G(SCH_1):PAGE345',
 TOLERANCE='10%',
 MATERIAL='X7R',
 PHYS_PAGE='144',
 XY='(12425,4200)',
 ROT='0',
 VER='1',
 PACK_TYPE='0402',
 LOCATION='C1923',
 CDS_LIB='pure_quanta',
 CDS_PART_NAME='Q_CAP_0402-0.1UF,25V,10%,X7R,CH4104K1B00',
 VOLTAGE='25V',
 PART_NUMBER='CH4104K1B00',
 VALUE='0.1UF',
 PRIM_FILE='./archive_libs/logical/q_cap/chips/chips.prt';

PART_NAME
 C1924 'Q_CAP_0402-0.1UF,25V,10%,X7R,CH4104K1B00':;

SECTION_NUMBER 1
 '@T6G_MB_LIB.T6G(SCH_1):PAGE345_I85@PURE_QUANTA.Q_CAP(CHIPS)':
 C_PATH='@t6g_mb_lib.t6g(sch_1):page345_i85@pure_quanta.q_cap(chips)',
 P_PATH='@t6g_mb_lib.t6g(sch_1):page144_i85@pure_quanta.q_cap(chips)',
 PATH='I85',
 DRAWING='@T6G_MB_LIB.T6G(SCH_1):PAGE345',
 TOLERANCE='10%',
 MATERIAL='X7R',
 PHYS_PAGE='144',
 XY='(12825,4200)',
 ROT='0',
 VER='1',
 PACK_TYPE='0402',
 LOCATION='C1924',
 CDS_LIB='pure_quanta',
 CDS_PART_NAME='Q_CAP_0402-0.1UF,25V,10%,X7R,CH4104K1B00',
 VOLTAGE='25V',
 PART_NUMBER='CH4104K1B00',
 VALUE='0.1UF',
 PRIM_FILE='./archive_libs/logical/q_cap/chips/chips.prt';

PART_NAME
 C1925 'Q_CAP_0402-0.1UF,25V,10%,X7R,CH4104K1B00':;

SECTION_NUMBER 1
 '@T6G_MB_LIB.T6G(SCH_1):PAGE345_I86@PURE_QUANTA.Q_CAP(CHIPS)':
 C_PATH='@t6g_mb_lib.t6g(sch_1):page345_i86@pure_quanta.q_cap(chips)',
 P_PATH='@t6g_mb_lib.t6g(sch_1):page144_i86@pure_quanta.q_cap(chips)',
 PATH='I86',
 DRAWING='@T6G_MB_LIB.T6G(SCH_1):PAGE345',
 TOLERANCE='10%',
 MATERIAL='X7R',
 PHYS_PAGE='144',
 XY='(13225,4200)',
 ROT='0',
 VER='1',
 PACK_TYPE='0402',
 LOCATION='C1925',
 CDS_LIB='pure_quanta',
 CDS_PART_NAME='Q_CAP_0402-0.1UF,25V,10%,X7R,CH4104K1B00',
 VOLTAGE='25V',
 PART_NUMBER='CH4104K1B00',
 VALUE='0.1UF',
 PRIM_FILE='./archive_libs/logical/q_cap/chips/chips.prt';

PART_NAME
 C1957 'Q_CAP_0402-0.1UF,25V,10%,X7R,CH4104K1B00':;

SECTION_NUMBER 1
 '@T6G_MB_LIB.T6G(SCH_1):PAGE334_I148@PURE_QUANTA.Q_CAP(CHIPS)':
 C_PATH='@t6g_mb_lib.t6g(sch_1):page334_i148@pure_quanta.q_cap(chips)',
 P_PATH='@t6g_mb_lib.t6g(sch_1):page128_i148@pure_quanta.q_cap(chips)',
 PATH='I148',
 DRAWING='@T6G_MB_LIB.T6G(SCH_1):PAGE334',
 TOLERANCE='10%',
 MATERIAL='X7R',
 PHYS_PAGE='128',
 XY='(-6075,2175)',
 ROT='0',
 VER='1',
 PACK_TYPE='0402',
 LOCATION='C1957',
 CDS_LIB='pure_quanta',
 CDS_PART_NAME='Q_CAP_0402-0.1UF,25V,10%,X7R,CH4104K1B00',
 VOLTAGE='25V',
 PART_NUMBER='CH4104K1B00',
 VALUE='0.1UF',
 PRIM_FILE='./archive_libs/logical/q_cap/chips/chips.prt';

PART_NAME
 C1958 'Q_CAP_0402-0.1UF,25V,10%,X7R,CH4104K1B00':;

SECTION_NUMBER 1
 '@T6G_MB_LIB.T6G(SCH_1):PAGE334_I29@PURE_QUANTA.Q_CAP(CHIPS)':
 C_PATH='@t6g_mb_lib.t6g(sch_1):page334_i29@pure_quanta.q_cap(chips)',
 P_PATH='@t6g_mb_lib.t6g(sch_1):page128_i29@pure_quanta.q_cap(chips)',
 PATH='I29',
 DRAWING='@T6G_MB_LIB.T6G(SCH_1):PAGE334',
 TOLERANCE='10%',
 MATERIAL='X7R',
 PHYS_PAGE='128',
 XY='(-5975,4500)',
 ROT='0',
 VER='1',
 PACK_TYPE='0402',
 LOCATION='C1958',
 CDS_LIB='pure_quanta',
 CDS_PART_NAME='Q_CAP_0402-0.1UF,25V,10%,X7R,CH4104K1B00',
 VOLTAGE='25V',
 PART_NUMBER='CH4104K1B00',
 VALUE='0.1UF',
 PRIM_FILE='./archive_libs/logical/q_cap/chips/chips.prt';

PART_NAME
 C1963 'Q_CAP_0402-0.1UF,25V,10%,X7R,CH4104K1B00':;

SECTION_NUMBER 1
 '@T6G_MB_LIB.T6G(SCH_1):PAGE255_I13@PURE_QUANTA.Q_CAP(CHIPS)':
 C_PATH='@t6g_mb_lib.t6g(sch_1):page255_i13@pure_quanta.q_cap(chips)',
 P_PATH='@t6g_mb_lib.t6g(sch_1):page129_i13@pure_quanta.q_cap(chips)',
 PATH='I13',
 DRAWING='@T6G_MB_LIB.T6G(SCH_1):PAGE255',
 TOLERANCE='10%',
 MATERIAL='X7R',
 PHYS_PAGE='129',
 XY='(1350,3550)',
 ROT='0',
 VER='1',
 PACK_TYPE='0402',
 LOCATION='C1963',
 CDS_LIB='pure_quanta',
 CDS_PART_NAME='Q_CAP_0402-0.1UF,25V,10%,X7R,CH4104K1B00',
 VOLTAGE='25V',
 PART_NUMBER='CH4104K1B00',
 VALUE='0.1UF',
 PRIM_FILE='./archive_libs/logical/q_cap/chips/chips.prt';

PART_NAME
 C1973 'Q_CAP_0402-0.1UF,25V,10%,X7R,CH4104K1B00':;

SECTION_NUMBER 1
 '@T6G_MB_LIB.T6G(SCH_1):PAGE299_I71@PURE_QUANTA.Q_CAP(CHIPS)':
 C_PATH='@t6g_mb_lib.t6g(sch_1):page299_i71@pure_quanta.q_cap(chips)',
 P_PATH='@t6g_mb_lib.t6g(sch_1):page126_i71@pure_quanta.q_cap(chips)',
 PATH='I71',
 DRAWING='@T6G_MB_LIB.T6G(SCH_1):PAGE299',
 TOLERANCE='10%',
 MATERIAL='X7R',
 PHYS_PAGE='126',
 XY='(50,2650)',
 ROT='0',
 VER='1',
 PACK_TYPE='0402',
 LOCATION='C1973',
 CDS_LIB='pure_quanta',
 CDS_PART_NAME='Q_CAP_0402-0.1UF,25V,10%,X7R,CH4104K1B00',
 VOLTAGE='25V',
 PART_NUMBER='CH4104K1B00',
 VALUE='0.1UF',
 PRIM_FILE='./archive_libs/logical/q_cap/chips/chips.prt';

PART_NAME
 C1974 'Q_CAP_0402-0.1UF,25V,10%,X7R,CH4104K1B00':;

SECTION_NUMBER 1
 '@T6G_MB_LIB.T6G(SCH_1):PAGE299_I74@PURE_QUANTA.Q_CAP(CHIPS)':
 C_PATH='@t6g_mb_lib.t6g(sch_1):page299_i74@pure_quanta.q_cap(chips)',
 P_PATH='@t6g_mb_lib.t6g(sch_1):page126_i74@pure_quanta.q_cap(chips)',
 PATH='I74',
 DRAWING='@T6G_MB_LIB.T6G(SCH_1):PAGE299',
 TOLERANCE='10%',
 MATERIAL='X7R',
 PHYS_PAGE='126',
 XY='(100,4025)',
 ROT='0',
 VER='1',
 PACK_TYPE='0402',
 LOCATION='C1974',
 CDS_LIB='pure_quanta',
 CDS_PART_NAME='Q_CAP_0402-0.1UF,25V,10%,X7R,CH4104K1B00',
 VOLTAGE='25V',
 PART_NUMBER='CH4104K1B00',
 VALUE='0.1UF',
 PRIM_FILE='./archive_libs/logical/q_cap/chips/chips.prt';

PART_NAME
 C1975 'Q_CAP_0402-0.1UF,25V,10%,X7R,CH4104K1B00':;

SECTION_NUMBER 1
 '@T6G_MB_LIB.T6G(SCH_1):PAGE299_I129@PURE_QUANTA.Q_CAP(CHIPS)':
 C_PATH='@t6g_mb_lib.t6g(sch_1):page299_i129@pure_quanta.q_cap(chips)',
 P_PATH='@t6g_mb_lib.t6g(sch_1):page126_i129@pure_quanta.q_cap(chips)',
 PATH='I129',
 DRAWING='@T6G_MB_LIB.T6G(SCH_1):PAGE299',
 TOLERANCE='10%',
 MATERIAL='X7R',
 PHYS_PAGE='126',
 XY='(100,1300)',
 ROT='0',
 VER='1',
 PACK_TYPE='0402',
 LOCATION='C1975',
 CDS_LIB='pure_quanta',
 CDS_PART_NAME='Q_CAP_0402-0.1UF,25V,10%,X7R,CH4104K1B00',
 VOLTAGE='25V',
 PART_NUMBER='CH4104K1B00',
 VALUE='0.1UF',
 PRIM_FILE='./archive_libs/logical/q_cap/chips/chips.prt';

PART_NAME
 C1976 'Q_CAP_0402-0.1UF,25V,10%,X7R,CH4104K1B00':;

SECTION_NUMBER 1
 '@T6G_MB_LIB.T6G(SCH_1):PAGE299_I30@PURE_QUANTA.Q_CAP(CHIPS)':
 C_PATH='@t6g_mb_lib.t6g(sch_1):page299_i30@pure_quanta.q_cap(chips)',
 P_PATH='@t6g_mb_lib.t6g(sch_1):page126_i30@pure_quanta.q_cap(chips)',
 PATH='I30',
 DRAWING='@T6G_MB_LIB.T6G(SCH_1):PAGE299',
 TOLERANCE='10%',
 MATERIAL='X7R',
 PHYS_PAGE='126',
 XY='(100,-450)',
 ROT='0',
 VER='1',
 PACK_TYPE='0402',
 LOCATION='C1976',
 CDS_LIB='pure_quanta',
 CDS_PART_NAME='Q_CAP_0402-0.1UF,25V,10%,X7R,CH4104K1B00',
 VOLTAGE='25V',
 PART_NUMBER='CH4104K1B00',
 VALUE='0.1UF',
 PRIM_FILE='./archive_libs/logical/q_cap/chips/chips.prt';

PART_NAME
 C1977 'Q_CAP_0402-0.1UF,25V,10%,X7R,CH4104K1B00':;

SECTION_NUMBER 1
 '@T6G_MB_LIB.T6G(SCH_1):PAGE334_I175@PURE_QUANTA.Q_CAP(CHIPS)':
 C_PATH='@t6g_mb_lib.t6g(sch_1):page334_i175@pure_quanta.q_cap(chips)',
 P_PATH='@t6g_mb_lib.t6g(sch_1):page128_i175@pure_quanta.q_cap(chips)',
 PATH='I175',
 DRAWING='@T6G_MB_LIB.T6G(SCH_1):PAGE334',
 TOLERANCE='10%',
 MATERIAL='X7R',
 PHYS_PAGE='128',
 XY='(-6175,300)',
 ROT='0',
 VER='1',
 PACK_TYPE='0402',
 LOCATION='C1977',
 CDS_LIB='pure_quanta',
 CDS_PART_NAME='Q_CAP_0402-0.1UF,25V,10%,X7R,CH4104K1B00',
 VOLTAGE='25V',
 PART_NUMBER='CH4104K1B00',
 VALUE='0.1UF',
 PRIM_FILE='./archive_libs/logical/q_cap/chips/chips.prt';

PART_NAME
 C1978 'Q_CAP_0402-0.1UF,25V,10%,X7R,CH4104K1B00':;

SECTION_NUMBER 1
 '@T6G_MB_LIB.T6G(SCH_1):PAGE299_I152@PURE_QUANTA.Q_CAP(CHIPS)':
 C_PATH='@t6g_mb_lib.t6g(sch_1):page299_i152@pure_quanta.q_cap(chips)',
 P_PATH='@t6g_mb_lib.t6g(sch_1):page126_i152@pure_quanta.q_cap(chips)',
 PATH='I152',
 DRAWING='@T6G_MB_LIB.T6G(SCH_1):PAGE299',
 TOLERANCE='10%',
 MATERIAL='X7R',
 PHYS_PAGE='126',
 XY='(4775,1550)',
 ROT='0',
 VER='1',
 PACK_TYPE='0402',
 LOCATION='C1978',
 CDS_LIB='pure_quanta',
 CDS_PART_NAME='Q_CAP_0402-0.1UF,25V,10%,X7R,CH4104K1B00',
 VOLTAGE='25V',
 PART_NUMBER='CH4104K1B00',
 VALUE='0.1UF',
 PRIM_FILE='./archive_libs/logical/q_cap/chips/chips.prt';

PART_NAME
 C1979 'Q_CAP_0402-0.1UF,25V,10%,X7R,CH4104K1B00':;

SECTION_NUMBER 1
 '@T6G_MB_LIB.T6G(SCH_1):PAGE255_I67@PURE_QUANTA.Q_CAP(CHIPS)':
 C_PATH='@t6g_mb_lib.t6g(sch_1):page255_i67@pure_quanta.q_cap(chips)',
 P_PATH='@t6g_mb_lib.t6g(sch_1):page129_i67@pure_quanta.q_cap(chips)',
 PATH='I67',
 DRAWING='@T6G_MB_LIB.T6G(SCH_1):PAGE255',
 TOLERANCE='10%',
 MATERIAL='X7R',
 PHYS_PAGE='129',
 XY='(1350,1050)',
 ROT='0',
 VER='1',
 PACK_TYPE='0402',
 LOCATION='C1979',
 CDS_LIB='pure_quanta',
 CDS_PART_NAME='Q_CAP_0402-0.1UF,25V,10%,X7R,CH4104K1B00',
 VOLTAGE='25V',
 PART_NUMBER='CH4104K1B00',
 VALUE='0.1UF',
 PRIM_FILE='./archive_libs/logical/q_cap/chips/chips.prt';

PART_NAME
 C1988 'Q_CAP_0402-0.1UF,25V,10%,X7R,CH4104K1B00':;

SECTION_NUMBER 1
 '@T6G_MB_LIB.T6G(SCH_1):PAGE299_I171@PURE_QUANTA.Q_CAP(CHIPS)':
 C_PATH='@t6g_mb_lib.t6g(sch_1):page299_i171@pure_quanta.q_cap(chips)',
 P_PATH='@t6g_mb_lib.t6g(sch_1):page126_i171@pure_quanta.q_cap(chips)',
 PATH='I171',
 DRAWING='@T6G_MB_LIB.T6G(SCH_1):PAGE299',
 TOLERANCE='10%',
 MATERIAL='X7R',
 PHYS_PAGE='126',
 XY='(4800,-175)',
 ROT='0',
 VER='1',
 PACK_TYPE='0402',
 LOCATION='C1988',
 CDS_LIB='pure_quanta',
 CDS_PART_NAME='Q_CAP_0402-0.1UF,25V,10%,X7R,CH4104K1B00',
 VOLTAGE='25V',
 PART_NUMBER='CH4104K1B00',
 VALUE='0.1UF',
 PRIM_FILE='./archive_libs/logical/q_cap/chips/chips.prt';

PART_NAME
 C1989 'Q_CAP_DIFFBUS_C0201-DIFF BUS_0.22UF,6.3V,20%,X6S,SA':;

SECTION_NUMBER 1
 '@T6G_MB_LIB.T6G(SCH_1):PAGE355_I8@PURE_QUANTA.Q_CAP_DIFFBUS(CHIPS)':
 C_PATH='@t6g_mb_lib.t6g(sch_1):page355_i8@pure_quanta.q_cap_diffbus(chips)',
 P_PATH='@t6g_mb_lib.t6g(sch_1):page67_i8@pure_quanta.q_cap_diffbus(chips)',
 PATH='I8',
 DRAWING='@T6G_MB_LIB.T6G(SCH_1):PAGE355',
 PIN_NAMES_ROTATE='TRUE',
 TOLERANCE='20%',
 MATERIAL='X6S',
 PHYS_PAGE='67',
 XY='(-1375,-500)',
 ROT='2',
 VER='2',
 PACK_TYPE='C0201',
 LOCATION='C1989',
 CDS_LIB='pure_quanta',
 CDS_PART_NAME='Q_CAP_DIFFBUS_C0201-DIFF BUS_0.22UF,6.3V,20%,X6S,SA',
 VOLTAGE='6.3V',
 PART_NUMBER='SP_CH4221MEE01',
 VALUE='DIFF BUS_0.22UF',
 PRIM_FILE='./archive_libs/logical/q_cap_diffbus/chips/chips.prt';

PART_NAME
 C1990 'Q_CAP_DIFFBUS_C0201-DIFF BUS_0.22UF,6.3V,20%,X6S,SA':;

SECTION_NUMBER 1
 '@T6G_MB_LIB.T6G(SCH_1):PAGE355_I7@PURE_QUANTA.Q_CAP_DIFFBUS(CHIPS)':
 C_PATH='@t6g_mb_lib.t6g(sch_1):page355_i7@pure_quanta.q_cap_diffbus(chips)',
 P_PATH='@t6g_mb_lib.t6g(sch_1):page67_i7@pure_quanta.q_cap_diffbus(chips)',
 PATH='I7',
 DRAWING='@T6G_MB_LIB.T6G(SCH_1):PAGE355',
 PIN_NAMES_ROTATE='TRUE',
 TOLERANCE='20%',
 MATERIAL='X6S',
 PHYS_PAGE='67',
 XY='(-1375,-550)',
 ROT='2',
 VER='2',
 PACK_TYPE='C0201',
 LOCATION='C1990',
 CDS_LIB='pure_quanta',
 CDS_PART_NAME='Q_CAP_DIFFBUS_C0201-DIFF BUS_0.22UF,6.3V,20%,X6S,SA',
 VOLTAGE='6.3V',
 PART_NUMBER='SP_CH4221MEE01',
 VALUE='DIFF BUS_0.22UF',
 PRIM_FILE='./archive_libs/logical/q_cap_diffbus/chips/chips.prt';

PART_NAME
 C1991 'Q_CAP_DIFFBUS_C0201-DIFF BUS_0.22UF,6.3V,20%,X6S,SA':;

SECTION_NUMBER 1
 '@T6G_MB_LIB.T6G(SCH_1):PAGE355_I10@PURE_QUANTA.Q_CAP_DIFFBUS(CHIPS)':
 C_PATH='@t6g_mb_lib.t6g(sch_1):page355_i10@pure_quanta.q_cap_diffbus(chips)',
 P_PATH='@t6g_mb_lib.t6g(sch_1):page67_i10@pure_quanta.q_cap_diffbus(chips)',
 PATH='I10',
 DRAWING='@T6G_MB_LIB.T6G(SCH_1):PAGE355',
 PIN_NAMES_ROTATE='TRUE',
 TOLERANCE='20%',
 MATERIAL='X6S',
 PHYS_PAGE='67',
 XY='(-1375,-300)',
 ROT='2',
 VER='2',
 PACK_TYPE='C0201',
 LOCATION='C1991',
 CDS_LIB='pure_quanta',
 CDS_PART_NAME='Q_CAP_DIFFBUS_C0201-DIFF BUS_0.22UF,6.3V,20%,X6S,SA',
 VOLTAGE='6.3V',
 PART_NUMBER='SP_CH4221MEE01',
 VALUE='DIFF BUS_0.22UF',
 PRIM_FILE='./archive_libs/logical/q_cap_diffbus/chips/chips.prt';

PART_NAME
 C1992 'Q_CAP_DIFFBUS_C0201-DIFF BUS_0.22UF,6.3V,20%,X6S,SA':;

SECTION_NUMBER 1
 '@T6G_MB_LIB.T6G(SCH_1):PAGE355_I9@PURE_QUANTA.Q_CAP_DIFFBUS(CHIPS)':
 C_PATH='@t6g_mb_lib.t6g(sch_1):page355_i9@pure_quanta.q_cap_diffbus(chips)',
 P_PATH='@t6g_mb_lib.t6g(sch_1):page67_i9@pure_quanta.q_cap_diffbus(chips)',
 PATH='I9',
 DRAWING='@T6G_MB_LIB.T6G(SCH_1):PAGE355',
 PIN_NAMES_ROTATE='TRUE',
 TOLERANCE='20%',
 MATERIAL='X6S',
 PHYS_PAGE='67',
 XY='(-1375,-350)',
 ROT='2',
 VER='2',
 PACK_TYPE='C0201',
 LOCATION='C1992',
 CDS_LIB='pure_quanta',
 CDS_PART_NAME='Q_CAP_DIFFBUS_C0201-DIFF BUS_0.22UF,6.3V,20%,X6S,SA',
 VOLTAGE='6.3V',
 PART_NUMBER='SP_CH4221MEE01',
 VALUE='DIFF BUS_0.22UF',
 PRIM_FILE='./archive_libs/logical/q_cap_diffbus/chips/chips.prt';

PART_NAME
 C1993 'Q_CAP_DIFFBUS_C0201-DIFF BUS_0.22UF,6.3V,20%,X6S,SA':;

SECTION_NUMBER 1
 '@T6G_MB_LIB.T6G(SCH_1):PAGE355_I12@PURE_QUANTA.Q_CAP_DIFFBUS(CHIPS)':
 C_PATH='@t6g_mb_lib.t6g(sch_1):page355_i12@pure_quanta.q_cap_diffbus(chips)',
 P_PATH='@t6g_mb_lib.t6g(sch_1):page67_i12@pure_quanta.q_cap_diffbus(chips)',
 PATH='I12',
 DRAWING='@T6G_MB_LIB.T6G(SCH_1):PAGE355',
 PIN_NAMES_ROTATE='TRUE',
 TOLERANCE='20%',
 MATERIAL='X6S',
 PHYS_PAGE='67',
 XY='(-1375,-100)',
 ROT='2',
 VER='2',
 PACK_TYPE='C0201',
 LOCATION='C1993',
 CDS_LIB='pure_quanta',
 CDS_PART_NAME='Q_CAP_DIFFBUS_C0201-DIFF BUS_0.22UF,6.3V,20%,X6S,SA',
 VOLTAGE='6.3V',
 PART_NUMBER='SP_CH4221MEE01',
 VALUE='DIFF BUS_0.22UF',
 PRIM_FILE='./archive_libs/logical/q_cap_diffbus/chips/chips.prt';

PART_NAME
 C1994 'Q_CAP_DIFFBUS_C0201-DIFF BUS_0.22UF,6.3V,20%,X6S,SA':;

SECTION_NUMBER 1
 '@T6G_MB_LIB.T6G(SCH_1):PAGE355_I11@PURE_QUANTA.Q_CAP_DIFFBUS(CHIPS)':
 C_PATH='@t6g_mb_lib.t6g(sch_1):page355_i11@pure_quanta.q_cap_diffbus(chips)',
 P_PATH='@t6g_mb_lib.t6g(sch_1):page67_i11@pure_quanta.q_cap_diffbus(chips)',
 PATH='I11',
 DRAWING='@T6G_MB_LIB.T6G(SCH_1):PAGE355',
 PIN_NAMES_ROTATE='TRUE',
 TOLERANCE='20%',
 MATERIAL='X6S',
 PHYS_PAGE='67',
 XY='(-1375,-150)',
 ROT='2',
 VER='2',
 PACK_TYPE='C0201',
 LOCATION='C1994',
 CDS_LIB='pure_quanta',
 CDS_PART_NAME='Q_CAP_DIFFBUS_C0201-DIFF BUS_0.22UF,6.3V,20%,X6S,SA',
 VOLTAGE='6.3V',
 PART_NUMBER='SP_CH4221MEE01',
 VALUE='DIFF BUS_0.22UF',
 PRIM_FILE='./archive_libs/logical/q_cap_diffbus/chips/chips.prt';

PART_NAME
 C1995 'Q_CAP_DIFFBUS_C0201-DIFF BUS_0.22UF,6.3V,20%,X6S,SA':;

SECTION_NUMBER 1
 '@T6G_MB_LIB.T6G(SCH_1):PAGE355_I52@PURE_QUANTA.Q_CAP_DIFFBUS(CHIPS)':
 C_PATH='@t6g_mb_lib.t6g(sch_1):page355_i52@pure_quanta.q_cap_diffbus(chips)',
 P_PATH='@t6g_mb_lib.t6g(sch_1):page67_i52@pure_quanta.q_cap_diffbus(chips)',
 PATH='I52',
 DRAWING='@T6G_MB_LIB.T6G(SCH_1):PAGE355',
 PIN_NAMES_ROTATE='TRUE',
 TOLERANCE='20%',
 MATERIAL='X6S',
 PHYS_PAGE='67',
 XY='(-1375,100)',
 ROT='2',
 VER='2',
 PACK_TYPE='C0201',
 LOCATION='C1995',
 CDS_LIB='pure_quanta',
 CDS_PART_NAME='Q_CAP_DIFFBUS_C0201-DIFF BUS_0.22UF,6.3V,20%,X6S,SA',
 VOLTAGE='6.3V',
 PART_NUMBER='SP_CH4221MEE01',
 VALUE='DIFF BUS_0.22UF',
 PRIM_FILE='./archive_libs/logical/q_cap_diffbus/chips/chips.prt';

PART_NAME
 C1996 'Q_CAP_DIFFBUS_C0201-DIFF BUS_0.22UF,6.3V,20%,X6S,SA':;

SECTION_NUMBER 1
 '@T6G_MB_LIB.T6G(SCH_1):PAGE355_I51@PURE_QUANTA.Q_CAP_DIFFBUS(CHIPS)':
 C_PATH='@t6g_mb_lib.t6g(sch_1):page355_i51@pure_quanta.q_cap_diffbus(chips)',
 P_PATH='@t6g_mb_lib.t6g(sch_1):page67_i51@pure_quanta.q_cap_diffbus(chips)',
 PATH='I51',
 DRAWING='@T6G_MB_LIB.T6G(SCH_1):PAGE355',
 PIN_NAMES_ROTATE='TRUE',
 TOLERANCE='20%',
 MATERIAL='X6S',
 PHYS_PAGE='67',
 XY='(-1375,50)',
 ROT='2',
 VER='2',
 PACK_TYPE='C0201',
 LOCATION='C1996',
 CDS_LIB='pure_quanta',
 CDS_PART_NAME='Q_CAP_DIFFBUS_C0201-DIFF BUS_0.22UF,6.3V,20%,X6S,SA',
 VOLTAGE='6.3V',
 PART_NUMBER='SP_CH4221MEE01',
 VALUE='DIFF BUS_0.22UF',
 PRIM_FILE='./archive_libs/logical/q_cap_diffbus/chips/chips.prt';

PART_NAME
 C1997 'Q_CAP_0402-0.1UF,25V,10%,X7R,CH4104K1B00':;

SECTION_NUMBER 1
 '@T6G_MB_LIB.T6G(SCH_1):PAGE346_I89@PURE_QUANTA.Q_CAP(CHIPS)':
 C_PATH='@t6g_mb_lib.t6g(sch_1):page346_i89@pure_quanta.q_cap(chips)',
 P_PATH='@t6g_mb_lib.t6g(sch_1):page148_i89@pure_quanta.q_cap(chips)',
 PATH='I89',
 DRAWING='@T6G_MB_LIB.T6G(SCH_1):PAGE346',
 TOLERANCE='10%',
 MATERIAL='X7R',
 PHYS_PAGE='148',
 XY='(-350,1625)',
 ROT='2',
 VER='1',
 PACK_TYPE='0402',
 LOCATION='C1997',
 CDS_LIB='pure_quanta',
 CDS_PART_NAME='Q_CAP_0402-0.1UF,25V,10%,X7R,CH4104K1B00',
 VOLTAGE='25V',
 PART_NUMBER='CH4104K1B00',
 VALUE='0.1UF',
 PRIM_FILE='./archive_libs/logical/q_cap/chips/chips.prt';

PART_NAME
 C1998 'Q_CAP_0402-0.1UF,25V,10%,X7R,CH4104K1B00':;

SECTION_NUMBER 1
 '@T6G_MB_LIB.T6G(SCH_1):PAGE346_I82@PURE_QUANTA.Q_CAP(CHIPS)':
 C_PATH='@t6g_mb_lib.t6g(sch_1):page346_i82@pure_quanta.q_cap(chips)',
 P_PATH='@t6g_mb_lib.t6g(sch_1):page148_i82@pure_quanta.q_cap(chips)',
 PATH='I82',
 DRAWING='@T6G_MB_LIB.T6G(SCH_1):PAGE346',
 TOLERANCE='10%',
 MATERIAL='X7R',
 PHYS_PAGE='148',
 XY='(1600,1650)',
 ROT='0',
 VER='1',
 PACK_TYPE='0402',
 LOCATION='C1998',
 CDS_LIB='pure_quanta',
 CDS_PART_NAME='Q_CAP_0402-0.1UF,25V,10%,X7R,CH4104K1B00',
 VOLTAGE='25V',
 PART_NUMBER='CH4104K1B00',
 VALUE='0.1UF',
 PRIM_FILE='./archive_libs/logical/q_cap/chips/chips.prt';

PART_NAME
 C2007 'Q_CAP_C0402-1UF,25V,10%,X6S,CH5104KEB02':;

SECTION_NUMBER 1
 '@T6G_MB_LIB.T6G(SCH_1):PAGE345_I6@PURE_QUANTA.Q_CAP(CHIPS)':
 C_PATH='@t6g_mb_lib.t6g(sch_1):page345_i6@pure_quanta.q_cap(chips)',
 P_PATH='@t6g_mb_lib.t6g(sch_1):page144_i6@pure_quanta.q_cap(chips)',
 PATH='I6',
 DRAWING='@T6G_MB_LIB.T6G(SCH_1):PAGE345',
 BOM_COST='VR_SYSTEM ',
 TOLERANCE='10%',
 MATERIAL='X6S',
 PHYS_PAGE='144',
 XY='(8000,-825)',
 ROT='0',
 VER='1',
 PACK_TYPE='C0402',
 LOCATION='C2007',
 CDS_LIB='pure_quanta',
 CDS_PART_NAME='Q_CAP_C0402-1UF,25V,10%,X6S,CH5104KEB02',
 VOLTAGE='25V',
 PART_NUMBER='CH5104KEB02',
 VALUE='1UF',
 PRIM_FILE='./archive_libs/logical/q_cap/chips/chips.prt';

PART_NAME
 C2010 'Q_CAP_0402-0.1UF,25V,10%,X7R,CH4104K1B00':;

SECTION_NUMBER 1
 '@T6G_MB_LIB.T6G(SCH_1):PAGE359_I16@PURE_QUANTA.Q_CAP(CHIPS)':
 C_PATH='@t6g_mb_lib.t6g(sch_1):page359_i16@pure_quanta.q_cap(chips)',
 P_PATH='@t6g_mb_lib.t6g(sch_1):page235_i16@pure_quanta.q_cap(chips)',
 PATH='I16',
 DRAWING='@T6G_MB_LIB.T6G(SCH_1):PAGE359',
 TOLERANCE='10%',
 MATERIAL='X7R',
 PHYS_PAGE='235',
 XY='(2600,1950)',
 ROT='2',
 VER='1',
 PACK_TYPE='0402',
 LOCATION='C2010',
 CDS_LIB='pure_quanta',
 CDS_PART_NAME='Q_CAP_0402-0.1UF,25V,10%,X7R,CH4104K1B00',
 VOLTAGE='25V',
 PART_NUMBER='CH4104K1B00',
 VALUE='0.1UF',
 PRIM_FILE='./archive_libs/logical/q_cap/chips/chips.prt';

PART_NAME
 C2012 'Q_CAP_0402-0.1UF,25V,10%,X7R,CH4104K1B00':;

SECTION_NUMBER 1
 '@T6G_MB_LIB.T6G(SCH_1):PAGE360_I98@PURE_QUANTA.Q_CAP(CHIPS)':
 C_PATH='@t6g_mb_lib.t6g(sch_1):page360_i98@pure_quanta.q_cap(chips)',
 P_PATH='@t6g_mb_lib.t6g(sch_1):page237_i98@pure_quanta.q_cap(chips)',
 PATH='I98',
 DRAWING='@T6G_MB_LIB.T6G(SCH_1):PAGE360',
 TOLERANCE='10%',
 MATERIAL='X7R',
 PHYS_PAGE='237',
 XY='(1025,725)',
 ROT='0',
 VER='1',
 PACK_TYPE='0402',
 LOCATION='C2012',
 CDS_LIB='pure_quanta',
 CDS_PART_NAME='Q_CAP_0402-0.1UF,25V,10%,X7R,CH4104K1B00',
 VOLTAGE='25V',
 PART_NUMBER='CH4104K1B00',
 VALUE='0.1UF',
 PRIM_FILE='./archive_libs/logical/q_cap/chips/chips.prt';

PART_NAME
 C2013 'Q_CAP_0402-0.1UF,25V,10%,X7R,CH4104K1B00':;

SECTION_NUMBER 1
 '@T6G_MB_LIB.T6G(SCH_1):PAGE360_I42@PURE_QUANTA.Q_CAP(CHIPS)':
 C_PATH='@t6g_mb_lib.t6g(sch_1):page360_i42@pure_quanta.q_cap(chips)',
 P_PATH='@t6g_mb_lib.t6g(sch_1):page237_i42@pure_quanta.q_cap(chips)',
 PATH='I42',
 DRAWING='@T6G_MB_LIB.T6G(SCH_1):PAGE360',
 TOLERANCE='10%',
 MATERIAL='X7R',
 PHYS_PAGE='237',
 XY='(600,-1375)',
 ROT='0',
 VER='1',
 PACK_TYPE='0402',
 LOCATION='C2013',
 CDS_LIB='pure_quanta',
 CDS_PART_NAME='Q_CAP_0402-0.1UF,25V,10%,X7R,CH4104K1B00',
 VOLTAGE='25V',
 PART_NUMBER='CH4104K1B00',
 VALUE='0.1UF',
 PRIM_FILE='./archive_libs/logical/q_cap/chips/chips.prt';

PART_NAME
 C2014 'Q_CAP_0402-0.1UF,25V,10%,X7R,CH4104K1B00':;

SECTION_NUMBER 1
 '@T6G_MB_LIB.T6G(SCH_1):PAGE360_I65@PURE_QUANTA.Q_CAP(CHIPS)':
 C_PATH='@t6g_mb_lib.t6g(sch_1):page360_i65@pure_quanta.q_cap(chips)',
 P_PATH='@t6g_mb_lib.t6g(sch_1):page237_i65@pure_quanta.q_cap(chips)',
 PATH='I65',
 DRAWING='@T6G_MB_LIB.T6G(SCH_1):PAGE360',
 TOLERANCE='10%',
 MATERIAL='X7R',
 PHYS_PAGE='237',
 XY='(725,-3525)',
 ROT='0',
 VER='1',
 PACK_TYPE='0402',
 LOCATION='C2014',
 CDS_LIB='pure_quanta',
 CDS_PART_NAME='Q_CAP_0402-0.1UF,25V,10%,X7R,CH4104K1B00',
 VOLTAGE='25V',
 PART_NUMBER='CH4104K1B00',
 VALUE='0.1UF',
 PRIM_FILE='./archive_libs/logical/q_cap/chips/chips.prt';

PART_NAME
 C2015 'Q_CAP_0402-0.1UF,25V,10%,X7R,CH4104K1B00':;

SECTION_NUMBER 1
 '@T6G_MB_LIB.T6G(SCH_1):PAGE295_I34@PURE_QUANTA.Q_CAP(CHIPS)':
 C_PATH='@t6g_mb_lib.t6g(sch_1):page295_i34@pure_quanta.q_cap(chips)',
 P_PATH='@t6g_mb_lib.t6g(sch_1):page236_i34@pure_quanta.q_cap(chips)',
 PATH='I34',
 DRAWING='@T6G_MB_LIB.T6G(SCH_1):PAGE295',
 TOLERANCE='10%',
 MATERIAL='X7R',
 PHYS_PAGE='236',
 XY='(2175,3675)',
 ROT='0',
 VER='1',
 PACK_TYPE='0402',
 LOCATION='C2015',
 CDS_LIB='pure_quanta',
 CDS_PART_NAME='Q_CAP_0402-0.1UF,25V,10%,X7R,CH4104K1B00',
 VOLTAGE='25V',
 PART_NUMBER='CH4104K1B00',
 VALUE='0.1UF',
 PRIM_FILE='./archive_libs/logical/q_cap/chips/chips.prt';

PART_NAME
 C2017 'Q_CAP_0402-0.1UF,25V,10%,X7R,CH4104K1B00':;

SECTION_NUMBER 1
 '@T6G_MB_LIB.T6G(SCH_1):PAGE360_I114@PURE_QUANTA.Q_CAP(CHIPS)':
 C_PATH='@t6g_mb_lib.t6g(sch_1):page360_i114@pure_quanta.q_cap(chips)',
 P_PATH='@t6g_mb_lib.t6g(sch_1):page237_i114@pure_quanta.q_cap(chips)',
 PATH='I114',
 DRAWING='@T6G_MB_LIB.T6G(SCH_1):PAGE360',
 TOLERANCE='10%',
 MATERIAL='X7R',
 PHYS_PAGE='237',
 XY='(-1650,300)',
 ROT='0',
 VER='1',
 PACK_TYPE='0402',
 LOCATION='C2017',
 CDS_LIB='pure_quanta',
 CDS_PART_NAME='Q_CAP_0402-0.1UF,25V,10%,X7R,CH4104K1B00',
 VOLTAGE='25V',
 PART_NUMBER='CH4104K1B00',
 VALUE='0.1UF',
 PRIM_FILE='./archive_libs/logical/q_cap/chips/chips.prt';

PART_NAME
 C2018 'Q_CAP_0402-0.1UF,25V,10%,X7R,CH4104K1B00':;

SECTION_NUMBER 1
 '@T6G_MB_LIB.T6G(SCH_1):PAGE360_I26@PURE_QUANTA.Q_CAP(CHIPS)':
 C_PATH='@t6g_mb_lib.t6g(sch_1):page360_i26@pure_quanta.q_cap(chips)',
 P_PATH='@t6g_mb_lib.t6g(sch_1):page237_i26@pure_quanta.q_cap(chips)',
 PATH='I26',
 DRAWING='@T6G_MB_LIB.T6G(SCH_1):PAGE360',
 TOLERANCE='10%',
 MATERIAL='X7R',
 PHYS_PAGE='237',
 XY='(-2075,-1800)',
 ROT='0',
 VER='1',
 PACK_TYPE='0402',
 LOCATION='C2018',
 CDS_LIB='pure_quanta',
 CDS_PART_NAME='Q_CAP_0402-0.1UF,25V,10%,X7R,CH4104K1B00',
 VOLTAGE='25V',
 PART_NUMBER='CH4104K1B00',
 VALUE='0.1UF',
 PRIM_FILE='./archive_libs/logical/q_cap/chips/chips.prt';

PART_NAME
 C2019 'Q_CAP_0402-0.1UF,25V,10%,X7R,CH4104K1B00':;

SECTION_NUMBER 1
 '@T6G_MB_LIB.T6G(SCH_1):PAGE360_I49@PURE_QUANTA.Q_CAP(CHIPS)':
 C_PATH='@t6g_mb_lib.t6g(sch_1):page360_i49@pure_quanta.q_cap(chips)',
 P_PATH='@t6g_mb_lib.t6g(sch_1):page237_i49@pure_quanta.q_cap(chips)',
 PATH='I49',
 DRAWING='@T6G_MB_LIB.T6G(SCH_1):PAGE360',
 TOLERANCE='10%',
 MATERIAL='X7R',
 PHYS_PAGE='237',
 XY='(-1950,-3950)',
 ROT='0',
 VER='1',
 PACK_TYPE='0402',
 LOCATION='C2019',
 CDS_LIB='pure_quanta',
 CDS_PART_NAME='Q_CAP_0402-0.1UF,25V,10%,X7R,CH4104K1B00',
 VOLTAGE='25V',
 PART_NUMBER='CH4104K1B00',
 VALUE='0.1UF',
 PRIM_FILE='./archive_libs/logical/q_cap/chips/chips.prt';

PART_NAME
 C2020 'Q_CAP_0402-0.1UF,25V,10%,X7R,CH4104K1B00':;

SECTION_NUMBER 1
 '@T6G_MB_LIB.T6G(SCH_1):PAGE360_I108@PURE_QUANTA.Q_CAP(CHIPS)':
 C_PATH='@t6g_mb_lib.t6g(sch_1):page360_i108@pure_quanta.q_cap(chips)',
 P_PATH='@t6g_mb_lib.t6g(sch_1):page237_i108@pure_quanta.q_cap(chips)',
 PATH='I108',
 DRAWING='@T6G_MB_LIB.T6G(SCH_1):PAGE360',
 TOLERANCE='10%',
 MATERIAL='X7R',
 PHYS_PAGE='237',
 XY='(500,-625)',
 ROT='0',
 VER='1',
 PACK_TYPE='0402',
 LOCATION='C2020',
 CDS_LIB='pure_quanta',
 CDS_PART_NAME='Q_CAP_0402-0.1UF,25V,10%,X7R,CH4104K1B00',
 VOLTAGE='25V',
 PART_NUMBER='CH4104K1B00',
 VALUE='0.1UF',
 PRIM_FILE='./archive_libs/logical/q_cap/chips/chips.prt';

PART_NAME
 C2021 'Q_CAP_0402-0.1UF,25V,10%,X7R,CH4104K1B00':;

SECTION_NUMBER 1
 '@T6G_MB_LIB.T6G(SCH_1):PAGE360_I71@PURE_QUANTA.Q_CAP(CHIPS)':
 C_PATH='@t6g_mb_lib.t6g(sch_1):page360_i71@pure_quanta.q_cap(chips)',
 P_PATH='@t6g_mb_lib.t6g(sch_1):page237_i71@pure_quanta.q_cap(chips)',
 PATH='I71',
 DRAWING='@T6G_MB_LIB.T6G(SCH_1):PAGE360',
 TOLERANCE='10%',
 MATERIAL='X7R',
 PHYS_PAGE='237',
 XY='(75,-2725)',
 ROT='0',
 VER='1',
 PACK_TYPE='0402',
 LOCATION='C2021',
 CDS_LIB='pure_quanta',
 CDS_PART_NAME='Q_CAP_0402-0.1UF,25V,10%,X7R,CH4104K1B00',
 VOLTAGE='25V',
 PART_NUMBER='CH4104K1B00',
 VALUE='0.1UF',
 PRIM_FILE='./archive_libs/logical/q_cap/chips/chips.prt';

PART_NAME
 C2022 'Q_CAP_0402-0.1UF,25V,10%,X7R,CH4104K1B00':;

SECTION_NUMBER 1
 '@T6G_MB_LIB.T6G(SCH_1):PAGE360_I72@PURE_QUANTA.Q_CAP(CHIPS)':
 C_PATH='@t6g_mb_lib.t6g(sch_1):page360_i72@pure_quanta.q_cap(chips)',
 P_PATH='@t6g_mb_lib.t6g(sch_1):page237_i72@pure_quanta.q_cap(chips)',
 PATH='I72',
 DRAWING='@T6G_MB_LIB.T6G(SCH_1):PAGE360',
 TOLERANCE='10%',
 MATERIAL='X7R',
 PHYS_PAGE='237',
 XY='(200,-4875)',
 ROT='0',
 VER='1',
 PACK_TYPE='0402',
 LOCATION='C2022',
 CDS_LIB='pure_quanta',
 CDS_PART_NAME='Q_CAP_0402-0.1UF,25V,10%,X7R,CH4104K1B00',
 VOLTAGE='25V',
 PART_NUMBER='CH4104K1B00',
 VALUE='0.1UF',
 PRIM_FILE='./archive_libs/logical/q_cap/chips/chips.prt';

PART_NAME
 C2024 'Q_CAP_0402-0.1UF,25V,10%,X7R,CH4104K1B00':;

SECTION_NUMBER 1
 '@T6G_MB_LIB.T6G(SCH_1):PAGE295_I50@PURE_QUANTA.Q_CAP(CHIPS)':
 C_PATH='@t6g_mb_lib.t6g(sch_1):page295_i50@pure_quanta.q_cap(chips)',
 P_PATH='@t6g_mb_lib.t6g(sch_1):page236_i50@pure_quanta.q_cap(chips)',
 PATH='I50',
 DRAWING='@T6G_MB_LIB.T6G(SCH_1):PAGE295',
 TOLERANCE='10%',
 MATERIAL='X7R',
 PHYS_PAGE='236',
 XY='(-500,3250)',
 ROT='0',
 VER='1',
 PACK_TYPE='0402',
 LOCATION='C2024',
 CDS_LIB='pure_quanta',
 CDS_PART_NAME='Q_CAP_0402-0.1UF,25V,10%,X7R,CH4104K1B00',
 VOLTAGE='25V',
 PART_NUMBER='CH4104K1B00',
 VALUE='0.1UF',
 PRIM_FILE='./archive_libs/logical/q_cap/chips/chips.prt';

PART_NAME
 C2027 'Q_CAP_0402-0.1UF,25V,10%,X7R,CH4104K1B00':;

SECTION_NUMBER 1
 '@T6G_MB_LIB.T6G(SCH_1):PAGE295_I77@PURE_QUANTA.Q_CAP(CHIPS)':
 C_PATH='@t6g_mb_lib.t6g(sch_1):page295_i77@pure_quanta.q_cap(chips)',
 P_PATH='@t6g_mb_lib.t6g(sch_1):page236_i77@pure_quanta.q_cap(chips)',
 PATH='I77',
 DRAWING='@T6G_MB_LIB.T6G(SCH_1):PAGE295',
 TOLERANCE='10%',
 MATERIAL='X7R',
 PHYS_PAGE='236',
 XY='(1650,2325)',
 ROT='0',
 VER='1',
 PACK_TYPE='0402',
 LOCATION='C2027',
 CDS_LIB='pure_quanta',
 CDS_PART_NAME='Q_CAP_0402-0.1UF,25V,10%,X7R,CH4104K1B00',
 VOLTAGE='25V',
 PART_NUMBER='CH4104K1B00',
 VALUE='0.1UF',
 PRIM_FILE='./archive_libs/logical/q_cap/chips/chips.prt';

PART_NAME
 C2029 'Q_CAP_0402-15PF,50V,5%,C0G,CH01506JB06':
 ROOM='USB2 BOM1';

SECTION_NUMBER 1
 '@T6G_MB_LIB.T6G(SCH_1):PAGE358_I212@PURE_QUANTA.Q_CAP(CHIPS)':
 C_PATH='@t6g_mb_lib.t6g(sch_1):page358_i212@pure_quanta.q_cap(chips)',
 P_PATH='@t6g_mb_lib.t6g(sch_1):page234_i212@pure_quanta.q_cap(chips)',
 PATH='I212',
 DRAWING='@T6G_MB_LIB.T6G(SCH_1):PAGE358',
 TOLERANCE='5%',
 MATERIAL='C0G',
 PHYS_PAGE='234',
 XY='(3475,4375)',
 ROT='0',
 VER='1',
 PACK_TYPE='0402',
 LOCATION='C2029',
 CDS_LIB='pure_quanta',
 CDS_PART_NAME='Q_CAP_0402-15PF,50V,5%,C0G,CH01506JB06',
 VOLTAGE='50V',
 ROOM='USB2 BOM1',
 PART_NUMBER='CH01506JB06',
 VALUE='15PF',
 PRIM_FILE='./archive_libs/logical/q_cap/chips/chips.prt';

PART_NAME
 C2030 'Q_CAP_0402-15PF,50V,5%,C0G,CH01506JB06':
 ROOM='USB2 BOM1';

SECTION_NUMBER 1
 '@T6G_MB_LIB.T6G(SCH_1):PAGE358_I211@PURE_QUANTA.Q_CAP(CHIPS)':
 C_PATH='@t6g_mb_lib.t6g(sch_1):page358_i211@pure_quanta.q_cap(chips)',
 P_PATH='@t6g_mb_lib.t6g(sch_1):page234_i211@pure_quanta.q_cap(chips)',
 PATH='I211',
 DRAWING='@T6G_MB_LIB.T6G(SCH_1):PAGE358',
 TOLERANCE='5%',
 MATERIAL='C0G',
 PHYS_PAGE='234',
 XY='(4475,4375)',
 ROT='0',
 VER='1',
 PACK_TYPE='0402',
 LOCATION='C2030',
 CDS_LIB='pure_quanta',
 CDS_PART_NAME='Q_CAP_0402-15PF,50V,5%,C0G,CH01506JB06',
 VOLTAGE='50V',
 ROOM='USB2 BOM1',
 PART_NUMBER='CH01506JB06',
 VALUE='15PF',
 PRIM_FILE='./archive_libs/logical/q_cap/chips/chips.prt';

PART_NAME
 C2031 'Q_CAP_C0402-1UF,25V,10%,X6S,CH5104KEB02':
 ROOM='USB2 BOM1';

SECTION_NUMBER 1
 '@T6G_MB_LIB.T6G(SCH_1):PAGE358_I148@PURE_QUANTA.Q_CAP(CHIPS)':
 C_PATH='@t6g_mb_lib.t6g(sch_1):page358_i148@pure_quanta.q_cap(chips)',
 P_PATH='@t6g_mb_lib.t6g(sch_1):page234_i148@pure_quanta.q_cap(chips)',
 PATH='I148',
 DRAWING='@T6G_MB_LIB.T6G(SCH_1):PAGE358',
 TOLERANCE='10%',
 MATERIAL='X6S',
 PHYS_PAGE='234',
 XY='(-2300,4500)',
 ROT='0',
 VER='1',
 PACK_TYPE='C0402',
 LOCATION='C2031',
 CDS_LIB='pure_quanta',
 CDS_PART_NAME='Q_CAP_C0402-1UF,25V,10%,X6S,CH5104KEB02',
 VOLTAGE='25V',
 ROOM='USB2 BOM1',
 PART_NUMBER='CH5104KEB02',
 VALUE='1UF',
 PRIM_FILE='./archive_libs/logical/q_cap/chips/chips.prt';

PART_NAME
 C2032 'Q_CAP_0402-0.1UF,25V,10%,X7R,CH4104K1B00':
 ROOM='USB2 BOM1';

SECTION_NUMBER 1
 '@T6G_MB_LIB.T6G(SCH_1):PAGE358_I145@PURE_QUANTA.Q_CAP(CHIPS)':
 C_PATH='@t6g_mb_lib.t6g(sch_1):page358_i145@pure_quanta.q_cap(chips)',
 P_PATH='@t6g_mb_lib.t6g(sch_1):page234_i145@pure_quanta.q_cap(chips)',
 PATH='I145',
 DRAWING='@T6G_MB_LIB.T6G(SCH_1):PAGE358',
 TOLERANCE='10%',
 MATERIAL='X7R',
 PHYS_PAGE='234',
 XY='(-1925,4500)',
 ROT='2',
 VER='1',
 PACK_TYPE='0402',
 LOCATION='C2032',
 CDS_LIB='pure_quanta',
 CDS_PART_NAME='Q_CAP_0402-0.1UF,25V,10%,X7R,CH4104K1B00',
 VOLTAGE='25V',
 ROOM='USB2 BOM1',
 PART_NUMBER='CH4104K1B00',
 VALUE='0.1UF',
 PRIM_FILE='./archive_libs/logical/q_cap/chips/chips.prt';

PART_NAME
 C2033 'Q_CAP_0402-0.1UF,25V,10%,X7R,CH4104K1B00':
 ROOM='USB2 BOM1';

SECTION_NUMBER 1
 '@T6G_MB_LIB.T6G(SCH_1):PAGE358_I143@PURE_QUANTA.Q_CAP(CHIPS)':
 C_PATH='@t6g_mb_lib.t6g(sch_1):page358_i143@pure_quanta.q_cap(chips)',
 P_PATH='@t6g_mb_lib.t6g(sch_1):page234_i143@pure_quanta.q_cap(chips)',
 PATH='I143',
 DRAWING='@T6G_MB_LIB.T6G(SCH_1):PAGE358',
 TOLERANCE='10%',
 MATERIAL='X7R',
 PHYS_PAGE='234',
 XY='(-1550,4500)',
 ROT='2',
 VER='1',
 PACK_TYPE='0402',
 LOCATION='C2033',
 CDS_LIB='pure_quanta',
 CDS_PART_NAME='Q_CAP_0402-0.1UF,25V,10%,X7R,CH4104K1B00',
 VOLTAGE='25V',
 ROOM='USB2 BOM1',
 PART_NUMBER='CH4104K1B00',
 VALUE='0.1UF',
 PRIM_FILE='./archive_libs/logical/q_cap/chips/chips.prt';

PART_NAME
 C2034 'Q_CAP_0402-0.1UF,25V,10%,X7R,CH4104K1B00':
 ROOM='USB2 BOM1';

SECTION_NUMBER 1
 '@T6G_MB_LIB.T6G(SCH_1):PAGE358_I142@PURE_QUANTA.Q_CAP(CHIPS)':
 C_PATH='@t6g_mb_lib.t6g(sch_1):page358_i142@pure_quanta.q_cap(chips)',
 P_PATH='@t6g_mb_lib.t6g(sch_1):page234_i142@pure_quanta.q_cap(chips)',
 PATH='I142',
 DRAWING='@T6G_MB_LIB.T6G(SCH_1):PAGE358',
 TOLERANCE='10%',
 MATERIAL='X7R',
 PHYS_PAGE='234',
 XY='(-1175,4500)',
 ROT='2',
 VER='1',
 PACK_TYPE='0402',
 LOCATION='C2034',
 CDS_LIB='pure_quanta',
 CDS_PART_NAME='Q_CAP_0402-0.1UF,25V,10%,X7R,CH4104K1B00',
 VOLTAGE='25V',
 ROOM='USB2 BOM1',
 PART_NUMBER='CH4104K1B00',
 VALUE='0.1UF',
 PRIM_FILE='./archive_libs/logical/q_cap/chips/chips.prt';

PART_NAME
 C2035 'Q_CAP_C0402-1UF,25V,10%,X6S,CH5104KEB02':
 ROOM='USB2 BOM1';

SECTION_NUMBER 1
 '@T6G_MB_LIB.T6G(SCH_1):PAGE358_I147@PURE_QUANTA.Q_CAP(CHIPS)':
 C_PATH='@t6g_mb_lib.t6g(sch_1):page358_i147@pure_quanta.q_cap(chips)',
 P_PATH='@t6g_mb_lib.t6g(sch_1):page234_i147@pure_quanta.q_cap(chips)',
 PATH='I147',
 DRAWING='@T6G_MB_LIB.T6G(SCH_1):PAGE358',
 TOLERANCE='10%',
 MATERIAL='X6S',
 PHYS_PAGE='234',
 XY='(-825,4500)',
 ROT='0',
 VER='1',
 PACK_TYPE='C0402',
 LOCATION='C2035',
 CDS_LIB='pure_quanta',
 CDS_PART_NAME='Q_CAP_C0402-1UF,25V,10%,X6S,CH5104KEB02',
 VOLTAGE='25V',
 ROOM='USB2 BOM1',
 PART_NUMBER='CH5104KEB02',
 VALUE='1UF',
 PRIM_FILE='./archive_libs/logical/q_cap/chips/chips.prt';

PART_NAME
 C2038 'Q_CAP_C0402-10UF,6.3V,20%,X6S,CH6101MEB01':
 ROOM='USB2 BOM1';

SECTION_NUMBER 1
 '@T6G_MB_LIB.T6G(SCH_1):PAGE358_I164@PURE_QUANTA.Q_CAP(CHIPS)':
 C_PATH='@t6g_mb_lib.t6g(sch_1):page358_i164@pure_quanta.q_cap(chips)',
 P_PATH='@t6g_mb_lib.t6g(sch_1):page234_i164@pure_quanta.q_cap(chips)',
 PATH='I164',
 DRAWING='@T6G_MB_LIB.T6G(SCH_1):PAGE358',
 TOLERANCE='20%',
 MATERIAL='X6S',
 PHYS_PAGE='234',
 XY='(-3450,4500)',
 ROT='0',
 VER='1',
 PACK_TYPE='C0402',
 LOCATION='C2038',
 CDS_LIB='pure_quanta',
 CDS_PART_NAME='Q_CAP_C0402-10UF,6.3V,20%,X6S,CH6101MEB01',
 VOLTAGE='6.3V',
 ROOM='USB2 BOM1',
 PART_NUMBER='CH6101MEB01',
 VALUE='10UF',
 PRIM_FILE='./archive_libs/logical/q_cap/chips/chips.prt';

PART_NAME
 C2039 'Q_CAP_0402-0.1UF,25V,10%,X7R,CH4104K1B00':
 ROOM='USB2 BOM1';

SECTION_NUMBER 1
 '@T6G_MB_LIB.T6G(SCH_1):PAGE358_I163@PURE_QUANTA.Q_CAP(CHIPS)':
 C_PATH='@t6g_mb_lib.t6g(sch_1):page358_i163@pure_quanta.q_cap(chips)',
 P_PATH='@t6g_mb_lib.t6g(sch_1):page234_i163@pure_quanta.q_cap(chips)',
 PATH='I163',
 DRAWING='@T6G_MB_LIB.T6G(SCH_1):PAGE358',
 TOLERANCE='10%',
 MATERIAL='X7R',
 PHYS_PAGE='234',
 XY='(-3075,4500)',
 ROT='2',
 VER='1',
 PACK_TYPE='0402',
 LOCATION='C2039',
 CDS_LIB='pure_quanta',
 CDS_PART_NAME='Q_CAP_0402-0.1UF,25V,10%,X7R,CH4104K1B00',
 VOLTAGE='25V',
 ROOM='USB2 BOM1',
 PART_NUMBER='CH4104K1B00',
 VALUE='0.1UF',
 PRIM_FILE='./archive_libs/logical/q_cap/chips/chips.prt';

PART_NAME
 C2040 'Q_CAP_0402-0.1UF,25V,10%,X7R,CH4104K1B00':
 ROOM='USB2 BOM1';

SECTION_NUMBER 1
 '@T6G_MB_LIB.T6G(SCH_1):PAGE358_I162@PURE_QUANTA.Q_CAP(CHIPS)':
 C_PATH='@t6g_mb_lib.t6g(sch_1):page358_i162@pure_quanta.q_cap(chips)',
 P_PATH='@t6g_mb_lib.t6g(sch_1):page234_i162@pure_quanta.q_cap(chips)',
 PATH='I162',
 DRAWING='@T6G_MB_LIB.T6G(SCH_1):PAGE358',
 TOLERANCE='10%',
 MATERIAL='X7R',
 PHYS_PAGE='234',
 XY='(-2675,4500)',
 ROT='2',
 VER='1',
 PACK_TYPE='0402',
 LOCATION='C2040',
 CDS_LIB='pure_quanta',
 CDS_PART_NAME='Q_CAP_0402-0.1UF,25V,10%,X7R,CH4104K1B00',
 VOLTAGE='25V',
 ROOM='USB2 BOM1',
 PART_NUMBER='CH4104K1B00',
 VALUE='0.1UF',
 PRIM_FILE='./archive_libs/logical/q_cap/chips/chips.prt';

PART_NAME
 C2041 'Q_CAP_C0402-1UF,25V,10%,X6S,CH5104KEB02':;

SECTION_NUMBER 1
 '@T6G_MB_LIB.T6G(SCH_1):PAGE358_I158@PURE_QUANTA.Q_CAP(CHIPS)':
 C_PATH='@t6g_mb_lib.t6g(sch_1):page358_i158@pure_quanta.q_cap(chips)',
 P_PATH='@t6g_mb_lib.t6g(sch_1):page234_i158@pure_quanta.q_cap(chips)',
 PATH='I158',
 DRAWING='@T6G_MB_LIB.T6G(SCH_1):PAGE358',
 TOLERANCE='10%',
 MATERIAL='X6S',
 PHYS_PAGE='234',
 XY='(-2275,3150)',
 ROT='0',
 VER='1',
 PACK_TYPE='C0402',
 LOCATION='C2041',
 CDS_LIB='pure_quanta',
 CDS_PART_NAME='Q_CAP_C0402-1UF,25V,10%,X6S,CH5104KEB02',
 VOLTAGE='25V',
 PART_NUMBER='CH5104KEB02',
 VALUE='1UF',
 PRIM_FILE='./archive_libs/logical/q_cap/chips/chips.prt';

PART_NAME
 C2042 'Q_CAP_0402-100PF,50V,5%,EMPTY,CH11006JB18':
 ROOM='ADC_MAM_BOM2';

SECTION_NUMBER 1
 '@T6G_MB_LIB.T6G(SCH_1):PAGE369_I99@PURE_QUANTA.Q_CAP(CHIPS)':
 C_PATH='@t6g_mb_lib.t6g(sch_1):page369_i99@pure_quanta.q_cap(chips)',
 P_PATH='@t6g_mb_lib.t6g(sch_1):page257_i99@pure_quanta.q_cap(chips)',
 PATH='I99',
 DRAWING='@T6G_MB_LIB.T6G(SCH_1):PAGE369',
 TOLERANCE='5%',
 MATERIAL='EMPTY',
 PHYS_PAGE='257',
 XY='(-7475,5575)',
 ROT='0',
 VER='1',
 PACK_TYPE='0402',
 LOCATION='C2042',
 CDS_LIB='pure_quanta',
 CDS_PART_NAME='Q_CAP_0402-100PF,50V,5%,EMPTY,CH11006JB18',
 VOLTAGE='50V',
 ROOM='ADC_MAM_BOM2',
 PART_NUMBER='CH11006JB18',
 VALUE='100PF',
 PRIM_FILE='./archive_libs/logical/q_cap/chips/chips.prt';

PART_NAME
 C2043 'Q_CAP_0402-100PF,50V,5%,EMPTY,CH11006JB18':
 ROOM='ADC_MAM_BOM2';

SECTION_NUMBER 1
 '@T6G_MB_LIB.T6G(SCH_1):PAGE369_I55@PURE_QUANTA.Q_CAP(CHIPS)':
 C_PATH='@t6g_mb_lib.t6g(sch_1):page369_i55@pure_quanta.q_cap(chips)',
 P_PATH='@t6g_mb_lib.t6g(sch_1):page257_i55@pure_quanta.q_cap(chips)',
 PATH='I55',
 DRAWING='@T6G_MB_LIB.T6G(SCH_1):PAGE369',
 TOLERANCE='5%',
 MATERIAL='EMPTY',
 PHYS_PAGE='257',
 XY='(-7550,4225)',
 ROT='0',
 VER='1',
 PACK_TYPE='0402',
 LOCATION='C2043',
 CDS_LIB='pure_quanta',
 CDS_PART_NAME='Q_CAP_0402-100PF,50V,5%,EMPTY,CH11006JB18',
 VOLTAGE='50V',
 ROOM='ADC_MAM_BOM2',
 PART_NUMBER='CH11006JB18',
 VALUE='100PF',
 PRIM_FILE='./archive_libs/logical/q_cap/chips/chips.prt';

PART_NAME
 C2044 'Q_CAP_0402-100PF,50V,5%,EMPTY,CH11006JB18':
 ROOM='ADC_MAM_BOM2';

SECTION_NUMBER 1
 '@T6G_MB_LIB.T6G(SCH_1):PAGE369_I52@PURE_QUANTA.Q_CAP(CHIPS)':
 C_PATH='@t6g_mb_lib.t6g(sch_1):page369_i52@pure_quanta.q_cap(chips)',
 P_PATH='@t6g_mb_lib.t6g(sch_1):page257_i52@pure_quanta.q_cap(chips)',
 PATH='I52',
 DRAWING='@T6G_MB_LIB.T6G(SCH_1):PAGE369',
 TOLERANCE='5%',
 MATERIAL='EMPTY',
 PHYS_PAGE='257',
 XY='(-7575,3075)',
 ROT='0',
 VER='1',
 PACK_TYPE='0402',
 LOCATION='C2044',
 CDS_LIB='pure_quanta',
 CDS_PART_NAME='Q_CAP_0402-100PF,50V,5%,EMPTY,CH11006JB18',
 VOLTAGE='50V',
 ROOM='ADC_MAM_BOM2',
 PART_NUMBER='CH11006JB18',
 VALUE='100PF',
 PRIM_FILE='./archive_libs/logical/q_cap/chips/chips.prt';

PART_NAME
 C2045 'Q_CAP_0402-100PF,50V,5%,EMPTY,CH11006JB18':
 ROOM='ADC_MAM_BOM2';

SECTION_NUMBER 1
 '@T6G_MB_LIB.T6G(SCH_1):PAGE369_I36@PURE_QUANTA.Q_CAP(CHIPS)':
 C_PATH='@t6g_mb_lib.t6g(sch_1):page369_i36@pure_quanta.q_cap(chips)',
 P_PATH='@t6g_mb_lib.t6g(sch_1):page257_i36@pure_quanta.q_cap(chips)',
 PATH='I36',
 DRAWING='@T6G_MB_LIB.T6G(SCH_1):PAGE369',
 TOLERANCE='5%',
 MATERIAL='EMPTY',
 PHYS_PAGE='257',
 XY='(-6525,875)',
 ROT='0',
 VER='1',
 PACK_TYPE='0402',
 LOCATION='C2045',
 CDS_LIB='pure_quanta',
 CDS_PART_NAME='Q_CAP_0402-100PF,50V,5%,EMPTY,CH11006JB18',
 VOLTAGE='50V',
 ROOM='ADC_MAM_BOM2',
 PART_NUMBER='CH11006JB18',
 VALUE='100PF',
 PRIM_FILE='./archive_libs/logical/q_cap/chips/chips.prt';

PART_NAME
 C2046 'Q_CAP_0402-0.1UF,25V,10%,X7R,CH4104K1B00':
 ROOM='ADC_TI_BOM1';

SECTION_NUMBER 1
 '@T6G_MB_LIB.T6G(SCH_1):PAGE369_I44@PURE_QUANTA.Q_CAP(CHIPS)':
 C_PATH='@t6g_mb_lib.t6g(sch_1):page369_i44@pure_quanta.q_cap(chips)',
 P_PATH='@t6g_mb_lib.t6g(sch_1):page257_i44@pure_quanta.q_cap(chips)',
 PATH='I44',
 DRAWING='@T6G_MB_LIB.T6G(SCH_1):PAGE369',
 TOLERANCE='10%',
 MATERIAL='X7R',
 PHYS_PAGE='257',
 XY='(-7550,1775)',
 ROT='2',
 VER='1',
 PACK_TYPE='0402',
 LOCATION='C2046',
 CDS_LIB='pure_quanta',
 CDS_PART_NAME='Q_CAP_0402-0.1UF,25V,10%,X7R,CH4104K1B00',
 VOLTAGE='25V',
 ROOM='ADC_TI_BOM1',
 PART_NUMBER='CH4104K1B00',
 VALUE='0.1UF',
 PRIM_FILE='./archive_libs/logical/q_cap/chips/chips.prt';

PART_NAME
 C2047 'Q_CAP_0402-0.1UF,25V,10%,X7R,CH4104K1B00':
 ROOM='ADC_TI_BOM1';

SECTION_NUMBER 1
 '@T6G_MB_LIB.T6G(SCH_1):PAGE369_I98@PURE_QUANTA.Q_CAP(CHIPS)':
 C_PATH='@t6g_mb_lib.t6g(sch_1):page369_i98@pure_quanta.q_cap(chips)',
 P_PATH='@t6g_mb_lib.t6g(sch_1):page257_i98@pure_quanta.q_cap(chips)',
 PATH='I98',
 DRAWING='@T6G_MB_LIB.T6G(SCH_1):PAGE369',
 TOLERANCE='10%',
 MATERIAL='X7R',
 PHYS_PAGE='257',
 XY='(-7825,5575)',
 ROT='2',
 VER='1',
 PACK_TYPE='0402',
 LOCATION='C2047',
 CDS_LIB='pure_quanta',
 CDS_PART_NAME='Q_CAP_0402-0.1UF,25V,10%,X7R,CH4104K1B00',
 VOLTAGE='25V',
 ROOM='ADC_TI_BOM1',
 PART_NUMBER='CH4104K1B00',
 VALUE='0.1UF',
 PRIM_FILE='./archive_libs/logical/q_cap/chips/chips.prt';

PART_NAME
 C2048 'Q_CAP_0402-0.1UF,25V,10%,X7R,CH4104K1B00':
 ROOM='ADC_TI_BOM1';

SECTION_NUMBER 1
 '@T6G_MB_LIB.T6G(SCH_1):PAGE369_I32@PURE_QUANTA.Q_CAP(CHIPS)':
 C_PATH='@t6g_mb_lib.t6g(sch_1):page369_i32@pure_quanta.q_cap(chips)',
 P_PATH='@t6g_mb_lib.t6g(sch_1):page257_i32@pure_quanta.q_cap(chips)',
 PATH='I32',
 DRAWING='@T6G_MB_LIB.T6G(SCH_1):PAGE369',
 TOLERANCE='10%',
 MATERIAL='X7R',
 PHYS_PAGE='257',
 XY='(-7900,4225)',
 ROT='2',
 VER='1',
 PACK_TYPE='0402',
 LOCATION='C2048',
 CDS_LIB='pure_quanta',
 CDS_PART_NAME='Q_CAP_0402-0.1UF,25V,10%,X7R,CH4104K1B00',
 VOLTAGE='25V',
 ROOM='ADC_TI_BOM1',
 PART_NUMBER='CH4104K1B00',
 VALUE='0.1UF',
 PRIM_FILE='./archive_libs/logical/q_cap/chips/chips.prt';

PART_NAME
 C2049 'Q_CAP_0402-0.1UF,25V,10%,X7R,CH4104K1B00':
 ROOM='ADC_TI_BOM1';

SECTION_NUMBER 1
 '@T6G_MB_LIB.T6G(SCH_1):PAGE369_I17@PURE_QUANTA.Q_CAP(CHIPS)':
 C_PATH='@t6g_mb_lib.t6g(sch_1):page369_i17@pure_quanta.q_cap(chips)',
 P_PATH='@t6g_mb_lib.t6g(sch_1):page257_i17@pure_quanta.q_cap(chips)',
 PATH='I17',
 DRAWING='@T6G_MB_LIB.T6G(SCH_1):PAGE369',
 TOLERANCE='10%',
 MATERIAL='X7R',
 PHYS_PAGE='257',
 XY='(-7925,3075)',
 ROT='2',
 VER='1',
 PACK_TYPE='0402',
 LOCATION='C2049',
 CDS_LIB='pure_quanta',
 CDS_PART_NAME='Q_CAP_0402-0.1UF,25V,10%,X7R,CH4104K1B00',
 VOLTAGE='25V',
 ROOM='ADC_TI_BOM1',
 PART_NUMBER='CH4104K1B00',
 VALUE='0.1UF',
 PRIM_FILE='./archive_libs/logical/q_cap/chips/chips.prt';

PART_NAME
 C2050 'Q_CAP_0402-0.1UF,25V,10%,X7R,CH4104K1B00':
 ROOM='ADC_TI_BOM1';

SECTION_NUMBER 1
 '@T6G_MB_LIB.T6G(SCH_1):PAGE369_I34@PURE_QUANTA.Q_CAP(CHIPS)':
 C_PATH='@t6g_mb_lib.t6g(sch_1):page369_i34@pure_quanta.q_cap(chips)',
 P_PATH='@t6g_mb_lib.t6g(sch_1):page257_i34@pure_quanta.q_cap(chips)',
 PATH='I34',
 DRAWING='@T6G_MB_LIB.T6G(SCH_1):PAGE369',
 TOLERANCE='10%',
 MATERIAL='X7R',
 PHYS_PAGE='257',
 XY='(-6875,875)',
 ROT='2',
 VER='1',
 PACK_TYPE='0402',
 LOCATION='C2050',
 CDS_LIB='pure_quanta',
 CDS_PART_NAME='Q_CAP_0402-0.1UF,25V,10%,X7R,CH4104K1B00',
 VOLTAGE='25V',
 ROOM='ADC_TI_BOM1',
 PART_NUMBER='CH4104K1B00',
 VALUE='0.1UF',
 PRIM_FILE='./archive_libs/logical/q_cap/chips/chips.prt';

PART_NAME
 C2051 'Q_CAP_0402-0.1UF,25V,10%,X7R,CH4104K1B00':
 ROOM='ADC_TI_BOM1';

SECTION_NUMBER 1
 '@T6G_MB_LIB.T6G(SCH_1):PAGE369_I71@PURE_QUANTA.Q_CAP(CHIPS)':
 C_PATH='@t6g_mb_lib.t6g(sch_1):page369_i71@pure_quanta.q_cap(chips)',
 P_PATH='@t6g_mb_lib.t6g(sch_1):page257_i71@pure_quanta.q_cap(chips)',
 PATH='I71',
 DRAWING='@T6G_MB_LIB.T6G(SCH_1):PAGE369',
 TOLERANCE='10%',
 MATERIAL='X7R',
 PHYS_PAGE='257',
 XY='(-4175,2500)',
 ROT='2',
 VER='1',
 PACK_TYPE='0402',
 LOCATION='C2051',
 CDS_LIB='pure_quanta',
 CDS_PART_NAME='Q_CAP_0402-0.1UF,25V,10%,X7R,CH4104K1B00',
 VOLTAGE='25V',
 ROOM='ADC_TI_BOM1',
 PART_NUMBER='CH4104K1B00',
 VALUE='0.1UF',
 PRIM_FILE='./archive_libs/logical/q_cap/chips/chips.prt';

PART_NAME
 C2052 'Q_CAP_0402-0.1UF,25V,10%,X7R,CH4104K1B00':
 ROOM='ADC_TI_BOM1';

SECTION_NUMBER 1
 '@T6G_MB_LIB.T6G(SCH_1):PAGE369_I72@PURE_QUANTA.Q_CAP(CHIPS)':
 C_PATH='@t6g_mb_lib.t6g(sch_1):page369_i72@pure_quanta.q_cap(chips)',
 P_PATH='@t6g_mb_lib.t6g(sch_1):page257_i72@pure_quanta.q_cap(chips)',
 PATH='I72',
 DRAWING='@T6G_MB_LIB.T6G(SCH_1):PAGE369',
 TOLERANCE='10%',
 MATERIAL='X7R',
 PHYS_PAGE='257',
 XY='(-3850,2500)',
 ROT='0',
 VER='1',
 PACK_TYPE='0402',
 LOCATION='C2052',
 CDS_LIB='pure_quanta',
 CDS_PART_NAME='Q_CAP_0402-0.1UF,25V,10%,X7R,CH4104K1B00',
 VOLTAGE='25V',
 ROOM='ADC_TI_BOM1',
 PART_NUMBER='CH4104K1B00',
 VALUE='0.1UF',
 PRIM_FILE='./archive_libs/logical/q_cap/chips/chips.prt';

PART_NAME
 C2056 'Q_CAP_0402-0.1UF,25V,10%,X7R,CH4104K1B00':;

SECTION_NUMBER 1
 '@T6G_MB_LIB.T6G(SCH_1):PAGE251_I38@PURE_QUANTA.Q_CAP(CHIPS)':
 C_PATH='@t6g_mb_lib.t6g(sch_1):page251_i38@pure_quanta.q_cap(chips)',
 P_PATH='@t6g_mb_lib.t6g(sch_1):page252_i38@pure_quanta.q_cap(chips)',
 PATH='I38',
 DRAWING='@T6G_MB_LIB.T6G(SCH_1):PAGE251',
 TOLERANCE='10%',
 MATERIAL='X7R',
 PHYS_PAGE='252',
 XY='(-5150,5025)',
 ROT='0',
 VER='1',
 PACK_TYPE='0402',
 LOCATION='C2056',
 CDS_LIB='pure_quanta',
 CDS_PART_NAME='Q_CAP_0402-0.1UF,25V,10%,X7R,CH4104K1B00',
 VOLTAGE='25V',
 PART_NUMBER='CH4104K1B00',
 VALUE='0.1UF',
 PRIM_FILE='./archive_libs/logical/q_cap/chips/chips.prt';

PART_NAME
 C2067 'Q_CAP_0402-0.1UF,25V,10%,X7R,CH4104K1B00':;

SECTION_NUMBER 1
 '@T6G_MB_LIB.T6G(SCH_1):PAGE295_I125@PURE_QUANTA.Q_CAP(CHIPS)':
 C_PATH='@t6g_mb_lib.t6g(sch_1):page295_i125@pure_quanta.q_cap(chips)',
 P_PATH='@t6g_mb_lib.t6g(sch_1):page236_i125@pure_quanta.q_cap(chips)',
 PATH='I125',
 DRAWING='@T6G_MB_LIB.T6G(SCH_1):PAGE295',
 TOLERANCE='10%',
 MATERIAL='X7R',
 PHYS_PAGE='236',
 XY='(2175,1075)',
 ROT='0',
 VER='1',
 PACK_TYPE='0402',
 LOCATION='C2067',
 CDS_LIB='pure_quanta',
 CDS_PART_NAME='Q_CAP_0402-0.1UF,25V,10%,X7R,CH4104K1B00',
 VOLTAGE='25V',
 PART_NUMBER='CH4104K1B00',
 VALUE='0.1UF',
 PRIM_FILE='./archive_libs/logical/q_cap/chips/chips.prt';

PART_NAME
 C2069 'Q_CAP_0402-0.1UF,25V,10%,X7R,CH4104K1B00':;

SECTION_NUMBER 1
 '@T6G_MB_LIB.T6G(SCH_1):PAGE295_I142@PURE_QUANTA.Q_CAP(CHIPS)':
 C_PATH='@t6g_mb_lib.t6g(sch_1):page295_i142@pure_quanta.q_cap(chips)',
 P_PATH='@t6g_mb_lib.t6g(sch_1):page236_i142@pure_quanta.q_cap(chips)',
 PATH='I142',
 DRAWING='@T6G_MB_LIB.T6G(SCH_1):PAGE295',
 TOLERANCE='10%',
 MATERIAL='X7R',
 PHYS_PAGE='236',
 XY='(-500,650)',
 ROT='0',
 VER='1',
 PACK_TYPE='0402',
 LOCATION='C2069',
 CDS_LIB='pure_quanta',
 CDS_PART_NAME='Q_CAP_0402-0.1UF,25V,10%,X7R,CH4104K1B00',
 VOLTAGE='25V',
 PART_NUMBER='CH4104K1B00',
 VALUE='0.1UF',
 PRIM_FILE='./archive_libs/logical/q_cap/chips/chips.prt';

PART_NAME
 C2071 'Q_CAP_0402-0.1UF,25V,10%,X7R,CH4104K1B00':;

SECTION_NUMBER 1
 '@T6G_MB_LIB.T6G(SCH_1):PAGE295_I133@PURE_QUANTA.Q_CAP(CHIPS)':
 C_PATH='@t6g_mb_lib.t6g(sch_1):page295_i133@pure_quanta.q_cap(chips)',
 P_PATH='@t6g_mb_lib.t6g(sch_1):page236_i133@pure_quanta.q_cap(chips)',
 PATH='I133',
 DRAWING='@T6G_MB_LIB.T6G(SCH_1):PAGE295',
 TOLERANCE='10%',
 MATERIAL='X7R',
 PHYS_PAGE='236',
 XY='(1650,-275)',
 ROT='0',
 VER='1',
 PACK_TYPE='0402',
 LOCATION='C2071',
 CDS_LIB='pure_quanta',
 CDS_PART_NAME='Q_CAP_0402-0.1UF,25V,10%,X7R,CH4104K1B00',
 VOLTAGE='25V',
 PART_NUMBER='CH4104K1B00',
 VALUE='0.1UF',
 PRIM_FILE='./archive_libs/logical/q_cap/chips/chips.prt';

PART_NAME
 C2073 'Q_CAP_DIFFBUS_C0201-DIFF BUS_0.22UF,6.3V,20%,X6S,SA':;

SECTION_NUMBER 1
 '@T6G_MB_LIB.T6G(SCH_1):PAGE53_I132@PURE_QUANTA.Q_CAP_DIFFBUS(CHIPS)':
 C_PATH='@t6g_mb_lib.t6g(sch_1):page53_i132@pure_quanta.q_cap_diffbus(chips)',
 P_PATH='@t6g_mb_lib.t6g(sch_1):page53_i132@pure_quanta.q_cap_diffbus(chips)',
 PATH='I132',
 DRAWING='@T6G_MB_LIB.T6G(SCH_1):PAGE53',
 PIN_NAMES_ROTATE='TRUE',
 TOLERANCE='20%',
 MATERIAL='X6S',
 PHYS_PAGE='53',
 XY='(-3050,4775)',
 ROT='2',
 VER='2',
 PACK_TYPE='C0201',
 LOCATION='C2073',
 CDS_LIB='pure_quanta',
 CDS_PART_NAME='Q_CAP_DIFFBUS_C0201-DIFF BUS_0.22UF,6.3V,20%,X6S,SA',
 VOLTAGE='6.3V',
 PART_NUMBER='SP_CH4221MEE01',
 VALUE='DIFF BUS_0.22UF',
 PRIM_FILE='./archive_libs/logical/q_cap_diffbus/chips/chips.prt';

PART_NAME
 C2074 'Q_CAP_DIFFBUS_C0201-DIFF BUS_0.22UF,6.3V,20%,X6S,SA':;

SECTION_NUMBER 1
 '@T6G_MB_LIB.T6G(SCH_1):PAGE53_I133@PURE_QUANTA.Q_CAP_DIFFBUS(CHIPS)':
 C_PATH='@t6g_mb_lib.t6g(sch_1):page53_i133@pure_quanta.q_cap_diffbus(chips)',
 P_PATH='@t6g_mb_lib.t6g(sch_1):page53_i133@pure_quanta.q_cap_diffbus(chips)',
 PATH='I133',
 DRAWING='@T6G_MB_LIB.T6G(SCH_1):PAGE53',
 PIN_NAMES_ROTATE='TRUE',
 TOLERANCE='20%',
 MATERIAL='X6S',
 PHYS_PAGE='53',
 XY='(-3050,4725)',
 ROT='2',
 VER='2',
 PACK_TYPE='C0201',
 LOCATION='C2074',
 CDS_LIB='pure_quanta',
 CDS_PART_NAME='Q_CAP_DIFFBUS_C0201-DIFF BUS_0.22UF,6.3V,20%,X6S,SA',
 VOLTAGE='6.3V',
 PART_NUMBER='SP_CH4221MEE01',
 VALUE='DIFF BUS_0.22UF',
 PRIM_FILE='./archive_libs/logical/q_cap_diffbus/chips/chips.prt';

PART_NAME
 C2075 'Q_CAP_DIFFBUS_C0201-DIFF BUS_0.22UF,6.3V,20%,X6S,SA':;

SECTION_NUMBER 1
 '@T6G_MB_LIB.T6G(SCH_1):PAGE53_I135@PURE_QUANTA.Q_CAP_DIFFBUS(CHIPS)':
 C_PATH='@t6g_mb_lib.t6g(sch_1):page53_i135@pure_quanta.q_cap_diffbus(chips)',
 P_PATH='@t6g_mb_lib.t6g(sch_1):page53_i135@pure_quanta.q_cap_diffbus(chips)',
 PATH='I135',
 DRAWING='@T6G_MB_LIB.T6G(SCH_1):PAGE53',
 PIN_NAMES_ROTATE='TRUE',
 TOLERANCE='20%',
 MATERIAL='X6S',
 PHYS_PAGE='53',
 XY='(-3050,4875)',
 ROT='2',
 VER='2',
 PACK_TYPE='C0201',
 LOCATION='C2075',
 CDS_LIB='pure_quanta',
 CDS_PART_NAME='Q_CAP_DIFFBUS_C0201-DIFF BUS_0.22UF,6.3V,20%,X6S,SA',
 VOLTAGE='6.3V',
 PART_NUMBER='SP_CH4221MEE01',
 VALUE='DIFF BUS_0.22UF',
 PRIM_FILE='./archive_libs/logical/q_cap_diffbus/chips/chips.prt';

PART_NAME
 C2076 'Q_CAP_DIFFBUS_C0201-DIFF BUS_0.22UF,6.3V,20%,X6S,SA':;

SECTION_NUMBER 1
 '@T6G_MB_LIB.T6G(SCH_1):PAGE53_I134@PURE_QUANTA.Q_CAP_DIFFBUS(CHIPS)':
 C_PATH='@t6g_mb_lib.t6g(sch_1):page53_i134@pure_quanta.q_cap_diffbus(chips)',
 P_PATH='@t6g_mb_lib.t6g(sch_1):page53_i134@pure_quanta.q_cap_diffbus(chips)',
 PATH='I134',
 DRAWING='@T6G_MB_LIB.T6G(SCH_1):PAGE53',
 PIN_NAMES_ROTATE='TRUE',
 TOLERANCE='20%',
 MATERIAL='X6S',
 PHYS_PAGE='53',
 XY='(-3050,4825)',
 ROT='2',
 VER='2',
 PACK_TYPE='C0201',
 LOCATION='C2076',
 CDS_LIB='pure_quanta',
 CDS_PART_NAME='Q_CAP_DIFFBUS_C0201-DIFF BUS_0.22UF,6.3V,20%,X6S,SA',
 VOLTAGE='6.3V',
 PART_NUMBER='SP_CH4221MEE01',
 VALUE='DIFF BUS_0.22UF',
 PRIM_FILE='./archive_libs/logical/q_cap_diffbus/chips/chips.prt';

PART_NAME
 C2077 'Q_CAP_DIFFBUS_C0201-DIFF BUS_0.22UF,6.3V,20%,X6S,SA':;

SECTION_NUMBER 1
 '@T6G_MB_LIB.T6G(SCH_1):PAGE26_I156@PURE_QUANTA.Q_CAP_DIFFBUS(CHIPS)':
 C_PATH='@t6g_mb_lib.t6g(sch_1):page26_i156@pure_quanta.q_cap_diffbus(chips)',
 P_PATH='@t6g_mb_lib.t6g(sch_1):page26_i156@pure_quanta.q_cap_diffbus(chips)',
 PATH='I156',
 DRAWING='@T6G_MB_LIB.T6G(SCH_1):PAGE26',
 PIN_NAMES_ROTATE='True',
 TOLERANCE='20%',
 MATERIAL='X6S',
 PHYS_PAGE='26',
 XY='(-2700,4450)',
 ROT='0',
 VER='2',
 PACK_TYPE='C0201',
 LOCATION='C2077',
 CDS_LIB='pure_quanta',
 CDS_PART_NAME='Q_CAP_DIFFBUS_C0201-DIFF BUS_0.22UF,6.3V,20%,X6S,SA',
 VOLTAGE='6.3V',
 PART_NUMBER='SP_CH4221MEE01',
 VALUE='DIFF BUS_0.22UF',
 PRIM_FILE='./archive_libs/logical/q_cap_diffbus/chips/chips.prt';

PART_NAME
 C2078 'Q_CAP_DIFFBUS_C0201-DIFF BUS_0.22UF,6.3V,20%,X6S,SA':;

SECTION_NUMBER 1
 '@T6G_MB_LIB.T6G(SCH_1):PAGE26_I157@PURE_QUANTA.Q_CAP_DIFFBUS(CHIPS)':
 C_PATH='@t6g_mb_lib.t6g(sch_1):page26_i157@pure_quanta.q_cap_diffbus(chips)',
 P_PATH='@t6g_mb_lib.t6g(sch_1):page26_i157@pure_quanta.q_cap_diffbus(chips)',
 PATH='I157',
 DRAWING='@T6G_MB_LIB.T6G(SCH_1):PAGE26',
 PIN_NAMES_ROTATE='True',
 TOLERANCE='20%',
 MATERIAL='X6S',
 PHYS_PAGE='26',
 XY='(-2700,4400)',
 ROT='0',
 VER='2',
 PACK_TYPE='C0201',
 LOCATION='C2078',
 CDS_LIB='pure_quanta',
 CDS_PART_NAME='Q_CAP_DIFFBUS_C0201-DIFF BUS_0.22UF,6.3V,20%,X6S,SA',
 VOLTAGE='6.3V',
 PART_NUMBER='SP_CH4221MEE01',
 VALUE='DIFF BUS_0.22UF',
 PRIM_FILE='./archive_libs/logical/q_cap_diffbus/chips/chips.prt';

PART_NAME
 C2102 'Q_CAP_C0402-22UF,4V,20%,X6S,CH622KMEB02':;

SECTION_NUMBER 1
 '@T6G_MB_LIB.T6G(SCH_1):PAGE73_I140@PURE_QUANTA.Q_CAP(CHIPS)':
 C_PATH='@t6g_mb_lib.t6g(sch_1):page73_i140@pure_quanta.q_cap(chips)',
 P_PATH='@t6g_mb_lib.t6g(sch_1):page74_i140@pure_quanta.q_cap(chips)',
 PATH='I140',
 DRAWING='@T6G_MB_LIB.T6G(SCH_1):PAGE73',
 TOLERANCE='20%',
 MATERIAL='X6S',
 PHYS_PAGE='74',
 XY='(5425,5875)',
 ROT='0',
 VER='1',
 PACK_TYPE='C0402',
 LOCATION='C2102',
 CDS_LIB='pure_quanta',
 CDS_PART_NAME='Q_CAP_C0402-22UF,4V,20%,X6S,CH622KMEB02',
 VOLTAGE='4V',
 PART_NUMBER='CH622KMEB02',
 VALUE='22UF',
 PRIM_FILE='./archive_libs/logical/q_cap/chips/chips.prt';

PART_NAME
 C2103 'Q_CAP_C0402-22UF,4V,20%,X6S,CH622KMEB02':;

SECTION_NUMBER 1
 '@T6G_MB_LIB.T6G(SCH_1):PAGE73_I137@PURE_QUANTA.Q_CAP(CHIPS)':
 C_PATH='@t6g_mb_lib.t6g(sch_1):page73_i137@pure_quanta.q_cap(chips)',
 P_PATH='@t6g_mb_lib.t6g(sch_1):page74_i137@pure_quanta.q_cap(chips)',
 PATH='I137',
 DRAWING='@T6G_MB_LIB.T6G(SCH_1):PAGE73',
 TOLERANCE='20%',
 MATERIAL='X6S',
 PHYS_PAGE='74',
 XY='(5450,4300)',
 ROT='0',
 VER='1',
 PACK_TYPE='C0402',
 LOCATION='C2103',
 CDS_LIB='pure_quanta',
 CDS_PART_NAME='Q_CAP_C0402-22UF,4V,20%,X6S,CH622KMEB02',
 VOLTAGE='4V',
 PART_NUMBER='CH622KMEB02',
 VALUE='22UF',
 PRIM_FILE='./archive_libs/logical/q_cap/chips/chips.prt';

PART_NAME
 C2104 'Q_CAP_C0402-22UF,4V,20%,X6S,CH622KMEB02':;

SECTION_NUMBER 1
 '@T6G_MB_LIB.T6G(SCH_1):PAGE73_I142@PURE_QUANTA.Q_CAP(CHIPS)':
 C_PATH='@t6g_mb_lib.t6g(sch_1):page73_i142@pure_quanta.q_cap(chips)',
 P_PATH='@t6g_mb_lib.t6g(sch_1):page74_i142@pure_quanta.q_cap(chips)',
 PATH='I142',
 DRAWING='@T6G_MB_LIB.T6G(SCH_1):PAGE73',
 TOLERANCE='20%',
 MATERIAL='X6S',
 PHYS_PAGE='74',
 XY='(5875,5875)',
 ROT='0',
 VER='1',
 PACK_TYPE='C0402',
 LOCATION='C2104',
 CDS_LIB='pure_quanta',
 CDS_PART_NAME='Q_CAP_C0402-22UF,4V,20%,X6S,CH622KMEB02',
 VOLTAGE='4V',
 PART_NUMBER='CH622KMEB02',
 VALUE='22UF',
 PRIM_FILE='./archive_libs/logical/q_cap/chips/chips.prt';

PART_NAME
 C2105 'Q_CAP_C0402-22UF,4V,20%,X6S,CH622KMEB02':;

SECTION_NUMBER 1
 '@T6G_MB_LIB.T6G(SCH_1):PAGE73_I141@PURE_QUANTA.Q_CAP(CHIPS)':
 C_PATH='@t6g_mb_lib.t6g(sch_1):page73_i141@pure_quanta.q_cap(chips)',
 P_PATH='@t6g_mb_lib.t6g(sch_1):page74_i141@pure_quanta.q_cap(chips)',
 PATH='I141',
 DRAWING='@T6G_MB_LIB.T6G(SCH_1):PAGE73',
 TOLERANCE='20%',
 MATERIAL='X6S',
 PHYS_PAGE='74',
 XY='(5875,5075)',
 ROT='0',
 VER='1',
 PACK_TYPE='C0402',
 LOCATION='C2105',
 CDS_LIB='pure_quanta',
 CDS_PART_NAME='Q_CAP_C0402-22UF,4V,20%,X6S,CH622KMEB02',
 VOLTAGE='4V',
 PART_NUMBER='CH622KMEB02',
 VALUE='22UF',
 PRIM_FILE='./archive_libs/logical/q_cap/chips/chips.prt';

PART_NAME
 C2106 'Q_CAP_C0402-22UF,4V,20%,X6S,CH622KMEB02':;

SECTION_NUMBER 1
 '@T6G_MB_LIB.T6G(SCH_1):PAGE73_I138@PURE_QUANTA.Q_CAP(CHIPS)':
 C_PATH='@t6g_mb_lib.t6g(sch_1):page73_i138@pure_quanta.q_cap(chips)',
 P_PATH='@t6g_mb_lib.t6g(sch_1):page74_i138@pure_quanta.q_cap(chips)',
 PATH='I138',
 DRAWING='@T6G_MB_LIB.T6G(SCH_1):PAGE73',
 TOLERANCE='20%',
 MATERIAL='X6S',
 PHYS_PAGE='74',
 XY='(5900,4300)',
 ROT='0',
 VER='1',
 PACK_TYPE='C0402',
 LOCATION='C2106',
 CDS_LIB='pure_quanta',
 CDS_PART_NAME='Q_CAP_C0402-22UF,4V,20%,X6S,CH622KMEB02',
 VOLTAGE='4V',
 PART_NUMBER='CH622KMEB02',
 VALUE='22UF',
 PRIM_FILE='./archive_libs/logical/q_cap/chips/chips.prt';

PART_NAME
 C2107 'Q_CAP_C0402-22UF,4V,20%,X6S,CH622KMEB02':;

SECTION_NUMBER 1
 '@T6G_MB_LIB.T6G(SCH_1):PAGE73_I145@PURE_QUANTA.Q_CAP(CHIPS)':
 C_PATH='@t6g_mb_lib.t6g(sch_1):page73_i145@pure_quanta.q_cap(chips)',
 P_PATH='@t6g_mb_lib.t6g(sch_1):page74_i145@pure_quanta.q_cap(chips)',
 PATH='I145',
 DRAWING='@T6G_MB_LIB.T6G(SCH_1):PAGE73',
 TOLERANCE='20%',
 MATERIAL='X6S',
 PHYS_PAGE='74',
 XY='(6325,5075)',
 ROT='0',
 VER='1',
 PACK_TYPE='C0402',
 LOCATION='C2107',
 CDS_LIB='pure_quanta',
 CDS_PART_NAME='Q_CAP_C0402-22UF,4V,20%,X6S,CH622KMEB02',
 VOLTAGE='4V',
 PART_NUMBER='CH622KMEB02',
 VALUE='22UF',
 PRIM_FILE='./archive_libs/logical/q_cap/chips/chips.prt';

PART_NAME
 C2108 'Q_CAP_C0402-22UF,4V,20%,X6S,CH622KMEB02':;

SECTION_NUMBER 1
 '@T6G_MB_LIB.T6G(SCH_1):PAGE73_I144@PURE_QUANTA.Q_CAP(CHIPS)':
 C_PATH='@t6g_mb_lib.t6g(sch_1):page73_i144@pure_quanta.q_cap(chips)',
 P_PATH='@t6g_mb_lib.t6g(sch_1):page74_i144@pure_quanta.q_cap(chips)',
 PATH='I144',
 DRAWING='@T6G_MB_LIB.T6G(SCH_1):PAGE73',
 TOLERANCE='20%',
 MATERIAL='X6S',
 PHYS_PAGE='74',
 XY='(6350,4300)',
 ROT='0',
 VER='1',
 PACK_TYPE='C0402',
 LOCATION='C2108',
 CDS_LIB='pure_quanta',
 CDS_PART_NAME='Q_CAP_C0402-22UF,4V,20%,X6S,CH622KMEB02',
 VOLTAGE='4V',
 PART_NUMBER='CH622KMEB02',
 VALUE='22UF',
 PRIM_FILE='./archive_libs/logical/q_cap/chips/chips.prt';

PART_NAME
 C2109 'Q_CAP_C0402-22UF,4V,20%,X6S,CH622KMEB02':;

SECTION_NUMBER 1
 '@T6G_MB_LIB.T6G(SCH_1):PAGE73_I148@PURE_QUANTA.Q_CAP(CHIPS)':
 C_PATH='@t6g_mb_lib.t6g(sch_1):page73_i148@pure_quanta.q_cap(chips)',
 P_PATH='@t6g_mb_lib.t6g(sch_1):page74_i148@pure_quanta.q_cap(chips)',
 PATH='I148',
 DRAWING='@T6G_MB_LIB.T6G(SCH_1):PAGE73',
 TOLERANCE='20%',
 MATERIAL='X6S',
 PHYS_PAGE='74',
 XY='(6775,5875)',
 ROT='0',
 VER='1',
 PACK_TYPE='C0402',
 LOCATION='C2109',
 CDS_LIB='pure_quanta',
 CDS_PART_NAME='Q_CAP_C0402-22UF,4V,20%,X6S,CH622KMEB02',
 VOLTAGE='4V',
 PART_NUMBER='CH622KMEB02',
 VALUE='22UF',
 PRIM_FILE='./archive_libs/logical/q_cap/chips/chips.prt';

PART_NAME
 C2110 'Q_CAP_C0402-22UF,4V,20%,X6S,CH622KMEB02':;

SECTION_NUMBER 1
 '@T6G_MB_LIB.T6G(SCH_1):PAGE73_I151@PURE_QUANTA.Q_CAP(CHIPS)':
 C_PATH='@t6g_mb_lib.t6g(sch_1):page73_i151@pure_quanta.q_cap(chips)',
 P_PATH='@t6g_mb_lib.t6g(sch_1):page74_i151@pure_quanta.q_cap(chips)',
 PATH='I151',
 DRAWING='@T6G_MB_LIB.T6G(SCH_1):PAGE73',
 TOLERANCE='20%',
 MATERIAL='X6S',
 PHYS_PAGE='74',
 XY='(7225,5875)',
 ROT='0',
 VER='1',
 PACK_TYPE='C0402',
 LOCATION='C2110',
 CDS_LIB='pure_quanta',
 CDS_PART_NAME='Q_CAP_C0402-22UF,4V,20%,X6S,CH622KMEB02',
 VOLTAGE='4V',
 PART_NUMBER='CH622KMEB02',
 VALUE='22UF',
 PRIM_FILE='./archive_libs/logical/q_cap/chips/chips.prt';

PART_NAME
 C2111 'Q_CAP_C0402-22UF,4V,20%,X6S,CH622KMEB02':;

SECTION_NUMBER 1
 '@T6G_MB_LIB.T6G(SCH_1):PAGE73_I149@PURE_QUANTA.Q_CAP(CHIPS)':
 C_PATH='@t6g_mb_lib.t6g(sch_1):page73_i149@pure_quanta.q_cap(chips)',
 P_PATH='@t6g_mb_lib.t6g(sch_1):page74_i149@pure_quanta.q_cap(chips)',
 PATH='I149',
 DRAWING='@T6G_MB_LIB.T6G(SCH_1):PAGE73',
 TOLERANCE='20%',
 MATERIAL='X6S',
 PHYS_PAGE='74',
 XY='(7225,5075)',
 ROT='0',
 VER='1',
 PACK_TYPE='C0402',
 LOCATION='C2111',
 CDS_LIB='pure_quanta',
 CDS_PART_NAME='Q_CAP_C0402-22UF,4V,20%,X6S,CH622KMEB02',
 VOLTAGE='4V',
 PART_NUMBER='CH622KMEB02',
 VALUE='22UF',
 PRIM_FILE='./archive_libs/logical/q_cap/chips/chips.prt';

PART_NAME
 C2112 'Q_CAP_C0402-22UF,4V,20%,X6S,CH622KMEB02':;

SECTION_NUMBER 1
 '@T6G_MB_LIB.T6G(SCH_1):PAGE73_I150@PURE_QUANTA.Q_CAP(CHIPS)':
 C_PATH='@t6g_mb_lib.t6g(sch_1):page73_i150@pure_quanta.q_cap(chips)',
 P_PATH='@t6g_mb_lib.t6g(sch_1):page74_i150@pure_quanta.q_cap(chips)',
 PATH='I150',
 DRAWING='@T6G_MB_LIB.T6G(SCH_1):PAGE73',
 TOLERANCE='20%',
 MATERIAL='X6S',
 PHYS_PAGE='74',
 XY='(7675,5075)',
 ROT='0',
 VER='1',
 PACK_TYPE='C0402',
 LOCATION='C2112',
 CDS_LIB='pure_quanta',
 CDS_PART_NAME='Q_CAP_C0402-22UF,4V,20%,X6S,CH622KMEB02',
 VOLTAGE='4V',
 PART_NUMBER='CH622KMEB02',
 VALUE='22UF',
 PRIM_FILE='./archive_libs/logical/q_cap/chips/chips.prt';

PART_NAME
 C2113 'Q_CAP_C0402-22UF,4V,20%,X6S,CH622KMEB02':;

SECTION_NUMBER 1
 '@T6G_MB_LIB.T6G(SCH_1):PAGE73_I119@PURE_QUANTA.Q_CAP(CHIPS)':
 C_PATH='@t6g_mb_lib.t6g(sch_1):page73_i119@pure_quanta.q_cap(chips)',
 P_PATH='@t6g_mb_lib.t6g(sch_1):page74_i119@pure_quanta.q_cap(chips)',
 PATH='I119',
 DRAWING='@T6G_MB_LIB.T6G(SCH_1):PAGE73',
 TOLERANCE='20%',
 MATERIAL='X6S',
 PHYS_PAGE='74',
 XY='(7700,2650)',
 ROT='0',
 VER='1',
 PACK_TYPE='C0402',
 LOCATION='C2113',
 CDS_LIB='pure_quanta',
 CDS_PART_NAME='Q_CAP_C0402-22UF,4V,20%,X6S,CH622KMEB02',
 VOLTAGE='4V',
 PART_NUMBER='CH622KMEB02',
 VALUE='22UF',
 PRIM_FILE='./archive_libs/logical/q_cap/chips/chips.prt';

PART_NAME
 C2114 'Q_CAP_C0402-22UF,4V,20%,X6S,CH622KMEB02':;

SECTION_NUMBER 1
 '@T6G_MB_LIB.T6G(SCH_1):PAGE73_I120@PURE_QUANTA.Q_CAP(CHIPS)':
 C_PATH='@t6g_mb_lib.t6g(sch_1):page73_i120@pure_quanta.q_cap(chips)',
 P_PATH='@t6g_mb_lib.t6g(sch_1):page74_i120@pure_quanta.q_cap(chips)',
 PATH='I120',
 DRAWING='@T6G_MB_LIB.T6G(SCH_1):PAGE73',
 TOLERANCE='20%',
 MATERIAL='X6S',
 PHYS_PAGE='74',
 XY='(7700,2025)',
 ROT='0',
 VER='1',
 PACK_TYPE='C0402',
 LOCATION='C2114',
 CDS_LIB='pure_quanta',
 CDS_PART_NAME='Q_CAP_C0402-22UF,4V,20%,X6S,CH622KMEB02',
 VOLTAGE='4V',
 PART_NUMBER='CH622KMEB02',
 VALUE='22UF',
 PRIM_FILE='./archive_libs/logical/q_cap/chips/chips.prt';

PART_NAME
 C2115 'Q_CAP_C0402-22UF,4V,20%,X6S,CH622KMEB02':;

SECTION_NUMBER 1
 '@T6G_MB_LIB.T6G(SCH_1):PAGE73_I108@PURE_QUANTA.Q_CAP(CHIPS)':
 C_PATH='@t6g_mb_lib.t6g(sch_1):page73_i108@pure_quanta.q_cap(chips)',
 P_PATH='@t6g_mb_lib.t6g(sch_1):page74_i108@pure_quanta.q_cap(chips)',
 PATH='I108',
 DRAWING='@T6G_MB_LIB.T6G(SCH_1):PAGE73',
 TOLERANCE='20%',
 MATERIAL='X6S',
 PHYS_PAGE='74',
 XY='(7700,1375)',
 ROT='0',
 VER='1',
 PACK_TYPE='C0402',
 LOCATION='C2115',
 CDS_LIB='pure_quanta',
 CDS_PART_NAME='Q_CAP_C0402-22UF,4V,20%,X6S,CH622KMEB02',
 VOLTAGE='4V',
 PART_NUMBER='CH622KMEB02',
 VALUE='22UF',
 PRIM_FILE='./archive_libs/logical/q_cap/chips/chips.prt';

PART_NAME
 C2116 'Q_CAP_C0402-22UF,4V,20%,X6S,CH622KMEB02':;

SECTION_NUMBER 1
 '@T6G_MB_LIB.T6G(SCH_1):PAGE73_I154@PURE_QUANTA.Q_CAP(CHIPS)':
 C_PATH='@t6g_mb_lib.t6g(sch_1):page73_i154@pure_quanta.q_cap(chips)',
 P_PATH='@t6g_mb_lib.t6g(sch_1):page74_i154@pure_quanta.q_cap(chips)',
 PATH='I154',
 DRAWING='@T6G_MB_LIB.T6G(SCH_1):PAGE73',
 TOLERANCE='20%',
 MATERIAL='X6S',
 PHYS_PAGE='74',
 XY='(8125,5875)',
 ROT='0',
 VER='1',
 PACK_TYPE='C0402',
 LOCATION='C2116',
 CDS_LIB='pure_quanta',
 CDS_PART_NAME='Q_CAP_C0402-22UF,4V,20%,X6S,CH622KMEB02',
 VOLTAGE='4V',
 PART_NUMBER='CH622KMEB02',
 VALUE='22UF',
 PRIM_FILE='./archive_libs/logical/q_cap/chips/chips.prt';

PART_NAME
 C2117 'Q_CAP_C0402-22UF,4V,20%,X6S,CH622KMEB02':;

SECTION_NUMBER 1
 '@T6G_MB_LIB.T6G(SCH_1):PAGE73_I153@PURE_QUANTA.Q_CAP(CHIPS)':
 C_PATH='@t6g_mb_lib.t6g(sch_1):page73_i153@pure_quanta.q_cap(chips)',
 P_PATH='@t6g_mb_lib.t6g(sch_1):page74_i153@pure_quanta.q_cap(chips)',
 PATH='I153',
 DRAWING='@T6G_MB_LIB.T6G(SCH_1):PAGE73',
 TOLERANCE='20%',
 MATERIAL='X6S',
 PHYS_PAGE='74',
 XY='(8125,5075)',
 ROT='0',
 VER='1',
 PACK_TYPE='C0402',
 LOCATION='C2117',
 CDS_LIB='pure_quanta',
 CDS_PART_NAME='Q_CAP_C0402-22UF,4V,20%,X6S,CH622KMEB02',
 VOLTAGE='4V',
 PART_NUMBER='CH622KMEB02',
 VALUE='22UF',
 PRIM_FILE='./archive_libs/logical/q_cap/chips/chips.prt';

PART_NAME
 C2118 'Q_CAP_C0402-22UF,4V,20%,X6S,CH622KMEB02':;

SECTION_NUMBER 1
 '@T6G_MB_LIB.T6G(SCH_1):PAGE73_I125@PURE_QUANTA.Q_CAP(CHIPS)':
 C_PATH='@t6g_mb_lib.t6g(sch_1):page73_i125@pure_quanta.q_cap(chips)',
 P_PATH='@t6g_mb_lib.t6g(sch_1):page74_i125@pure_quanta.q_cap(chips)',
 PATH='I125',
 DRAWING='@T6G_MB_LIB.T6G(SCH_1):PAGE73',
 TOLERANCE='20%',
 MATERIAL='X6S',
 PHYS_PAGE='74',
 XY='(8150,3325)',
 ROT='0',
 VER='1',
 PACK_TYPE='C0402',
 LOCATION='C2118',
 CDS_LIB='pure_quanta',
 CDS_PART_NAME='Q_CAP_C0402-22UF,4V,20%,X6S,CH622KMEB02',
 VOLTAGE='4V',
 PART_NUMBER='CH622KMEB02',
 VALUE='22UF',
 PRIM_FILE='./archive_libs/logical/q_cap/chips/chips.prt';

PART_NAME
 C2119 'Q_CAP_C0402-22UF,4V,20%,X6S,CH622KMEB02':;

SECTION_NUMBER 1
 '@T6G_MB_LIB.T6G(SCH_1):PAGE73_I122@PURE_QUANTA.Q_CAP(CHIPS)':
 C_PATH='@t6g_mb_lib.t6g(sch_1):page73_i122@pure_quanta.q_cap(chips)',
 P_PATH='@t6g_mb_lib.t6g(sch_1):page74_i122@pure_quanta.q_cap(chips)',
 PATH='I122',
 DRAWING='@T6G_MB_LIB.T6G(SCH_1):PAGE73',
 TOLERANCE='20%',
 MATERIAL='X6S',
 PHYS_PAGE='74',
 XY='(8150,2650)',
 ROT='0',
 VER='1',
 PACK_TYPE='C0402',
 LOCATION='C2119',
 CDS_LIB='pure_quanta',
 CDS_PART_NAME='Q_CAP_C0402-22UF,4V,20%,X6S,CH622KMEB02',
 VOLTAGE='4V',
 PART_NUMBER='CH622KMEB02',
 VALUE='22UF',
 PRIM_FILE='./archive_libs/logical/q_cap/chips/chips.prt';

PART_NAME
 C2120 'Q_CAP_C0402-22UF,4V,20%,X6S,CH622KMEB02':;

SECTION_NUMBER 1
 '@T6G_MB_LIB.T6G(SCH_1):PAGE73_I121@PURE_QUANTA.Q_CAP(CHIPS)':
 C_PATH='@t6g_mb_lib.t6g(sch_1):page73_i121@pure_quanta.q_cap(chips)',
 P_PATH='@t6g_mb_lib.t6g(sch_1):page74_i121@pure_quanta.q_cap(chips)',
 PATH='I121',
 DRAWING='@T6G_MB_LIB.T6G(SCH_1):PAGE73',
 TOLERANCE='20%',
 MATERIAL='X6S',
 PHYS_PAGE='74',
 XY='(8150,2025)',
 ROT='0',
 VER='1',
 PACK_TYPE='C0402',
 LOCATION='C2120',
 CDS_LIB='pure_quanta',
 CDS_PART_NAME='Q_CAP_C0402-22UF,4V,20%,X6S,CH622KMEB02',
 VOLTAGE='4V',
 PART_NUMBER='CH622KMEB02',
 VALUE='22UF',
 PRIM_FILE='./archive_libs/logical/q_cap/chips/chips.prt';

PART_NAME
 C2121 'Q_CAP_C0402-22UF,4V,20%,X6S,CH622KMEB02':;

SECTION_NUMBER 1
 '@T6G_MB_LIB.T6G(SCH_1):PAGE73_I109@PURE_QUANTA.Q_CAP(CHIPS)':
 C_PATH='@t6g_mb_lib.t6g(sch_1):page73_i109@pure_quanta.q_cap(chips)',
 P_PATH='@t6g_mb_lib.t6g(sch_1):page74_i109@pure_quanta.q_cap(chips)',
 PATH='I109',
 DRAWING='@T6G_MB_LIB.T6G(SCH_1):PAGE73',
 TOLERANCE='20%',
 MATERIAL='X6S',
 PHYS_PAGE='74',
 XY='(8150,1375)',
 ROT='0',
 VER='1',
 PACK_TYPE='C0402',
 LOCATION='C2121',
 CDS_LIB='pure_quanta',
 CDS_PART_NAME='Q_CAP_C0402-22UF,4V,20%,X6S,CH622KMEB02',
 VOLTAGE='4V',
 PART_NUMBER='CH622KMEB02',
 VALUE='22UF',
 PRIM_FILE='./archive_libs/logical/q_cap/chips/chips.prt';

PART_NAME
 C2122 'Q_CAP_C0402-22UF,4V,20%,X6S,CH622KMEB02':;

SECTION_NUMBER 1
 '@T6G_MB_LIB.T6G(SCH_1):PAGE73_I169@PURE_QUANTA.Q_CAP(CHIPS)':
 C_PATH='@t6g_mb_lib.t6g(sch_1):page73_i169@pure_quanta.q_cap(chips)',
 P_PATH='@t6g_mb_lib.t6g(sch_1):page74_i169@pure_quanta.q_cap(chips)',
 PATH='I169',
 DRAWING='@T6G_MB_LIB.T6G(SCH_1):PAGE73',
 TOLERANCE='20%',
 MATERIAL='X6S',
 PHYS_PAGE='74',
 XY='(8575,5875)',
 ROT='0',
 VER='1',
 PACK_TYPE='C0402',
 LOCATION='C2122',
 CDS_LIB='pure_quanta',
 CDS_PART_NAME='Q_CAP_C0402-22UF,4V,20%,X6S,CH622KMEB02',
 VOLTAGE='4V',
 PART_NUMBER='CH622KMEB02',
 VALUE='22UF',
 PRIM_FILE='./archive_libs/logical/q_cap/chips/chips.prt';

PART_NAME
 C2123 'Q_CAP_C0402-22UF,4V,20%,X6S,CH622KMEB02':;

SECTION_NUMBER 1
 '@T6G_MB_LIB.T6G(SCH_1):PAGE73_I168@PURE_QUANTA.Q_CAP(CHIPS)':
 C_PATH='@t6g_mb_lib.t6g(sch_1):page73_i168@pure_quanta.q_cap(chips)',
 P_PATH='@t6g_mb_lib.t6g(sch_1):page74_i168@pure_quanta.q_cap(chips)',
 PATH='I168',
 DRAWING='@T6G_MB_LIB.T6G(SCH_1):PAGE73',
 TOLERANCE='20%',
 MATERIAL='X6S',
 PHYS_PAGE='74',
 XY='(8575,5075)',
 ROT='0',
 VER='1',
 PACK_TYPE='C0402',
 LOCATION='C2123',
 CDS_LIB='pure_quanta',
 CDS_PART_NAME='Q_CAP_C0402-22UF,4V,20%,X6S,CH622KMEB02',
 VOLTAGE='4V',
 PART_NUMBER='CH622KMEB02',
 VALUE='22UF',
 PRIM_FILE='./archive_libs/logical/q_cap/chips/chips.prt';

PART_NAME
 C2124 'Q_CAP_C0402-22UF,4V,20%,X6S,CH622KMEB02':;

SECTION_NUMBER 1
 '@T6G_MB_LIB.T6G(SCH_1):PAGE73_I164@PURE_QUANTA.Q_CAP(CHIPS)':
 C_PATH='@t6g_mb_lib.t6g(sch_1):page73_i164@pure_quanta.q_cap(chips)',
 P_PATH='@t6g_mb_lib.t6g(sch_1):page74_i164@pure_quanta.q_cap(chips)',
 PATH='I164',
 DRAWING='@T6G_MB_LIB.T6G(SCH_1):PAGE73',
 TOLERANCE='20%',
 MATERIAL='X6S',
 PHYS_PAGE='74',
 XY='(8600,3325)',
 ROT='0',
 VER='1',
 PACK_TYPE='C0402',
 LOCATION='C2124',
 CDS_LIB='pure_quanta',
 CDS_PART_NAME='Q_CAP_C0402-22UF,4V,20%,X6S,CH622KMEB02',
 VOLTAGE='4V',
 PART_NUMBER='CH622KMEB02',
 VALUE='22UF',
 PRIM_FILE='./archive_libs/logical/q_cap/chips/chips.prt';

PART_NAME
 C2125 'Q_CAP_C0402-22UF,4V,20%,X6S,CH622KMEB02':;

SECTION_NUMBER 1
 '@T6G_MB_LIB.T6G(SCH_1):PAGE73_I160@PURE_QUANTA.Q_CAP(CHIPS)':
 C_PATH='@t6g_mb_lib.t6g(sch_1):page73_i160@pure_quanta.q_cap(chips)',
 P_PATH='@t6g_mb_lib.t6g(sch_1):page74_i160@pure_quanta.q_cap(chips)',
 PATH='I160',
 DRAWING='@T6G_MB_LIB.T6G(SCH_1):PAGE73',
 TOLERANCE='20%',
 MATERIAL='X6S',
 PHYS_PAGE='74',
 XY='(8600,2650)',
 ROT='0',
 VER='1',
 PACK_TYPE='C0402',
 LOCATION='C2125',
 CDS_LIB='pure_quanta',
 CDS_PART_NAME='Q_CAP_C0402-22UF,4V,20%,X6S,CH622KMEB02',
 VOLTAGE='4V',
 PART_NUMBER='CH622KMEB02',
 VALUE='22UF',
 PRIM_FILE='./archive_libs/logical/q_cap/chips/chips.prt';

PART_NAME
 C2126 'Q_CAP_C0402-22UF,4V,20%,X6S,CH622KMEB02':;

SECTION_NUMBER 1
 '@T6G_MB_LIB.T6G(SCH_1):PAGE73_I159@PURE_QUANTA.Q_CAP(CHIPS)':
 C_PATH='@t6g_mb_lib.t6g(sch_1):page73_i159@pure_quanta.q_cap(chips)',
 P_PATH='@t6g_mb_lib.t6g(sch_1):page74_i159@pure_quanta.q_cap(chips)',
 PATH='I159',
 DRAWING='@T6G_MB_LIB.T6G(SCH_1):PAGE73',
 TOLERANCE='20%',
 MATERIAL='X6S',
 PHYS_PAGE='74',
 XY='(8600,2025)',
 ROT='0',
 VER='1',
 PACK_TYPE='C0402',
 LOCATION='C2126',
 CDS_LIB='pure_quanta',
 CDS_PART_NAME='Q_CAP_C0402-22UF,4V,20%,X6S,CH622KMEB02',
 VOLTAGE='4V',
 PART_NUMBER='CH622KMEB02',
 VALUE='22UF',
 PRIM_FILE='./archive_libs/logical/q_cap/chips/chips.prt';

PART_NAME
 C2127 'Q_CAP_C0402-22UF,4V,20%,X6S,CH622KMEB02':;

SECTION_NUMBER 1
 '@T6G_MB_LIB.T6G(SCH_1):PAGE73_I172@PURE_QUANTA.Q_CAP(CHIPS)':
 C_PATH='@t6g_mb_lib.t6g(sch_1):page73_i172@pure_quanta.q_cap(chips)',
 P_PATH='@t6g_mb_lib.t6g(sch_1):page74_i172@pure_quanta.q_cap(chips)',
 PATH='I172',
 DRAWING='@T6G_MB_LIB.T6G(SCH_1):PAGE73',
 TOLERANCE='20%',
 MATERIAL='X6S',
 PHYS_PAGE='74',
 XY='(8975,5875)',
 ROT='0',
 VER='1',
 PACK_TYPE='C0402',
 LOCATION='C2127',
 CDS_LIB='pure_quanta',
 CDS_PART_NAME='Q_CAP_C0402-22UF,4V,20%,X6S,CH622KMEB02',
 VOLTAGE='4V',
 PART_NUMBER='CH622KMEB02',
 VALUE='22UF',
 PRIM_FILE='./archive_libs/logical/q_cap/chips/chips.prt';

PART_NAME
 C2128 'Q_CAP_C0402-22UF,4V,20%,X6S,CH622KMEB02':;

SECTION_NUMBER 1
 '@T6G_MB_LIB.T6G(SCH_1):PAGE73_I166@PURE_QUANTA.Q_CAP(CHIPS)':
 C_PATH='@t6g_mb_lib.t6g(sch_1):page73_i166@pure_quanta.q_cap(chips)',
 P_PATH='@t6g_mb_lib.t6g(sch_1):page74_i166@pure_quanta.q_cap(chips)',
 PATH='I166',
 DRAWING='@T6G_MB_LIB.T6G(SCH_1):PAGE73',
 TOLERANCE='20%',
 MATERIAL='X6S',
 PHYS_PAGE='74',
 XY='(9000,3325)',
 ROT='0',
 VER='1',
 PACK_TYPE='C0402',
 LOCATION='C2128',
 CDS_LIB='pure_quanta',
 CDS_PART_NAME='Q_CAP_C0402-22UF,4V,20%,X6S,CH622KMEB02',
 VOLTAGE='4V',
 PART_NUMBER='CH622KMEB02',
 VALUE='22UF',
 PRIM_FILE='./archive_libs/logical/q_cap/chips/chips.prt';

PART_NAME
 C2129 'Q_CAP_C0402-22UF,4V,20%,X6S,CH622KMEB02':;

SECTION_NUMBER 1
 '@T6G_MB_LIB.T6G(SCH_1):PAGE67_I89@PURE_QUANTA.Q_CAP(CHIPS)':
 C_PATH='@t6g_mb_lib.t6g(sch_1):page67_i89@pure_quanta.q_cap(chips)',
 P_PATH='@t6g_mb_lib.t6g(sch_1):page68_i89@pure_quanta.q_cap(chips)',
 PATH='I89',
 DRAWING='@T6G_MB_LIB.T6G(SCH_1):PAGE67',
 TOLERANCE='20%',
 MATERIAL='X6S',
 PHYS_PAGE='68',
 XY='(-13125,5850)',
 ROT='0',
 VER='1',
 PACK_TYPE='C0402',
 LOCATION='C2129',
 CDS_LIB='pure_quanta',
 CDS_PART_NAME='Q_CAP_C0402-22UF,4V,20%,X6S,CH622KMEB02',
 VOLTAGE='4V',
 PART_NUMBER='CH622KMEB02',
 VALUE='22UF',
 PRIM_FILE='./archive_libs/logical/q_cap/chips/chips.prt';

PART_NAME
 C2130 'Q_CAP_C0402-22UF,4V,20%,X6S,CH622KMEB02':;

SECTION_NUMBER 1
 '@T6G_MB_LIB.T6G(SCH_1):PAGE67_I85@PURE_QUANTA.Q_CAP(CHIPS)':
 C_PATH='@t6g_mb_lib.t6g(sch_1):page67_i85@pure_quanta.q_cap(chips)',
 P_PATH='@t6g_mb_lib.t6g(sch_1):page68_i85@pure_quanta.q_cap(chips)',
 PATH='I85',
 DRAWING='@T6G_MB_LIB.T6G(SCH_1):PAGE67',
 TOLERANCE='20%',
 MATERIAL='X6S',
 PHYS_PAGE='68',
 XY='(-13125,5050)',
 ROT='0',
 VER='1',
 PACK_TYPE='C0402',
 LOCATION='C2130',
 CDS_LIB='pure_quanta',
 CDS_PART_NAME='Q_CAP_C0402-22UF,4V,20%,X6S,CH622KMEB02',
 VOLTAGE='4V',
 PART_NUMBER='CH622KMEB02',
 VALUE='22UF',
 PRIM_FILE='./archive_libs/logical/q_cap/chips/chips.prt';

PART_NAME
 C2131 'Q_CAP_C0402-22UF,4V,20%,X6S,CH622KMEB02':;

SECTION_NUMBER 1
 '@T6G_MB_LIB.T6G(SCH_1):PAGE67_I135@PURE_QUANTA.Q_CAP(CHIPS)':
 C_PATH='@t6g_mb_lib.t6g(sch_1):page67_i135@pure_quanta.q_cap(chips)',
 P_PATH='@t6g_mb_lib.t6g(sch_1):page68_i135@pure_quanta.q_cap(chips)',
 PATH='I135',
 DRAWING='@T6G_MB_LIB.T6G(SCH_1):PAGE67',
 TOLERANCE='20%',
 MATERIAL='X6S',
 PHYS_PAGE='68',
 XY='(-8200,5950)',
 ROT='0',
 VER='1',
 PACK_TYPE='C0402',
 LOCATION='C2131',
 CDS_LIB='pure_quanta',
 CDS_PART_NAME='Q_CAP_C0402-22UF,4V,20%,X6S,CH622KMEB02',
 VOLTAGE='4V',
 PART_NUMBER='CH622KMEB02',
 VALUE='22UF',
 PRIM_FILE='./archive_libs/logical/q_cap/chips/chips.prt';

PART_NAME
 C2132 'Q_CAP_C0402-22UF,4V,20%,X6S,CH622KMEB02':;

SECTION_NUMBER 1
 '@T6G_MB_LIB.T6G(SCH_1):PAGE67_I113@PURE_QUANTA.Q_CAP(CHIPS)':
 C_PATH='@t6g_mb_lib.t6g(sch_1):page67_i113@pure_quanta.q_cap(chips)',
 P_PATH='@t6g_mb_lib.t6g(sch_1):page68_i113@pure_quanta.q_cap(chips)',
 PATH='I113',
 DRAWING='@T6G_MB_LIB.T6G(SCH_1):PAGE67',
 TOLERANCE='20%',
 MATERIAL='X6S',
 PHYS_PAGE='68',
 XY='(-13125,2350)',
 ROT='0',
 VER='1',
 PACK_TYPE='C0402',
 LOCATION='C2132',
 CDS_LIB='pure_quanta',
 CDS_PART_NAME='Q_CAP_C0402-22UF,4V,20%,X6S,CH622KMEB02',
 VOLTAGE='4V',
 PART_NUMBER='CH622KMEB02',
 VALUE='22UF',
 PRIM_FILE='./archive_libs/logical/q_cap/chips/chips.prt';

PART_NAME
 C2133 'Q_CAP_C0402-22UF,4V,20%,X6S,CH622KMEB02':;

SECTION_NUMBER 1
 '@T6G_MB_LIB.T6G(SCH_1):PAGE67_I110@PURE_QUANTA.Q_CAP(CHIPS)':
 C_PATH='@t6g_mb_lib.t6g(sch_1):page67_i110@pure_quanta.q_cap(chips)',
 P_PATH='@t6g_mb_lib.t6g(sch_1):page68_i110@pure_quanta.q_cap(chips)',
 PATH='I110',
 DRAWING='@T6G_MB_LIB.T6G(SCH_1):PAGE67',
 TOLERANCE='20%',
 MATERIAL='X6S',
 PHYS_PAGE='68',
 XY='(-13125,1600)',
 ROT='0',
 VER='1',
 PACK_TYPE='C0402',
 LOCATION='C2133',
 CDS_LIB='pure_quanta',
 CDS_PART_NAME='Q_CAP_C0402-22UF,4V,20%,X6S,CH622KMEB02',
 VOLTAGE='4V',
 PART_NUMBER='CH622KMEB02',
 VALUE='22UF',
 PRIM_FILE='./archive_libs/logical/q_cap/chips/chips.prt';

PART_NAME
 C2134 'Q_CAP_C0402-22UF,4V,20%,X6S,CH622KMEB02':;

SECTION_NUMBER 1
 '@T6G_MB_LIB.T6G(SCH_1):PAGE67_I90@PURE_QUANTA.Q_CAP(CHIPS)':
 C_PATH='@t6g_mb_lib.t6g(sch_1):page67_i90@pure_quanta.q_cap(chips)',
 P_PATH='@t6g_mb_lib.t6g(sch_1):page68_i90@pure_quanta.q_cap(chips)',
 PATH='I90',
 DRAWING='@T6G_MB_LIB.T6G(SCH_1):PAGE67',
 TOLERANCE='20%',
 MATERIAL='X6S',
 PHYS_PAGE='68',
 XY='(-12675,5850)',
 ROT='0',
 VER='1',
 PACK_TYPE='C0402',
 LOCATION='C2134',
 CDS_LIB='pure_quanta',
 CDS_PART_NAME='Q_CAP_C0402-22UF,4V,20%,X6S,CH622KMEB02',
 VOLTAGE='4V',
 PART_NUMBER='CH622KMEB02',
 VALUE='22UF',
 PRIM_FILE='./archive_libs/logical/q_cap/chips/chips.prt';

PART_NAME
 C2135 'Q_CAP_C0402-22UF,4V,20%,X6S,CH622KMEB02':;

SECTION_NUMBER 1
 '@T6G_MB_LIB.T6G(SCH_1):PAGE67_I87@PURE_QUANTA.Q_CAP(CHIPS)':
 C_PATH='@t6g_mb_lib.t6g(sch_1):page67_i87@pure_quanta.q_cap(chips)',
 P_PATH='@t6g_mb_lib.t6g(sch_1):page68_i87@pure_quanta.q_cap(chips)',
 PATH='I87',
 DRAWING='@T6G_MB_LIB.T6G(SCH_1):PAGE67',
 TOLERANCE='20%',
 MATERIAL='X6S',
 PHYS_PAGE='68',
 XY='(-12675,5050)',
 ROT='0',
 VER='1',
 PACK_TYPE='C0402',
 LOCATION='C2135',
 CDS_LIB='pure_quanta',
 CDS_PART_NAME='Q_CAP_C0402-22UF,4V,20%,X6S,CH622KMEB02',
 VOLTAGE='4V',
 PART_NUMBER='CH622KMEB02',
 VALUE='22UF',
 PRIM_FILE='./archive_libs/logical/q_cap/chips/chips.prt';

PART_NAME
 C2136 'Q_CAP_C0402-22UF,4V,20%,X6S,CH622KMEB02':;

SECTION_NUMBER 1
 '@T6G_MB_LIB.T6G(SCH_1):PAGE67_I136@PURE_QUANTA.Q_CAP(CHIPS)':
 C_PATH='@t6g_mb_lib.t6g(sch_1):page67_i136@pure_quanta.q_cap(chips)',
 P_PATH='@t6g_mb_lib.t6g(sch_1):page68_i136@pure_quanta.q_cap(chips)',
 PATH='I136',
 DRAWING='@T6G_MB_LIB.T6G(SCH_1):PAGE67',
 TOLERANCE='20%',
 MATERIAL='X6S',
 PHYS_PAGE='68',
 XY='(-7750,5950)',
 ROT='0',
 VER='1',
 PACK_TYPE='C0402',
 LOCATION='C2136',
 CDS_LIB='pure_quanta',
 CDS_PART_NAME='Q_CAP_C0402-22UF,4V,20%,X6S,CH622KMEB02',
 VOLTAGE='4V',
 PART_NUMBER='CH622KMEB02',
 VALUE='22UF',
 PRIM_FILE='./archive_libs/logical/q_cap/chips/chips.prt';

PART_NAME
 C2137 'Q_CAP_C0402-22UF,4V,20%,X6S,CH622KMEB02':;

SECTION_NUMBER 1
 '@T6G_MB_LIB.T6G(SCH_1):PAGE67_I115@PURE_QUANTA.Q_CAP(CHIPS)':
 C_PATH='@t6g_mb_lib.t6g(sch_1):page67_i115@pure_quanta.q_cap(chips)',
 P_PATH='@t6g_mb_lib.t6g(sch_1):page68_i115@pure_quanta.q_cap(chips)',
 PATH='I115',
 DRAWING='@T6G_MB_LIB.T6G(SCH_1):PAGE67',
 TOLERANCE='20%',
 MATERIAL='X6S',
 PHYS_PAGE='68',
 XY='(-12675,2350)',
 ROT='0',
 VER='1',
 PACK_TYPE='C0402',
 LOCATION='C2137',
 CDS_LIB='pure_quanta',
 CDS_PART_NAME='Q_CAP_C0402-22UF,4V,20%,X6S,CH622KMEB02',
 VOLTAGE='4V',
 PART_NUMBER='CH622KMEB02',
 VALUE='22UF',
 PRIM_FILE='./archive_libs/logical/q_cap/chips/chips.prt';

PART_NAME
 C2138 'Q_CAP_C0402-22UF,4V,20%,X6S,CH622KMEB02':;

SECTION_NUMBER 1
 '@T6G_MB_LIB.T6G(SCH_1):PAGE67_I112@PURE_QUANTA.Q_CAP(CHIPS)':
 C_PATH='@t6g_mb_lib.t6g(sch_1):page67_i112@pure_quanta.q_cap(chips)',
 P_PATH='@t6g_mb_lib.t6g(sch_1):page68_i112@pure_quanta.q_cap(chips)',
 PATH='I112',
 DRAWING='@T6G_MB_LIB.T6G(SCH_1):PAGE67',
 TOLERANCE='20%',
 MATERIAL='X6S',
 PHYS_PAGE='68',
 XY='(-12675,1600)',
 ROT='0',
 VER='1',
 PACK_TYPE='C0402',
 LOCATION='C2138',
 CDS_LIB='pure_quanta',
 CDS_PART_NAME='Q_CAP_C0402-22UF,4V,20%,X6S,CH622KMEB02',
 VOLTAGE='4V',
 PART_NUMBER='CH622KMEB02',
 VALUE='22UF',
 PRIM_FILE='./archive_libs/logical/q_cap/chips/chips.prt';

PART_NAME
 C2139 'Q_CAP_C0402-22UF,4V,20%,X6S,CH622KMEB02':;

SECTION_NUMBER 1
 '@T6G_MB_LIB.T6G(SCH_1):PAGE67_I95@PURE_QUANTA.Q_CAP(CHIPS)':
 C_PATH='@t6g_mb_lib.t6g(sch_1):page67_i95@pure_quanta.q_cap(chips)',
 P_PATH='@t6g_mb_lib.t6g(sch_1):page68_i95@pure_quanta.q_cap(chips)',
 PATH='I95',
 DRAWING='@T6G_MB_LIB.T6G(SCH_1):PAGE67',
 TOLERANCE='20%',
 MATERIAL='X6S',
 PHYS_PAGE='68',
 XY='(-12225,5850)',
 ROT='0',
 VER='1',
 PACK_TYPE='C0402',
 LOCATION='C2139',
 CDS_LIB='pure_quanta',
 CDS_PART_NAME='Q_CAP_C0402-22UF,4V,20%,X6S,CH622KMEB02',
 VOLTAGE='4V',
 PART_NUMBER='CH622KMEB02',
 VALUE='22UF',
 PRIM_FILE='./archive_libs/logical/q_cap/chips/chips.prt';

PART_NAME
 C2140 'Q_CAP_C0402-22UF,4V,20%,X6S,CH622KMEB02':;

SECTION_NUMBER 1
 '@T6G_MB_LIB.T6G(SCH_1):PAGE67_I92@PURE_QUANTA.Q_CAP(CHIPS)':
 C_PATH='@t6g_mb_lib.t6g(sch_1):page67_i92@pure_quanta.q_cap(chips)',
 P_PATH='@t6g_mb_lib.t6g(sch_1):page68_i92@pure_quanta.q_cap(chips)',
 PATH='I92',
 DRAWING='@T6G_MB_LIB.T6G(SCH_1):PAGE67',
 TOLERANCE='20%',
 MATERIAL='X6S',
 PHYS_PAGE='68',
 XY='(-12225,5050)',
 ROT='0',
 VER='1',
 PACK_TYPE='C0402',
 LOCATION='C2140',
 CDS_LIB='pure_quanta',
 CDS_PART_NAME='Q_CAP_C0402-22UF,4V,20%,X6S,CH622KMEB02',
 VOLTAGE='4V',
 PART_NUMBER='CH622KMEB02',
 VALUE='22UF',
 PRIM_FILE='./archive_libs/logical/q_cap/chips/chips.prt';

PART_NAME
 C2141 'Q_CAP_C0402-22UF,4V,20%,X6S,CH622KMEB02':;

SECTION_NUMBER 1
 '@T6G_MB_LIB.T6G(SCH_1):PAGE67_I137@PURE_QUANTA.Q_CAP(CHIPS)':
 C_PATH='@t6g_mb_lib.t6g(sch_1):page67_i137@pure_quanta.q_cap(chips)',
 P_PATH='@t6g_mb_lib.t6g(sch_1):page68_i137@pure_quanta.q_cap(chips)',
 PATH='I137',
 DRAWING='@T6G_MB_LIB.T6G(SCH_1):PAGE67',
 TOLERANCE='20%',
 MATERIAL='X6S',
 PHYS_PAGE='68',
 XY='(-7300,5950)',
 ROT='0',
 VER='1',
 PACK_TYPE='C0402',
 LOCATION='C2141',
 CDS_LIB='pure_quanta',
 CDS_PART_NAME='Q_CAP_C0402-22UF,4V,20%,X6S,CH622KMEB02',
 VOLTAGE='4V',
 PART_NUMBER='CH622KMEB02',
 VALUE='22UF',
 PRIM_FILE='./archive_libs/logical/q_cap/chips/chips.prt';

PART_NAME
 C2142 'Q_CAP_C0402-22UF,4V,20%,X6S,CH622KMEB02':;

SECTION_NUMBER 1
 '@T6G_MB_LIB.T6G(SCH_1):PAGE67_I121@PURE_QUANTA.Q_CAP(CHIPS)':
 C_PATH='@t6g_mb_lib.t6g(sch_1):page67_i121@pure_quanta.q_cap(chips)',
 P_PATH='@t6g_mb_lib.t6g(sch_1):page68_i121@pure_quanta.q_cap(chips)',
 PATH='I121',
 DRAWING='@T6G_MB_LIB.T6G(SCH_1):PAGE67',
 TOLERANCE='20%',
 MATERIAL='X6S',
 PHYS_PAGE='68',
 XY='(-12225,2350)',
 ROT='0',
 VER='1',
 PACK_TYPE='C0402',
 LOCATION='C2142',
 CDS_LIB='pure_quanta',
 CDS_PART_NAME='Q_CAP_C0402-22UF,4V,20%,X6S,CH622KMEB02',
 VOLTAGE='4V',
 PART_NUMBER='CH622KMEB02',
 VALUE='22UF',
 PRIM_FILE='./archive_libs/logical/q_cap/chips/chips.prt';

PART_NAME
 C2143 'Q_CAP_C0402-22UF,4V,20%,X6S,CH622KMEB02':;

SECTION_NUMBER 1
 '@T6G_MB_LIB.T6G(SCH_1):PAGE67_I96@PURE_QUANTA.Q_CAP(CHIPS)':
 C_PATH='@t6g_mb_lib.t6g(sch_1):page67_i96@pure_quanta.q_cap(chips)',
 P_PATH='@t6g_mb_lib.t6g(sch_1):page68_i96@pure_quanta.q_cap(chips)',
 PATH='I96',
 DRAWING='@T6G_MB_LIB.T6G(SCH_1):PAGE67',
 TOLERANCE='20%',
 MATERIAL='X6S',
 PHYS_PAGE='68',
 XY='(-11775,5850)',
 ROT='0',
 VER='1',
 PACK_TYPE='C0402',
 LOCATION='C2143',
 CDS_LIB='pure_quanta',
 CDS_PART_NAME='Q_CAP_C0402-22UF,4V,20%,X6S,CH622KMEB02',
 VOLTAGE='4V',
 PART_NUMBER='CH622KMEB02',
 VALUE='22UF',
 PRIM_FILE='./archive_libs/logical/q_cap/chips/chips.prt';

PART_NAME
 C2144 'Q_CAP_C0402-22UF,4V,20%,X6S,CH622KMEB02':;

SECTION_NUMBER 1
 '@T6G_MB_LIB.T6G(SCH_1):PAGE67_I93@PURE_QUANTA.Q_CAP(CHIPS)':
 C_PATH='@t6g_mb_lib.t6g(sch_1):page67_i93@pure_quanta.q_cap(chips)',
 P_PATH='@t6g_mb_lib.t6g(sch_1):page68_i93@pure_quanta.q_cap(chips)',
 PATH='I93',
 DRAWING='@T6G_MB_LIB.T6G(SCH_1):PAGE67',
 TOLERANCE='20%',
 MATERIAL='X6S',
 PHYS_PAGE='68',
 XY='(-11775,5050)',
 ROT='0',
 VER='1',
 PACK_TYPE='C0402',
 LOCATION='C2144',
 CDS_LIB='pure_quanta',
 CDS_PART_NAME='Q_CAP_C0402-22UF,4V,20%,X6S,CH622KMEB02',
 VOLTAGE='4V',
 PART_NUMBER='CH622KMEB02',
 VALUE='22UF',
 PRIM_FILE='./archive_libs/logical/q_cap/chips/chips.prt';

PART_NAME
 C2145 'Q_CAP_C0402-22UF,4V,20%,X6S,CH622KMEB02':;

SECTION_NUMBER 1
 '@T6G_MB_LIB.T6G(SCH_1):PAGE67_I138@PURE_QUANTA.Q_CAP(CHIPS)':
 C_PATH='@t6g_mb_lib.t6g(sch_1):page67_i138@pure_quanta.q_cap(chips)',
 P_PATH='@t6g_mb_lib.t6g(sch_1):page68_i138@pure_quanta.q_cap(chips)',
 PATH='I138',
 DRAWING='@T6G_MB_LIB.T6G(SCH_1):PAGE67',
 TOLERANCE='20%',
 MATERIAL='X6S',
 PHYS_PAGE='68',
 XY='(-6850,5950)',
 ROT='0',
 VER='1',
 PACK_TYPE='C0402',
 LOCATION='C2145',
 CDS_LIB='pure_quanta',
 CDS_PART_NAME='Q_CAP_C0402-22UF,4V,20%,X6S,CH622KMEB02',
 VOLTAGE='4V',
 PART_NUMBER='CH622KMEB02',
 VALUE='22UF',
 PRIM_FILE='./archive_libs/logical/q_cap/chips/chips.prt';

PART_NAME
 C2146 'Q_CAP_C0402-22UF,4V,20%,X6S,CH622KMEB02':;

SECTION_NUMBER 1
 '@T6G_MB_LIB.T6G(SCH_1):PAGE67_I122@PURE_QUANTA.Q_CAP(CHIPS)':
 C_PATH='@t6g_mb_lib.t6g(sch_1):page67_i122@pure_quanta.q_cap(chips)',
 P_PATH='@t6g_mb_lib.t6g(sch_1):page68_i122@pure_quanta.q_cap(chips)',
 PATH='I122',
 DRAWING='@T6G_MB_LIB.T6G(SCH_1):PAGE67',
 TOLERANCE='20%',
 MATERIAL='X6S',
 PHYS_PAGE='68',
 XY='(-11775,2350)',
 ROT='0',
 VER='1',
 PACK_TYPE='C0402',
 LOCATION='C2146',
 CDS_LIB='pure_quanta',
 CDS_PART_NAME='Q_CAP_C0402-22UF,4V,20%,X6S,CH622KMEB02',
 VOLTAGE='4V',
 PART_NUMBER='CH622KMEB02',
 VALUE='22UF',
 PRIM_FILE='./archive_libs/logical/q_cap/chips/chips.prt';

PART_NAME
 C2147 'Q_CAP_C0402-22UF,4V,20%,X6S,CH622KMEB02':;

SECTION_NUMBER 1
 '@T6G_MB_LIB.T6G(SCH_1):PAGE67_I109@PURE_QUANTA.Q_CAP(CHIPS)':
 C_PATH='@t6g_mb_lib.t6g(sch_1):page67_i109@pure_quanta.q_cap(chips)',
 P_PATH='@t6g_mb_lib.t6g(sch_1):page68_i109@pure_quanta.q_cap(chips)',
 PATH='I109',
 DRAWING='@T6G_MB_LIB.T6G(SCH_1):PAGE67',
 TOLERANCE='20%',
 MATERIAL='X6S',
 PHYS_PAGE='68',
 XY='(-11325,5850)',
 ROT='0',
 VER='1',
 PACK_TYPE='C0402',
 LOCATION='C2147',
 CDS_LIB='pure_quanta',
 CDS_PART_NAME='Q_CAP_C0402-22UF,4V,20%,X6S,CH622KMEB02',
 VOLTAGE='4V',
 PART_NUMBER='CH622KMEB02',
 VALUE='22UF',
 PRIM_FILE='./archive_libs/logical/q_cap/chips/chips.prt';

PART_NAME
 C2148 'Q_CAP_C0402-22UF,4V,20%,X6S,CH622KMEB02':;

SECTION_NUMBER 1
 '@T6G_MB_LIB.T6G(SCH_1):PAGE67_I94@PURE_QUANTA.Q_CAP(CHIPS)':
 C_PATH='@t6g_mb_lib.t6g(sch_1):page67_i94@pure_quanta.q_cap(chips)',
 P_PATH='@t6g_mb_lib.t6g(sch_1):page68_i94@pure_quanta.q_cap(chips)',
 PATH='I94',
 DRAWING='@T6G_MB_LIB.T6G(SCH_1):PAGE67',
 TOLERANCE='20%',
 MATERIAL='X6S',
 PHYS_PAGE='68',
 XY='(-11325,5050)',
 ROT='0',
 VER='1',
 PACK_TYPE='C0402',
 LOCATION='C2148',
 CDS_LIB='pure_quanta',
 CDS_PART_NAME='Q_CAP_C0402-22UF,4V,20%,X6S,CH622KMEB02',
 VOLTAGE='4V',
 PART_NUMBER='CH622KMEB02',
 VALUE='22UF',
 PRIM_FILE='./archive_libs/logical/q_cap/chips/chips.prt';

PART_NAME
 C2149 'Q_CAP_C0402-22UF,4V,20%,X6S,CH622KMEB02':;

SECTION_NUMBER 1
 '@T6G_MB_LIB.T6G(SCH_1):PAGE67_I139@PURE_QUANTA.Q_CAP(CHIPS)':
 C_PATH='@t6g_mb_lib.t6g(sch_1):page67_i139@pure_quanta.q_cap(chips)',
 P_PATH='@t6g_mb_lib.t6g(sch_1):page68_i139@pure_quanta.q_cap(chips)',
 PATH='I139',
 DRAWING='@T6G_MB_LIB.T6G(SCH_1):PAGE67',
 TOLERANCE='20%',
 MATERIAL='X6S',
 PHYS_PAGE='68',
 XY='(-6400,5950)',
 ROT='0',
 VER='1',
 PACK_TYPE='C0402',
 LOCATION='C2149',
 CDS_LIB='pure_quanta',
 CDS_PART_NAME='Q_CAP_C0402-22UF,4V,20%,X6S,CH622KMEB02',
 VOLTAGE='4V',
 PART_NUMBER='CH622KMEB02',
 VALUE='22UF',
 PRIM_FILE='./archive_libs/logical/q_cap/chips/chips.prt';

PART_NAME
 C2150 'Q_CAP_C0402-22UF,4V,20%,X6S,CH622KMEB02':;

SECTION_NUMBER 1
 '@T6G_MB_LIB.T6G(SCH_1):PAGE67_I123@PURE_QUANTA.Q_CAP(CHIPS)':
 C_PATH='@t6g_mb_lib.t6g(sch_1):page67_i123@pure_quanta.q_cap(chips)',
 P_PATH='@t6g_mb_lib.t6g(sch_1):page68_i123@pure_quanta.q_cap(chips)',
 PATH='I123',
 DRAWING='@T6G_MB_LIB.T6G(SCH_1):PAGE67',
 TOLERANCE='20%',
 MATERIAL='X6S',
 PHYS_PAGE='68',
 XY='(-11325,2350)',
 ROT='0',
 VER='1',
 PACK_TYPE='C0402',
 LOCATION='C2150',
 CDS_LIB='pure_quanta',
 CDS_PART_NAME='Q_CAP_C0402-22UF,4V,20%,X6S,CH622KMEB02',
 VOLTAGE='4V',
 PART_NUMBER='CH622KMEB02',
 VALUE='22UF',
 PRIM_FILE='./archive_libs/logical/q_cap/chips/chips.prt';

PART_NAME
 C2151 'Q_CAP_C0402-22UF,4V,20%,X6S,CH622KMEB02':;

SECTION_NUMBER 1
 '@T6G_MB_LIB.T6G(SCH_1):PAGE67_I99@PURE_QUANTA.Q_CAP(CHIPS)':
 C_PATH='@t6g_mb_lib.t6g(sch_1):page67_i99@pure_quanta.q_cap(chips)',
 P_PATH='@t6g_mb_lib.t6g(sch_1):page68_i99@pure_quanta.q_cap(chips)',
 PATH='I99',
 DRAWING='@T6G_MB_LIB.T6G(SCH_1):PAGE67',
 TOLERANCE='20%',
 MATERIAL='X6S',
 PHYS_PAGE='68',
 XY='(-10875,5850)',
 ROT='0',
 VER='1',
 PACK_TYPE='C0402',
 LOCATION='C2151',
 CDS_LIB='pure_quanta',
 CDS_PART_NAME='Q_CAP_C0402-22UF,4V,20%,X6S,CH622KMEB02',
 VOLTAGE='4V',
 PART_NUMBER='CH622KMEB02',
 VALUE='22UF',
 PRIM_FILE='./archive_libs/logical/q_cap/chips/chips.prt';

PART_NAME
 C2152 'Q_CAP_C0402-22UF,4V,20%,X6S,CH622KMEB02':;

SECTION_NUMBER 1
 '@T6G_MB_LIB.T6G(SCH_1):PAGE67_I97@PURE_QUANTA.Q_CAP(CHIPS)':
 C_PATH='@t6g_mb_lib.t6g(sch_1):page67_i97@pure_quanta.q_cap(chips)',
 P_PATH='@t6g_mb_lib.t6g(sch_1):page68_i97@pure_quanta.q_cap(chips)',
 PATH='I97',
 DRAWING='@T6G_MB_LIB.T6G(SCH_1):PAGE67',
 TOLERANCE='20%',
 MATERIAL='X6S',
 PHYS_PAGE='68',
 XY='(-10875,5050)',
 ROT='0',
 VER='1',
 PACK_TYPE='C0402',
 LOCATION='C2152',
 CDS_LIB='pure_quanta',
 CDS_PART_NAME='Q_CAP_C0402-22UF,4V,20%,X6S,CH622KMEB02',
 VOLTAGE='4V',
 PART_NUMBER='CH622KMEB02',
 VALUE='22UF',
 PRIM_FILE='./archive_libs/logical/q_cap/chips/chips.prt';

PART_NAME
 C2153 'Q_CAP_C0402-22UF,4V,20%,X6S,CH622KMEB02':;

SECTION_NUMBER 1
 '@T6G_MB_LIB.T6G(SCH_1):PAGE67_I124@PURE_QUANTA.Q_CAP(CHIPS)':
 C_PATH='@t6g_mb_lib.t6g(sch_1):page67_i124@pure_quanta.q_cap(chips)',
 P_PATH='@t6g_mb_lib.t6g(sch_1):page68_i124@pure_quanta.q_cap(chips)',
 PATH='I124',
 DRAWING='@T6G_MB_LIB.T6G(SCH_1):PAGE67',
 TOLERANCE='20%',
 MATERIAL='X6S',
 PHYS_PAGE='68',
 XY='(-10875,2350)',
 ROT='0',
 VER='1',
 PACK_TYPE='C0402',
 LOCATION='C2153',
 CDS_LIB='pure_quanta',
 CDS_PART_NAME='Q_CAP_C0402-22UF,4V,20%,X6S,CH622KMEB02',
 VOLTAGE='4V',
 PART_NUMBER='CH622KMEB02',
 VALUE='22UF',
 PRIM_FILE='./archive_libs/logical/q_cap/chips/chips.prt';

PART_NAME
 C2154 'Q_CAP_C0402-22UF,4V,20%,X6S,CH622KMEB02':;

SECTION_NUMBER 1
 '@T6G_MB_LIB.T6G(SCH_1):PAGE67_I100@PURE_QUANTA.Q_CAP(CHIPS)':
 C_PATH='@t6g_mb_lib.t6g(sch_1):page67_i100@pure_quanta.q_cap(chips)',
 P_PATH='@t6g_mb_lib.t6g(sch_1):page68_i100@pure_quanta.q_cap(chips)',
 PATH='I100',
 DRAWING='@T6G_MB_LIB.T6G(SCH_1):PAGE67',
 TOLERANCE='20%',
 MATERIAL='X6S',
 PHYS_PAGE='68',
 XY='(-10425,5850)',
 ROT='0',
 VER='1',
 PACK_TYPE='C0402',
 LOCATION='C2154',
 CDS_LIB='pure_quanta',
 CDS_PART_NAME='Q_CAP_C0402-22UF,4V,20%,X6S,CH622KMEB02',
 VOLTAGE='4V',
 PART_NUMBER='CH622KMEB02',
 VALUE='22UF',
 PRIM_FILE='./archive_libs/logical/q_cap/chips/chips.prt';

PART_NAME
 C2155 'Q_CAP_C0402-22UF,4V,20%,X6S,CH622KMEB02':;

SECTION_NUMBER 1
 '@T6G_MB_LIB.T6G(SCH_1):PAGE67_I98@PURE_QUANTA.Q_CAP(CHIPS)':
 C_PATH='@t6g_mb_lib.t6g(sch_1):page67_i98@pure_quanta.q_cap(chips)',
 P_PATH='@t6g_mb_lib.t6g(sch_1):page68_i98@pure_quanta.q_cap(chips)',
 PATH='I98',
 DRAWING='@T6G_MB_LIB.T6G(SCH_1):PAGE67',
 TOLERANCE='20%',
 MATERIAL='X6S',
 PHYS_PAGE='68',
 XY='(-10425,5050)',
 ROT='0',
 VER='1',
 PACK_TYPE='C0402',
 LOCATION='C2155',
 CDS_LIB='pure_quanta',
 CDS_PART_NAME='Q_CAP_C0402-22UF,4V,20%,X6S,CH622KMEB02',
 VOLTAGE='4V',
 PART_NUMBER='CH622KMEB02',
 VALUE='22UF',
 PRIM_FILE='./archive_libs/logical/q_cap/chips/chips.prt';

PART_NAME
 C2156 'Q_CAP_C0402-22UF,4V,20%,X6S,CH622KMEB02':;

SECTION_NUMBER 1
 '@T6G_MB_LIB.T6G(SCH_1):PAGE67_I125@PURE_QUANTA.Q_CAP(CHIPS)':
 C_PATH='@t6g_mb_lib.t6g(sch_1):page67_i125@pure_quanta.q_cap(chips)',
 P_PATH='@t6g_mb_lib.t6g(sch_1):page68_i125@pure_quanta.q_cap(chips)',
 PATH='I125',
 DRAWING='@T6G_MB_LIB.T6G(SCH_1):PAGE67',
 TOLERANCE='20%',
 MATERIAL='X6S',
 PHYS_PAGE='68',
 XY='(-10425,2350)',
 ROT='0',
 VER='1',
 PACK_TYPE='C0402',
 LOCATION='C2156',
 CDS_LIB='pure_quanta',
 CDS_PART_NAME='Q_CAP_C0402-22UF,4V,20%,X6S,CH622KMEB02',
 VOLTAGE='4V',
 PART_NUMBER='CH622KMEB02',
 VALUE='22UF',
 PRIM_FILE='./archive_libs/logical/q_cap/chips/chips.prt';

PART_NAME
 C2157 'Q_CAP_C0402-22UF,4V,20%,X6S,CH622KMEB02':;

SECTION_NUMBER 1
 '@T6G_MB_LIB.T6G(SCH_1):PAGE67_I103@PURE_QUANTA.Q_CAP(CHIPS)':
 C_PATH='@t6g_mb_lib.t6g(sch_1):page67_i103@pure_quanta.q_cap(chips)',
 P_PATH='@t6g_mb_lib.t6g(sch_1):page68_i103@pure_quanta.q_cap(chips)',
 PATH='I103',
 DRAWING='@T6G_MB_LIB.T6G(SCH_1):PAGE67',
 TOLERANCE='20%',
 MATERIAL='X6S',
 PHYS_PAGE='68',
 XY='(-9975,5850)',
 ROT='0',
 VER='1',
 PACK_TYPE='C0402',
 LOCATION='C2157',
 CDS_LIB='pure_quanta',
 CDS_PART_NAME='Q_CAP_C0402-22UF,4V,20%,X6S,CH622KMEB02',
 VOLTAGE='4V',
 PART_NUMBER='CH622KMEB02',
 VALUE='22UF',
 PRIM_FILE='./archive_libs/logical/q_cap/chips/chips.prt';

PART_NAME
 C2158 'Q_CAP_C0402-22UF,4V,20%,X6S,CH622KMEB02':;

SECTION_NUMBER 1
 '@T6G_MB_LIB.T6G(SCH_1):PAGE67_I127@PURE_QUANTA.Q_CAP(CHIPS)':
 C_PATH='@t6g_mb_lib.t6g(sch_1):page67_i127@pure_quanta.q_cap(chips)',
 P_PATH='@t6g_mb_lib.t6g(sch_1):page68_i127@pure_quanta.q_cap(chips)',
 PATH='I127',
 DRAWING='@T6G_MB_LIB.T6G(SCH_1):PAGE67',
 TOLERANCE='20%',
 MATERIAL='X6S',
 PHYS_PAGE='68',
 XY='(-9975,2350)',
 ROT='0',
 VER='1',
 PACK_TYPE='C0402',
 LOCATION='C2158',
 CDS_LIB='pure_quanta',
 CDS_PART_NAME='Q_CAP_C0402-22UF,4V,20%,X6S,CH622KMEB02',
 VOLTAGE='4V',
 PART_NUMBER='CH622KMEB02',
 VALUE='22UF',
 PRIM_FILE='./archive_libs/logical/q_cap/chips/chips.prt';

PART_NAME
 C2159 'Q_CAP_C0402-22UF,4V,20%,X6S,CH622KMEB02':;

SECTION_NUMBER 1
 '@T6G_MB_LIB.T6G(SCH_1):PAGE67_I104@PURE_QUANTA.Q_CAP(CHIPS)':
 C_PATH='@t6g_mb_lib.t6g(sch_1):page67_i104@pure_quanta.q_cap(chips)',
 P_PATH='@t6g_mb_lib.t6g(sch_1):page68_i104@pure_quanta.q_cap(chips)',
 PATH='I104',
 DRAWING='@T6G_MB_LIB.T6G(SCH_1):PAGE67',
 TOLERANCE='20%',
 MATERIAL='X6S',
 PHYS_PAGE='68',
 XY='(-9525,5850)',
 ROT='0',
 VER='1',
 PACK_TYPE='C0402',
 LOCATION='C2159',
 CDS_LIB='pure_quanta',
 CDS_PART_NAME='Q_CAP_C0402-22UF,4V,20%,X6S,CH622KMEB02',
 VOLTAGE='4V',
 PART_NUMBER='CH622KMEB02',
 VALUE='22UF',
 PRIM_FILE='./archive_libs/logical/q_cap/chips/chips.prt';

PART_NAME
 C2160 'Q_CAP_C0402-22UF,4V,20%,X6S,CH622KMEB02':;

SECTION_NUMBER 1
 '@T6G_MB_LIB.T6G(SCH_1):PAGE67_I128@PURE_QUANTA.Q_CAP(CHIPS)':
 C_PATH='@t6g_mb_lib.t6g(sch_1):page67_i128@pure_quanta.q_cap(chips)',
 P_PATH='@t6g_mb_lib.t6g(sch_1):page68_i128@pure_quanta.q_cap(chips)',
 PATH='I128',
 DRAWING='@T6G_MB_LIB.T6G(SCH_1):PAGE67',
 TOLERANCE='20%',
 MATERIAL='X6S',
 PHYS_PAGE='68',
 XY='(-9525,2350)',
 ROT='0',
 VER='1',
 PACK_TYPE='C0402',
 LOCATION='C2160',
 CDS_LIB='pure_quanta',
 CDS_PART_NAME='Q_CAP_C0402-22UF,4V,20%,X6S,CH622KMEB02',
 VOLTAGE='4V',
 PART_NUMBER='CH622KMEB02',
 VALUE='22UF',
 PRIM_FILE='./archive_libs/logical/q_cap/chips/chips.prt';

PART_NAME
 C2161 'Q_CAP_C0402-22UF,4V,20%,X6S,CH622KMEB02':;

SECTION_NUMBER 1
 '@T6G_MB_LIB.T6G(SCH_1):PAGE67_I108@PURE_QUANTA.Q_CAP(CHIPS)':
 C_PATH='@t6g_mb_lib.t6g(sch_1):page67_i108@pure_quanta.q_cap(chips)',
 P_PATH='@t6g_mb_lib.t6g(sch_1):page68_i108@pure_quanta.q_cap(chips)',
 PATH='I108',
 DRAWING='@T6G_MB_LIB.T6G(SCH_1):PAGE67',
 TOLERANCE='20%',
 MATERIAL='X6S',
 PHYS_PAGE='68',
 XY='(-9125,5850)',
 ROT='0',
 VER='1',
 PACK_TYPE='C0402',
 LOCATION='C2161',
 CDS_LIB='pure_quanta',
 CDS_PART_NAME='Q_CAP_C0402-22UF,4V,20%,X6S,CH622KMEB02',
 VOLTAGE='4V',
 PART_NUMBER='CH622KMEB02',
 VALUE='22UF',
 PRIM_FILE='./archive_libs/logical/q_cap/chips/chips.prt';

PART_NAME
 C2162 'Q_CAP_C0402-22UF,4V,20%,X6S,CH622KMEB02':;

SECTION_NUMBER 1
 '@T6G_MB_LIB.T6G(SCH_1):PAGE67_I129@PURE_QUANTA.Q_CAP(CHIPS)':
 C_PATH='@t6g_mb_lib.t6g(sch_1):page67_i129@pure_quanta.q_cap(chips)',
 P_PATH='@t6g_mb_lib.t6g(sch_1):page68_i129@pure_quanta.q_cap(chips)',
 PATH='I129',
 DRAWING='@T6G_MB_LIB.T6G(SCH_1):PAGE67',
 TOLERANCE='20%',
 MATERIAL='X6S',
 PHYS_PAGE='68',
 XY='(-9125,2350)',
 ROT='0',
 VER='1',
 PACK_TYPE='C0402',
 LOCATION='C2162',
 CDS_LIB='pure_quanta',
 CDS_PART_NAME='Q_CAP_C0402-22UF,4V,20%,X6S,CH622KMEB02',
 VOLTAGE='4V',
 PART_NUMBER='CH622KMEB02',
 VALUE='22UF',
 PRIM_FILE='./archive_libs/logical/q_cap/chips/chips.prt';

PART_NAME
 C2163 'Q_CAP_C0402-22UF,4V,20%,X6S,CH622KMEB02':;

SECTION_NUMBER 1
 '@T6G_MB_LIB.T6G(SCH_1):PAGE67_I131@PURE_QUANTA.Q_CAP(CHIPS)':
 C_PATH='@t6g_mb_lib.t6g(sch_1):page67_i131@pure_quanta.q_cap(chips)',
 P_PATH='@t6g_mb_lib.t6g(sch_1):page68_i131@pure_quanta.q_cap(chips)',
 PATH='I131',
 DRAWING='@T6G_MB_LIB.T6G(SCH_1):PAGE67',
 TOLERANCE='20%',
 MATERIAL='X6S',
 PHYS_PAGE='68',
 XY='(-8150,4200)',
 ROT='0',
 VER='1',
 PACK_TYPE='C0402',
 LOCATION='C2163',
 CDS_LIB='pure_quanta',
 CDS_PART_NAME='Q_CAP_C0402-22UF,4V,20%,X6S,CH622KMEB02',
 VOLTAGE='4V',
 PART_NUMBER='CH622KMEB02',
 VALUE='22UF',
 PRIM_FILE='./archive_libs/logical/q_cap/chips/chips.prt';

PART_NAME
 C2164 'Q_CAP_C0402-22UF,4V,20%,X6S,CH622KMEB02':;

SECTION_NUMBER 1
 '@T6G_MB_LIB.T6G(SCH_1):PAGE67_I133@PURE_QUANTA.Q_CAP(CHIPS)':
 C_PATH='@t6g_mb_lib.t6g(sch_1):page67_i133@pure_quanta.q_cap(chips)',
 P_PATH='@t6g_mb_lib.t6g(sch_1):page68_i133@pure_quanta.q_cap(chips)',
 PATH='I133',
 DRAWING='@T6G_MB_LIB.T6G(SCH_1):PAGE67',
 TOLERANCE='20%',
 MATERIAL='X6S',
 PHYS_PAGE='68',
 XY='(-7700,4200)',
 ROT='0',
 VER='1',
 PACK_TYPE='C0402',
 LOCATION='C2164',
 CDS_LIB='pure_quanta',
 CDS_PART_NAME='Q_CAP_C0402-22UF,4V,20%,X6S,CH622KMEB02',
 VOLTAGE='4V',
 PART_NUMBER='CH622KMEB02',
 VALUE='22UF',
 PRIM_FILE='./archive_libs/logical/q_cap/chips/chips.prt';

PART_NAME
 C2165 'Q_CAP_C0402-22UF,4V,20%,X6S,CH622KMEB02':;

SECTION_NUMBER 1
 '@T6G_MB_LIB.T6G(SCH_1):PAGE68_I7@PURE_QUANTA.Q_CAP(CHIPS)':
 C_PATH='@t6g_mb_lib.t6g(sch_1):page68_i7@pure_quanta.q_cap(chips)',
 P_PATH='@t6g_mb_lib.t6g(sch_1):page69_i7@pure_quanta.q_cap(chips)',
 PATH='I7',
 DRAWING='@T6G_MB_LIB.T6G(SCH_1):PAGE68',
 TOLERANCE='20%',
 MATERIAL='X6S',
 PHYS_PAGE='69',
 XY='(-9000,3675)',
 ROT='0',
 VER='1',
 PACK_TYPE='C0402',
 LOCATION='C2165',
 CDS_LIB='pure_quanta',
 CDS_PART_NAME='Q_CAP_C0402-22UF,4V,20%,X6S,CH622KMEB02',
 VOLTAGE='4V',
 PART_NUMBER='CH622KMEB02',
 VALUE='22UF',
 PRIM_FILE='./archive_libs/logical/q_cap/chips/chips.prt';

PART_NAME
 C2166 'Q_CAP_C0402-22UF,4V,20%,X6S,CH622KMEB02':;

SECTION_NUMBER 1
 '@T6G_MB_LIB.T6G(SCH_1):PAGE68_I4@PURE_QUANTA.Q_CAP(CHIPS)':
 C_PATH='@t6g_mb_lib.t6g(sch_1):page68_i4@pure_quanta.q_cap(chips)',
 P_PATH='@t6g_mb_lib.t6g(sch_1):page69_i4@pure_quanta.q_cap(chips)',
 PATH='I4',
 DRAWING='@T6G_MB_LIB.T6G(SCH_1):PAGE68',
 TOLERANCE='20%',
 MATERIAL='X6S',
 PHYS_PAGE='69',
 XY='(-9000,2875)',
 ROT='0',
 VER='1',
 PACK_TYPE='C0402',
 LOCATION='C2166',
 CDS_LIB='pure_quanta',
 CDS_PART_NAME='Q_CAP_C0402-22UF,4V,20%,X6S,CH622KMEB02',
 VOLTAGE='4V',
 PART_NUMBER='CH622KMEB02',
 VALUE='22UF',
 PRIM_FILE='./archive_libs/logical/q_cap/chips/chips.prt';

PART_NAME
 C2167 'Q_CAP_C0402-22UF,4V,20%,X6S,CH622KMEB02':;

SECTION_NUMBER 1
 '@T6G_MB_LIB.T6G(SCH_1):PAGE68_I1@PURE_QUANTA.Q_CAP(CHIPS)':
 C_PATH='@t6g_mb_lib.t6g(sch_1):page68_i1@pure_quanta.q_cap(chips)',
 P_PATH='@t6g_mb_lib.t6g(sch_1):page69_i1@pure_quanta.q_cap(chips)',
 PATH='I1',
 DRAWING='@T6G_MB_LIB.T6G(SCH_1):PAGE68',
 TOLERANCE='20%',
 MATERIAL='X6S',
 PHYS_PAGE='69',
 XY='(-9000,2075)',
 ROT='0',
 VER='1',
 PACK_TYPE='C0402',
 LOCATION='C2167',
 CDS_LIB='pure_quanta',
 CDS_PART_NAME='Q_CAP_C0402-22UF,4V,20%,X6S,CH622KMEB02',
 VOLTAGE='4V',
 PART_NUMBER='CH622KMEB02',
 VALUE='22UF',
 PRIM_FILE='./archive_libs/logical/q_cap/chips/chips.prt';

PART_NAME
 C2169 'Q_CAP_C0402-22UF,4V,20%,X6S,CH622KMEB02':;

SECTION_NUMBER 1
 '@T6G_MB_LIB.T6G(SCH_1):PAGE68_I9@PURE_QUANTA.Q_CAP(CHIPS)':
 C_PATH='@t6g_mb_lib.t6g(sch_1):page68_i9@pure_quanta.q_cap(chips)',
 P_PATH='@t6g_mb_lib.t6g(sch_1):page69_i9@pure_quanta.q_cap(chips)',
 PATH='I9',
 DRAWING='@T6G_MB_LIB.T6G(SCH_1):PAGE68',
 TOLERANCE='20%',
 MATERIAL='X6S',
 PHYS_PAGE='69',
 XY='(-8550,3675)',
 ROT='0',
 VER='1',
 PACK_TYPE='C0402',
 LOCATION='C2169',
 CDS_LIB='pure_quanta',
 CDS_PART_NAME='Q_CAP_C0402-22UF,4V,20%,X6S,CH622KMEB02',
 VOLTAGE='4V',
 PART_NUMBER='CH622KMEB02',
 VALUE='22UF',
 PRIM_FILE='./archive_libs/logical/q_cap/chips/chips.prt';

PART_NAME
 C2170 'Q_CAP_C0402-22UF,4V,20%,X6S,CH622KMEB02':;

SECTION_NUMBER 1
 '@T6G_MB_LIB.T6G(SCH_1):PAGE68_I5@PURE_QUANTA.Q_CAP(CHIPS)':
 C_PATH='@t6g_mb_lib.t6g(sch_1):page68_i5@pure_quanta.q_cap(chips)',
 P_PATH='@t6g_mb_lib.t6g(sch_1):page69_i5@pure_quanta.q_cap(chips)',
 PATH='I5',
 DRAWING='@T6G_MB_LIB.T6G(SCH_1):PAGE68',
 TOLERANCE='20%',
 MATERIAL='X6S',
 PHYS_PAGE='69',
 XY='(-8550,2875)',
 ROT='0',
 VER='1',
 PACK_TYPE='C0402',
 LOCATION='C2170',
 CDS_LIB='pure_quanta',
 CDS_PART_NAME='Q_CAP_C0402-22UF,4V,20%,X6S,CH622KMEB02',
 VOLTAGE='4V',
 PART_NUMBER='CH622KMEB02',
 VALUE='22UF',
 PRIM_FILE='./archive_libs/logical/q_cap/chips/chips.prt';

PART_NAME
 C2171 'Q_CAP_C0402-22UF,4V,20%,X6S,CH622KMEB02':;

SECTION_NUMBER 1
 '@T6G_MB_LIB.T6G(SCH_1):PAGE68_I2@PURE_QUANTA.Q_CAP(CHIPS)':
 C_PATH='@t6g_mb_lib.t6g(sch_1):page68_i2@pure_quanta.q_cap(chips)',
 P_PATH='@t6g_mb_lib.t6g(sch_1):page69_i2@pure_quanta.q_cap(chips)',
 PATH='I2',
 DRAWING='@T6G_MB_LIB.T6G(SCH_1):PAGE68',
 TOLERANCE='20%',
 MATERIAL='X6S',
 PHYS_PAGE='69',
 XY='(-8550,2075)',
 ROT='0',
 VER='1',
 PACK_TYPE='C0402',
 LOCATION='C2171',
 CDS_LIB='pure_quanta',
 CDS_PART_NAME='Q_CAP_C0402-22UF,4V,20%,X6S,CH622KMEB02',
 VOLTAGE='4V',
 PART_NUMBER='CH622KMEB02',
 VALUE='22UF',
 PRIM_FILE='./archive_libs/logical/q_cap/chips/chips.prt';

PART_NAME
 C2173 'Q_CAP_C0402-22UF,4V,20%,X6S,CH622KMEB02':;

SECTION_NUMBER 1
 '@T6G_MB_LIB.T6G(SCH_1):PAGE68_I22@PURE_QUANTA.Q_CAP(CHIPS)':
 C_PATH='@t6g_mb_lib.t6g(sch_1):page68_i22@pure_quanta.q_cap(chips)',
 P_PATH='@t6g_mb_lib.t6g(sch_1):page69_i22@pure_quanta.q_cap(chips)',
 PATH='I22',
 DRAWING='@T6G_MB_LIB.T6G(SCH_1):PAGE68',
 TOLERANCE='20%',
 MATERIAL='X6S',
 PHYS_PAGE='69',
 XY='(-8100,3675)',
 ROT='0',
 VER='1',
 PACK_TYPE='C0402',
 LOCATION='C2173',
 CDS_LIB='pure_quanta',
 CDS_PART_NAME='Q_CAP_C0402-22UF,4V,20%,X6S,CH622KMEB02',
 VOLTAGE='4V',
 PART_NUMBER='CH622KMEB02',
 VALUE='22UF',
 PRIM_FILE='./archive_libs/logical/q_cap/chips/chips.prt';

PART_NAME
 C2174 'Q_CAP_C0402-22UF,4V,20%,X6S,CH622KMEB02':;

SECTION_NUMBER 1
 '@T6G_MB_LIB.T6G(SCH_1):PAGE68_I20@PURE_QUANTA.Q_CAP(CHIPS)':
 C_PATH='@t6g_mb_lib.t6g(sch_1):page68_i20@pure_quanta.q_cap(chips)',
 P_PATH='@t6g_mb_lib.t6g(sch_1):page69_i20@pure_quanta.q_cap(chips)',
 PATH='I20',
 DRAWING='@T6G_MB_LIB.T6G(SCH_1):PAGE68',
 TOLERANCE='20%',
 MATERIAL='X6S',
 PHYS_PAGE='69',
 XY='(-8100,2875)',
 ROT='0',
 VER='1',
 PACK_TYPE='C0402',
 LOCATION='C2174',
 CDS_LIB='pure_quanta',
 CDS_PART_NAME='Q_CAP_C0402-22UF,4V,20%,X6S,CH622KMEB02',
 VOLTAGE='4V',
 PART_NUMBER='CH622KMEB02',
 VALUE='22UF',
 PRIM_FILE='./archive_libs/logical/q_cap/chips/chips.prt';

PART_NAME
 C2175 'Q_CAP_C0402-22UF,4V,20%,X6S,CH622KMEB02':;

SECTION_NUMBER 1
 '@T6G_MB_LIB.T6G(SCH_1):PAGE68_I16@PURE_QUANTA.Q_CAP(CHIPS)':
 C_PATH='@t6g_mb_lib.t6g(sch_1):page68_i16@pure_quanta.q_cap(chips)',
 P_PATH='@t6g_mb_lib.t6g(sch_1):page69_i16@pure_quanta.q_cap(chips)',
 PATH='I16',
 DRAWING='@T6G_MB_LIB.T6G(SCH_1):PAGE68',
 TOLERANCE='20%',
 MATERIAL='X6S',
 PHYS_PAGE='69',
 XY='(-8100,2075)',
 ROT='0',
 VER='1',
 PACK_TYPE='C0402',
 LOCATION='C2175',
 CDS_LIB='pure_quanta',
 CDS_PART_NAME='Q_CAP_C0402-22UF,4V,20%,X6S,CH622KMEB02',
 VOLTAGE='4V',
 PART_NUMBER='CH622KMEB02',
 VALUE='22UF',
 PRIM_FILE='./archive_libs/logical/q_cap/chips/chips.prt';

PART_NAME
 C2176 'Q_CAP_0402-100PF,50V,5%,EMPTY,CH11006JB18':
 ROOM='ADC_MAM_BOM2';

SECTION_NUMBER 1
 '@T6G_MB_LIB.T6G(SCH_1):PAGE369_I114@PURE_QUANTA.Q_CAP(CHIPS)':
 C_PATH='@t6g_mb_lib.t6g(sch_1):page369_i114@pure_quanta.q_cap(chips)',
 P_PATH='@t6g_mb_lib.t6g(sch_1):page257_i114@pure_quanta.q_cap(chips)',
 PATH='I114',
 DRAWING='@T6G_MB_LIB.T6G(SCH_1):PAGE369',
 TOLERANCE='5%',
 MATERIAL='EMPTY',
 PHYS_PAGE='257',
 XY='(-4925,5850)',
 ROT='0',
 VER='1',
 PACK_TYPE='0402',
 LOCATION='C2176',
 CDS_LIB='pure_quanta',
 CDS_PART_NAME='Q_CAP_0402-100PF,50V,5%,EMPTY,CH11006JB18',
 VOLTAGE='50V',
 ROOM='ADC_MAM_BOM2',
 PART_NUMBER='CH11006JB18',
 VALUE='100PF',
 PRIM_FILE='./archive_libs/logical/q_cap/chips/chips.prt';

PART_NAME
 C2177 'Q_CAP_C0402-22UF,4V,20%,X6S,CH622KMEB02':;

SECTION_NUMBER 1
 '@T6G_MB_LIB.T6G(SCH_1):PAGE68_I23@PURE_QUANTA.Q_CAP(CHIPS)':
 C_PATH='@t6g_mb_lib.t6g(sch_1):page68_i23@pure_quanta.q_cap(chips)',
 P_PATH='@t6g_mb_lib.t6g(sch_1):page69_i23@pure_quanta.q_cap(chips)',
 PATH='I23',
 DRAWING='@T6G_MB_LIB.T6G(SCH_1):PAGE68',
 TOLERANCE='20%',
 MATERIAL='X6S',
 PHYS_PAGE='69',
 XY='(-7650,3675)',
 ROT='0',
 VER='1',
 PACK_TYPE='C0402',
 LOCATION='C2177',
 CDS_LIB='pure_quanta',
 CDS_PART_NAME='Q_CAP_C0402-22UF,4V,20%,X6S,CH622KMEB02',
 VOLTAGE='4V',
 PART_NUMBER='CH622KMEB02',
 VALUE='22UF',
 PRIM_FILE='./archive_libs/logical/q_cap/chips/chips.prt';

PART_NAME
 C2178 'Q_CAP_C0402-22UF,4V,20%,X6S,CH622KMEB02':;

SECTION_NUMBER 1
 '@T6G_MB_LIB.T6G(SCH_1):PAGE68_I21@PURE_QUANTA.Q_CAP(CHIPS)':
 C_PATH='@t6g_mb_lib.t6g(sch_1):page68_i21@pure_quanta.q_cap(chips)',
 P_PATH='@t6g_mb_lib.t6g(sch_1):page69_i21@pure_quanta.q_cap(chips)',
 PATH='I21',
 DRAWING='@T6G_MB_LIB.T6G(SCH_1):PAGE68',
 TOLERANCE='20%',
 MATERIAL='X6S',
 PHYS_PAGE='69',
 XY='(-7650,2875)',
 ROT='0',
 VER='1',
 PACK_TYPE='C0402',
 LOCATION='C2178',
 CDS_LIB='pure_quanta',
 CDS_PART_NAME='Q_CAP_C0402-22UF,4V,20%,X6S,CH622KMEB02',
 VOLTAGE='4V',
 PART_NUMBER='CH622KMEB02',
 VALUE='22UF',
 PRIM_FILE='./archive_libs/logical/q_cap/chips/chips.prt';

PART_NAME
 C2179 'Q_CAP_C0402-100NF,50V,10%,X7R,CH4106K1B01':;

SECTION_NUMBER 1
 '@T6G_MB_LIB.T6G(SCH_1):PAGE372_I22@PURE_QUANTA.Q_CAP(CHIPS)':
 C_PATH='@t6g_mb_lib.t6g(sch_1):page372_i22@pure_quanta.q_cap(chips)',
 P_PATH='@t6g_mb_lib.t6g(sch_1):page268_i22@pure_quanta.q_cap(chips)',
 PATH='I22',
 DRAWING='@T6G_MB_LIB.T6G(SCH_1):PAGE372',
 SEC_TYPE='C0402',
 TOLERANCE='10%',
 MATERIAL='X7R',
 PHYS_PAGE='268',
 XY='(-5900,1000)',
 ROT='0',
 VER='1',
 PACK_TYPE='C0402',
 LOCATION='C2179',
 SEC='1',
 CDS_LIB='pure_quanta',
 CDS_PART_NAME='Q_CAP_C0402-100NF,50V,10%,X7R,CH4106K1B01',
 VOLTAGE='50V',
 PART_NUMBER='CH4106K1B01',
 VALUE='100NF',
 PRIM_FILE='./archive_libs/logical/q_cap/chips/chips.prt';

PART_NAME
 C2181 'Q_CAP_C0402-22UF,4V,20%,X6S,CH622KMEB02':;

SECTION_NUMBER 1
 '@T6G_MB_LIB.T6G(SCH_1):PAGE68_I25@PURE_QUANTA.Q_CAP(CHIPS)':
 C_PATH='@t6g_mb_lib.t6g(sch_1):page68_i25@pure_quanta.q_cap(chips)',
 P_PATH='@t6g_mb_lib.t6g(sch_1):page69_i25@pure_quanta.q_cap(chips)',
 PATH='I25',
 DRAWING='@T6G_MB_LIB.T6G(SCH_1):PAGE68',
 TOLERANCE='20%',
 MATERIAL='X6S',
 PHYS_PAGE='69',
 XY='(-7200,3675)',
 ROT='0',
 VER='1',
 PACK_TYPE='C0402',
 LOCATION='C2181',
 CDS_LIB='pure_quanta',
 CDS_PART_NAME='Q_CAP_C0402-22UF,4V,20%,X6S,CH622KMEB02',
 VOLTAGE='4V',
 PART_NUMBER='CH622KMEB02',
 VALUE='22UF',
 PRIM_FILE='./archive_libs/logical/q_cap/chips/chips.prt';

PART_NAME
 C2182 'Q_CAP_C0402-22UF,4V,20%,X6S,CH622KMEB02':;

SECTION_NUMBER 1
 '@T6G_MB_LIB.T6G(SCH_1):PAGE68_I24@PURE_QUANTA.Q_CAP(CHIPS)':
 C_PATH='@t6g_mb_lib.t6g(sch_1):page68_i24@pure_quanta.q_cap(chips)',
 P_PATH='@t6g_mb_lib.t6g(sch_1):page69_i24@pure_quanta.q_cap(chips)',
 PATH='I24',
 DRAWING='@T6G_MB_LIB.T6G(SCH_1):PAGE68',
 TOLERANCE='20%',
 MATERIAL='X6S',
 PHYS_PAGE='69',
 XY='(-7200,2875)',
 ROT='0',
 VER='1',
 PACK_TYPE='C0402',
 LOCATION='C2182',
 CDS_LIB='pure_quanta',
 CDS_PART_NAME='Q_CAP_C0402-22UF,4V,20%,X6S,CH622KMEB02',
 VOLTAGE='4V',
 PART_NUMBER='CH622KMEB02',
 VALUE='22UF',
 PRIM_FILE='./archive_libs/logical/q_cap/chips/chips.prt';

PART_NAME
 C2183 'Q_CAP_C0402-22UF,4V,20%,X6S,CH622KMEB02':;

SECTION_NUMBER 1
 '@T6G_MB_LIB.T6G(SCH_1):PAGE68_I19@PURE_QUANTA.Q_CAP(CHIPS)':
 C_PATH='@t6g_mb_lib.t6g(sch_1):page68_i19@pure_quanta.q_cap(chips)',
 P_PATH='@t6g_mb_lib.t6g(sch_1):page69_i19@pure_quanta.q_cap(chips)',
 PATH='I19',
 DRAWING='@T6G_MB_LIB.T6G(SCH_1):PAGE68',
 TOLERANCE='20%',
 MATERIAL='X6S',
 PHYS_PAGE='69',
 XY='(-7200,2075)',
 ROT='0',
 VER='1',
 PACK_TYPE='C0402',
 LOCATION='C2183',
 CDS_LIB='pure_quanta',
 CDS_PART_NAME='Q_CAP_C0402-22UF,4V,20%,X6S,CH622KMEB02',
 VOLTAGE='4V',
 PART_NUMBER='CH622KMEB02',
 VALUE='22UF',
 PRIM_FILE='./archive_libs/logical/q_cap/chips/chips.prt';

PART_NAME
 C2185 'Q_CAP_C0402-22UF,4V,20%,X6S,CH622KMEB02':;

SECTION_NUMBER 1
 '@T6G_MB_LIB.T6G(SCH_1):PAGE68_I28@PURE_QUANTA.Q_CAP(CHIPS)':
 C_PATH='@t6g_mb_lib.t6g(sch_1):page68_i28@pure_quanta.q_cap(chips)',
 P_PATH='@t6g_mb_lib.t6g(sch_1):page69_i28@pure_quanta.q_cap(chips)',
 PATH='I28',
 DRAWING='@T6G_MB_LIB.T6G(SCH_1):PAGE68',
 TOLERANCE='20%',
 MATERIAL='X6S',
 PHYS_PAGE='69',
 XY='(-6750,3675)',
 ROT='0',
 VER='1',
 PACK_TYPE='C0402',
 LOCATION='C2185',
 CDS_LIB='pure_quanta',
 CDS_PART_NAME='Q_CAP_C0402-22UF,4V,20%,X6S,CH622KMEB02',
 VOLTAGE='4V',
 PART_NUMBER='CH622KMEB02',
 VALUE='22UF',
 PRIM_FILE='./archive_libs/logical/q_cap/chips/chips.prt';

PART_NAME
 C2186 'Q_CAP_C0402-22UF,4V,20%,X6S,CH622KMEB02':;

SECTION_NUMBER 1
 '@T6G_MB_LIB.T6G(SCH_1):PAGE68_I26@PURE_QUANTA.Q_CAP(CHIPS)':
 C_PATH='@t6g_mb_lib.t6g(sch_1):page68_i26@pure_quanta.q_cap(chips)',
 P_PATH='@t6g_mb_lib.t6g(sch_1):page69_i26@pure_quanta.q_cap(chips)',
 PATH='I26',
 DRAWING='@T6G_MB_LIB.T6G(SCH_1):PAGE68',
 TOLERANCE='20%',
 MATERIAL='X6S',
 PHYS_PAGE='69',
 XY='(-6750,2875)',
 ROT='0',
 VER='1',
 PACK_TYPE='C0402',
 LOCATION='C2186',
 CDS_LIB='pure_quanta',
 CDS_PART_NAME='Q_CAP_C0402-22UF,4V,20%,X6S,CH622KMEB02',
 VOLTAGE='4V',
 PART_NUMBER='CH622KMEB02',
 VALUE='22UF',
 PRIM_FILE='./archive_libs/logical/q_cap/chips/chips.prt';

PART_NAME
 C2189 'Q_CAP_C0402-22UF,4V,20%,X6S,CH622KMEB02':;

SECTION_NUMBER 1
 '@T6G_MB_LIB.T6G(SCH_1):PAGE68_I29@PURE_QUANTA.Q_CAP(CHIPS)':
 C_PATH='@t6g_mb_lib.t6g(sch_1):page68_i29@pure_quanta.q_cap(chips)',
 P_PATH='@t6g_mb_lib.t6g(sch_1):page69_i29@pure_quanta.q_cap(chips)',
 PATH='I29',
 DRAWING='@T6G_MB_LIB.T6G(SCH_1):PAGE68',
 TOLERANCE='20%',
 MATERIAL='X6S',
 PHYS_PAGE='69',
 XY='(-6300,3675)',
 ROT='0',
 VER='1',
 PACK_TYPE='C0402',
 LOCATION='C2189',
 CDS_LIB='pure_quanta',
 CDS_PART_NAME='Q_CAP_C0402-22UF,4V,20%,X6S,CH622KMEB02',
 VOLTAGE='4V',
 PART_NUMBER='CH622KMEB02',
 VALUE='22UF',
 PRIM_FILE='./archive_libs/logical/q_cap/chips/chips.prt';

PART_NAME
 C2190 'Q_CAP_C0402-22UF,4V,20%,X6S,CH622KMEB02':;

SECTION_NUMBER 1
 '@T6G_MB_LIB.T6G(SCH_1):PAGE68_I27@PURE_QUANTA.Q_CAP(CHIPS)':
 C_PATH='@t6g_mb_lib.t6g(sch_1):page68_i27@pure_quanta.q_cap(chips)',
 P_PATH='@t6g_mb_lib.t6g(sch_1):page69_i27@pure_quanta.q_cap(chips)',
 PATH='I27',
 DRAWING='@T6G_MB_LIB.T6G(SCH_1):PAGE68',
 TOLERANCE='20%',
 MATERIAL='X6S',
 PHYS_PAGE='69',
 XY='(-6300,2875)',
 ROT='0',
 VER='1',
 PACK_TYPE='C0402',
 LOCATION='C2190',
 CDS_LIB='pure_quanta',
 CDS_PART_NAME='Q_CAP_C0402-22UF,4V,20%,X6S,CH622KMEB02',
 VOLTAGE='4V',
 PART_NUMBER='CH622KMEB02',
 VALUE='22UF',
 PRIM_FILE='./archive_libs/logical/q_cap/chips/chips.prt';

PART_NAME
 C2192 'Q_CAP_C0402-22UF,4V,20%,X6S,CH622KMEB02':;

SECTION_NUMBER 1
 '@T6G_MB_LIB.T6G(SCH_1):PAGE68_I33@PURE_QUANTA.Q_CAP(CHIPS)':
 C_PATH='@t6g_mb_lib.t6g(sch_1):page68_i33@pure_quanta.q_cap(chips)',
 P_PATH='@t6g_mb_lib.t6g(sch_1):page69_i33@pure_quanta.q_cap(chips)',
 PATH='I33',
 DRAWING='@T6G_MB_LIB.T6G(SCH_1):PAGE68',
 TOLERANCE='20%',
 MATERIAL='X6S',
 PHYS_PAGE='69',
 XY='(-5850,3675)',
 ROT='0',
 VER='1',
 PACK_TYPE='C0402',
 LOCATION='C2192',
 CDS_LIB='pure_quanta',
 CDS_PART_NAME='Q_CAP_C0402-22UF,4V,20%,X6S,CH622KMEB02',
 VOLTAGE='4V',
 PART_NUMBER='CH622KMEB02',
 VALUE='22UF',
 PRIM_FILE='./archive_libs/logical/q_cap/chips/chips.prt';

PART_NAME
 C2193 'Q_CAP_C0402-22UF,4V,20%,X6S,CH622KMEB02':;

SECTION_NUMBER 1
 '@T6G_MB_LIB.T6G(SCH_1):PAGE68_I31@PURE_QUANTA.Q_CAP(CHIPS)':
 C_PATH='@t6g_mb_lib.t6g(sch_1):page68_i31@pure_quanta.q_cap(chips)',
 P_PATH='@t6g_mb_lib.t6g(sch_1):page69_i31@pure_quanta.q_cap(chips)',
 PATH='I31',
 DRAWING='@T6G_MB_LIB.T6G(SCH_1):PAGE68',
 TOLERANCE='20%',
 MATERIAL='X6S',
 PHYS_PAGE='69',
 XY='(-5850,2875)',
 ROT='0',
 VER='1',
 PACK_TYPE='C0402',
 LOCATION='C2193',
 CDS_LIB='pure_quanta',
 CDS_PART_NAME='Q_CAP_C0402-22UF,4V,20%,X6S,CH622KMEB02',
 VOLTAGE='4V',
 PART_NUMBER='CH622KMEB02',
 VALUE='22UF',
 PRIM_FILE='./archive_libs/logical/q_cap/chips/chips.prt';

PART_NAME
 C2194 'Q_CAP_0402-0.1UF,25V,10%,X7R,CH4104K1B00':
 ROOM='ADC_TI_BOM1';

SECTION_NUMBER 1
 '@T6G_MB_LIB.T6G(SCH_1):PAGE369_I76@PURE_QUANTA.Q_CAP(CHIPS)':
 C_PATH='@t6g_mb_lib.t6g(sch_1):page369_i76@pure_quanta.q_cap(chips)',
 P_PATH='@t6g_mb_lib.t6g(sch_1):page257_i76@pure_quanta.q_cap(chips)',
 PATH='I76',
 DRAWING='@T6G_MB_LIB.T6G(SCH_1):PAGE369',
 TOLERANCE='10%',
 MATERIAL='X7R',
 PHYS_PAGE='257',
 XY='(-5000,3350)',
 ROT='2',
 VER='1',
 PACK_TYPE='0402',
 LOCATION='C2194',
 CDS_LIB='pure_quanta',
 CDS_PART_NAME='Q_CAP_0402-0.1UF,25V,10%,X7R,CH4104K1B00',
 VOLTAGE='25V',
 ROOM='ADC_TI_BOM1',
 PART_NUMBER='CH4104K1B00',
 VALUE='0.1UF',
 PRIM_FILE='./archive_libs/logical/q_cap/chips/chips.prt';

PART_NAME
 C2195 'Q_CAP_C0402-22UF,4V,20%,X6S,CH622KMEB02':;

SECTION_NUMBER 1
 '@T6G_MB_LIB.T6G(SCH_1):PAGE68_I34@PURE_QUANTA.Q_CAP(CHIPS)':
 C_PATH='@t6g_mb_lib.t6g(sch_1):page68_i34@pure_quanta.q_cap(chips)',
 P_PATH='@t6g_mb_lib.t6g(sch_1):page69_i34@pure_quanta.q_cap(chips)',
 PATH='I34',
 DRAWING='@T6G_MB_LIB.T6G(SCH_1):PAGE68',
 TOLERANCE='20%',
 MATERIAL='X6S',
 PHYS_PAGE='69',
 XY='(-5400,3675)',
 ROT='0',
 VER='1',
 PACK_TYPE='C0402',
 LOCATION='C2195',
 CDS_LIB='pure_quanta',
 CDS_PART_NAME='Q_CAP_C0402-22UF,4V,20%,X6S,CH622KMEB02',
 VOLTAGE='4V',
 PART_NUMBER='CH622KMEB02',
 VALUE='22UF',
 PRIM_FILE='./archive_libs/logical/q_cap/chips/chips.prt';

PART_NAME
 C2196 'Q_CAP_C0402-22UF,4V,20%,X6S,CH622KMEB02':;

SECTION_NUMBER 1
 '@T6G_MB_LIB.T6G(SCH_1):PAGE68_I32@PURE_QUANTA.Q_CAP(CHIPS)':
 C_PATH='@t6g_mb_lib.t6g(sch_1):page68_i32@pure_quanta.q_cap(chips)',
 P_PATH='@t6g_mb_lib.t6g(sch_1):page69_i32@pure_quanta.q_cap(chips)',
 PATH='I32',
 DRAWING='@T6G_MB_LIB.T6G(SCH_1):PAGE68',
 TOLERANCE='20%',
 MATERIAL='X6S',
 PHYS_PAGE='69',
 XY='(-5400,2875)',
 ROT='0',
 VER='1',
 PACK_TYPE='C0402',
 LOCATION='C2196',
 CDS_LIB='pure_quanta',
 CDS_PART_NAME='Q_CAP_C0402-22UF,4V,20%,X6S,CH622KMEB02',
 VOLTAGE='4V',
 PART_NUMBER='CH622KMEB02',
 VALUE='22UF',
 PRIM_FILE='./archive_libs/logical/q_cap/chips/chips.prt';

PART_NAME
 C2198 'Q_CAP_C0402-22UF,4V,20%,X6S,CH622KMEB02':;

SECTION_NUMBER 1
 '@T6G_MB_LIB.T6G(SCH_1):PAGE68_I40@PURE_QUANTA.Q_CAP(CHIPS)':
 C_PATH='@t6g_mb_lib.t6g(sch_1):page68_i40@pure_quanta.q_cap(chips)',
 P_PATH='@t6g_mb_lib.t6g(sch_1):page69_i40@pure_quanta.q_cap(chips)',
 PATH='I40',
 DRAWING='@T6G_MB_LIB.T6G(SCH_1):PAGE68',
 TOLERANCE='20%',
 MATERIAL='X6S',
 PHYS_PAGE='69',
 XY='(-5000,3675)',
 ROT='0',
 VER='1',
 PACK_TYPE='C0402',
 LOCATION='C2198',
 CDS_LIB='pure_quanta',
 CDS_PART_NAME='Q_CAP_C0402-22UF,4V,20%,X6S,CH622KMEB02',
 VOLTAGE='4V',
 PART_NUMBER='CH622KMEB02',
 VALUE='22UF',
 PRIM_FILE='./archive_libs/logical/q_cap/chips/chips.prt';

PART_NAME
 C2199 'Q_CAP_C0402-22UF,4V,20%,X6S,CH622KMEB02':;

SECTION_NUMBER 1
 '@T6G_MB_LIB.T6G(SCH_1):PAGE68_I36@PURE_QUANTA.Q_CAP(CHIPS)':
 C_PATH='@t6g_mb_lib.t6g(sch_1):page68_i36@pure_quanta.q_cap(chips)',
 P_PATH='@t6g_mb_lib.t6g(sch_1):page69_i36@pure_quanta.q_cap(chips)',
 PATH='I36',
 DRAWING='@T6G_MB_LIB.T6G(SCH_1):PAGE68',
 TOLERANCE='20%',
 MATERIAL='X6S',
 PHYS_PAGE='69',
 XY='(-5000,2875)',
 ROT='0',
 VER='1',
 PACK_TYPE='C0402',
 LOCATION='C2199',
 CDS_LIB='pure_quanta',
 CDS_PART_NAME='Q_CAP_C0402-22UF,4V,20%,X6S,CH622KMEB02',
 VOLTAGE='4V',
 PART_NUMBER='CH622KMEB02',
 VALUE='22UF',
 PRIM_FILE='./archive_libs/logical/q_cap/chips/chips.prt';

PART_NAME
 C2201 'Q_CAP_C0402-22UF,4V,20%,X6S,CH622KMEB02':;

SECTION_NUMBER 1
 '@T6G_MB_LIB.T6G(SCH_1):PAGE68_I63@PURE_QUANTA.Q_CAP(CHIPS)':
 C_PATH='@t6g_mb_lib.t6g(sch_1):page68_i63@pure_quanta.q_cap(chips)',
 P_PATH='@t6g_mb_lib.t6g(sch_1):page69_i63@pure_quanta.q_cap(chips)',
 PATH='I63',
 DRAWING='@T6G_MB_LIB.T6G(SCH_1):PAGE68',
 TOLERANCE='20%',
 MATERIAL='X6S',
 PHYS_PAGE='69',
 XY='(-4425,5250)',
 ROT='0',
 VER='1',
 PACK_TYPE='C0402',
 LOCATION='C2201',
 CDS_LIB='pure_quanta',
 CDS_PART_NAME='Q_CAP_C0402-22UF,4V,20%,X6S,CH622KMEB02',
 VOLTAGE='4V',
 PART_NUMBER='CH622KMEB02',
 VALUE='22UF',
 PRIM_FILE='./archive_libs/logical/q_cap/chips/chips.prt';

PART_NAME
 C2202 'Q_CAP_C0402-22UF,4V,20%,X6S,CH622KMEB02':;

SECTION_NUMBER 1
 '@T6G_MB_LIB.T6G(SCH_1):PAGE68_I60@PURE_QUANTA.Q_CAP(CHIPS)':
 C_PATH='@t6g_mb_lib.t6g(sch_1):page68_i60@pure_quanta.q_cap(chips)',
 P_PATH='@t6g_mb_lib.t6g(sch_1):page69_i60@pure_quanta.q_cap(chips)',
 PATH='I60',
 DRAWING='@T6G_MB_LIB.T6G(SCH_1):PAGE68',
 TOLERANCE='20%',
 MATERIAL='X6S',
 PHYS_PAGE='69',
 XY='(-4425,4475)',
 ROT='0',
 VER='1',
 PACK_TYPE='C0402',
 LOCATION='C2202',
 CDS_LIB='pure_quanta',
 CDS_PART_NAME='Q_CAP_C0402-22UF,4V,20%,X6S,CH622KMEB02',
 VOLTAGE='4V',
 PART_NUMBER='CH622KMEB02',
 VALUE='22UF',
 PRIM_FILE='./archive_libs/logical/q_cap/chips/chips.prt';

PART_NAME
 C2203 'Q_CAP_C0402-22UF,4V,20%,X6S,CH622KMEB02':;

SECTION_NUMBER 1
 '@T6G_MB_LIB.T6G(SCH_1):PAGE68_I43@PURE_QUANTA.Q_CAP(CHIPS)':
 C_PATH='@t6g_mb_lib.t6g(sch_1):page68_i43@pure_quanta.q_cap(chips)',
 P_PATH='@t6g_mb_lib.t6g(sch_1):page69_i43@pure_quanta.q_cap(chips)',
 PATH='I43',
 DRAWING='@T6G_MB_LIB.T6G(SCH_1):PAGE68',
 TOLERANCE='20%',
 MATERIAL='X6S',
 PHYS_PAGE='69',
 XY='(-4425,3675)',
 ROT='0',
 VER='1',
 PACK_TYPE='C0402',
 LOCATION='C2203',
 CDS_LIB='pure_quanta',
 CDS_PART_NAME='Q_CAP_C0402-22UF,4V,20%,X6S,CH622KMEB02',
 VOLTAGE='4V',
 PART_NUMBER='CH622KMEB02',
 VALUE='22UF',
 PRIM_FILE='./archive_libs/logical/q_cap/chips/chips.prt';

PART_NAME
 C2204 'Q_CAP_C0402-22UF,4V,20%,X6S,CH622KMEB02':;

SECTION_NUMBER 1
 '@T6G_MB_LIB.T6G(SCH_1):PAGE68_I38@PURE_QUANTA.Q_CAP(CHIPS)':
 C_PATH='@t6g_mb_lib.t6g(sch_1):page68_i38@pure_quanta.q_cap(chips)',
 P_PATH='@t6g_mb_lib.t6g(sch_1):page69_i38@pure_quanta.q_cap(chips)',
 PATH='I38',
 DRAWING='@T6G_MB_LIB.T6G(SCH_1):PAGE68',
 TOLERANCE='20%',
 MATERIAL='X6S',
 PHYS_PAGE='69',
 XY='(-4425,2875)',
 ROT='0',
 VER='1',
 PACK_TYPE='C0402',
 LOCATION='C2204',
 CDS_LIB='pure_quanta',
 CDS_PART_NAME='Q_CAP_C0402-22UF,4V,20%,X6S,CH622KMEB02',
 VOLTAGE='4V',
 PART_NUMBER='CH622KMEB02',
 VALUE='22UF',
 PRIM_FILE='./archive_libs/logical/q_cap/chips/chips.prt';

PART_NAME
 C2205 'Q_CAP_C0402-22UF,4V,20%,X6S,CH622KMEB02':;

SECTION_NUMBER 1
 '@T6G_MB_LIB.T6G(SCH_1):PAGE68_I30@PURE_QUANTA.Q_CAP(CHIPS)':
 C_PATH='@t6g_mb_lib.t6g(sch_1):page68_i30@pure_quanta.q_cap(chips)',
 P_PATH='@t6g_mb_lib.t6g(sch_1):page69_i30@pure_quanta.q_cap(chips)',
 PATH='I30',
 DRAWING='@T6G_MB_LIB.T6G(SCH_1):PAGE68',
 TOLERANCE='20%',
 MATERIAL='X6S',
 PHYS_PAGE='69',
 XY='(-4425,2075)',
 ROT='0',
 VER='1',
 PACK_TYPE='C0402',
 LOCATION='C2205',
 CDS_LIB='pure_quanta',
 CDS_PART_NAME='Q_CAP_C0402-22UF,4V,20%,X6S,CH622KMEB02',
 VOLTAGE='4V',
 PART_NUMBER='CH622KMEB02',
 VALUE='22UF',
 PRIM_FILE='./archive_libs/logical/q_cap/chips/chips.prt';

PART_NAME
 C2207 'Q_CAP_C0402-22UF,4V,20%,X6S,CH622KMEB02':;

SECTION_NUMBER 1
 '@T6G_MB_LIB.T6G(SCH_1):PAGE68_I93@PURE_QUANTA.Q_CAP(CHIPS)':
 C_PATH='@t6g_mb_lib.t6g(sch_1):page68_i93@pure_quanta.q_cap(chips)',
 P_PATH='@t6g_mb_lib.t6g(sch_1):page69_i93@pure_quanta.q_cap(chips)',
 PATH='I93',
 DRAWING='@T6G_MB_LIB.T6G(SCH_1):PAGE68',
 TOLERANCE='20%',
 MATERIAL='X6S',
 PHYS_PAGE='69',
 XY='(-3975,5250)',
 ROT='0',
 VER='1',
 PACK_TYPE='C0402',
 LOCATION='C2207',
 CDS_LIB='pure_quanta',
 CDS_PART_NAME='Q_CAP_C0402-22UF,4V,20%,X6S,CH622KMEB02',
 VOLTAGE='4V',
 PART_NUMBER='CH622KMEB02',
 VALUE='22UF',
 PRIM_FILE='./archive_libs/logical/q_cap/chips/chips.prt';

PART_NAME
 C2208 'Q_CAP_C0402-22UF,4V,20%,X6S,CH622KMEB02':;

SECTION_NUMBER 1
 '@T6G_MB_LIB.T6G(SCH_1):PAGE68_I91@PURE_QUANTA.Q_CAP(CHIPS)':
 C_PATH='@t6g_mb_lib.t6g(sch_1):page68_i91@pure_quanta.q_cap(chips)',
 P_PATH='@t6g_mb_lib.t6g(sch_1):page69_i91@pure_quanta.q_cap(chips)',
 PATH='I91',
 DRAWING='@T6G_MB_LIB.T6G(SCH_1):PAGE68',
 TOLERANCE='20%',
 MATERIAL='X6S',
 PHYS_PAGE='69',
 XY='(-3975,4475)',
 ROT='0',
 VER='1',
 PACK_TYPE='C0402',
 LOCATION='C2208',
 CDS_LIB='pure_quanta',
 CDS_PART_NAME='Q_CAP_C0402-22UF,4V,20%,X6S,CH622KMEB02',
 VOLTAGE='4V',
 PART_NUMBER='CH622KMEB02',
 VALUE='22UF',
 PRIM_FILE='./archive_libs/logical/q_cap/chips/chips.prt';

PART_NAME
 C2209 'Q_CAP_C0402-22UF,4V,20%,X6S,CH622KMEB02':;

SECTION_NUMBER 1
 '@T6G_MB_LIB.T6G(SCH_1):PAGE68_I72@PURE_QUANTA.Q_CAP(CHIPS)':
 C_PATH='@t6g_mb_lib.t6g(sch_1):page68_i72@pure_quanta.q_cap(chips)',
 P_PATH='@t6g_mb_lib.t6g(sch_1):page69_i72@pure_quanta.q_cap(chips)',
 PATH='I72',
 DRAWING='@T6G_MB_LIB.T6G(SCH_1):PAGE68',
 TOLERANCE='20%',
 MATERIAL='X6S',
 PHYS_PAGE='69',
 XY='(-3975,3675)',
 ROT='0',
 VER='1',
 PACK_TYPE='C0402',
 LOCATION='C2209',
 CDS_LIB='pure_quanta',
 CDS_PART_NAME='Q_CAP_C0402-22UF,4V,20%,X6S,CH622KMEB02',
 VOLTAGE='4V',
 PART_NUMBER='CH622KMEB02',
 VALUE='22UF',
 PRIM_FILE='./archive_libs/logical/q_cap/chips/chips.prt';

PART_NAME
 C2210 'Q_CAP_C0402-22UF,4V,20%,X6S,CH622KMEB02':;

SECTION_NUMBER 1
 '@T6G_MB_LIB.T6G(SCH_1):PAGE68_I70@PURE_QUANTA.Q_CAP(CHIPS)':
 C_PATH='@t6g_mb_lib.t6g(sch_1):page68_i70@pure_quanta.q_cap(chips)',
 P_PATH='@t6g_mb_lib.t6g(sch_1):page69_i70@pure_quanta.q_cap(chips)',
 PATH='I70',
 DRAWING='@T6G_MB_LIB.T6G(SCH_1):PAGE68',
 TOLERANCE='20%',
 MATERIAL='X6S',
 PHYS_PAGE='69',
 XY='(-3975,2875)',
 ROT='0',
 VER='1',
 PACK_TYPE='C0402',
 LOCATION='C2210',
 CDS_LIB='pure_quanta',
 CDS_PART_NAME='Q_CAP_C0402-22UF,4V,20%,X6S,CH622KMEB02',
 VOLTAGE='4V',
 PART_NUMBER='CH622KMEB02',
 VALUE='22UF',
 PRIM_FILE='./archive_libs/logical/q_cap/chips/chips.prt';

PART_NAME
 C2211 'Q_CAP_C0402-22UF,4V,20%,X6S,CH622KMEB02':;

SECTION_NUMBER 1
 '@T6G_MB_LIB.T6G(SCH_1):PAGE68_I65@PURE_QUANTA.Q_CAP(CHIPS)':
 C_PATH='@t6g_mb_lib.t6g(sch_1):page68_i65@pure_quanta.q_cap(chips)',
 P_PATH='@t6g_mb_lib.t6g(sch_1):page69_i65@pure_quanta.q_cap(chips)',
 PATH='I65',
 DRAWING='@T6G_MB_LIB.T6G(SCH_1):PAGE68',
 TOLERANCE='20%',
 MATERIAL='X6S',
 PHYS_PAGE='69',
 XY='(-3975,2075)',
 ROT='0',
 VER='1',
 PACK_TYPE='C0402',
 LOCATION='C2211',
 CDS_LIB='pure_quanta',
 CDS_PART_NAME='Q_CAP_C0402-22UF,4V,20%,X6S,CH622KMEB02',
 VOLTAGE='4V',
 PART_NUMBER='CH622KMEB02',
 VALUE='22UF',
 PRIM_FILE='./archive_libs/logical/q_cap/chips/chips.prt';

PART_NAME
 C2213 'Q_CAP_C0402-22UF,4V,20%,X6S,CH622KMEB02':;

SECTION_NUMBER 1
 '@T6G_MB_LIB.T6G(SCH_1):PAGE68_I94@PURE_QUANTA.Q_CAP(CHIPS)':
 C_PATH='@t6g_mb_lib.t6g(sch_1):page68_i94@pure_quanta.q_cap(chips)',
 P_PATH='@t6g_mb_lib.t6g(sch_1):page69_i94@pure_quanta.q_cap(chips)',
 PATH='I94',
 DRAWING='@T6G_MB_LIB.T6G(SCH_1):PAGE68',
 TOLERANCE='20%',
 MATERIAL='X6S',
 PHYS_PAGE='69',
 XY='(-3525,5250)',
 ROT='0',
 VER='1',
 PACK_TYPE='C0402',
 LOCATION='C2213',
 CDS_LIB='pure_quanta',
 CDS_PART_NAME='Q_CAP_C0402-22UF,4V,20%,X6S,CH622KMEB02',
 VOLTAGE='4V',
 PART_NUMBER='CH622KMEB02',
 VALUE='22UF',
 PRIM_FILE='./archive_libs/logical/q_cap/chips/chips.prt';

PART_NAME
 C2214 'Q_CAP_C0402-22UF,4V,20%,X6S,CH622KMEB02':;

SECTION_NUMBER 1
 '@T6G_MB_LIB.T6G(SCH_1):PAGE68_I92@PURE_QUANTA.Q_CAP(CHIPS)':
 C_PATH='@t6g_mb_lib.t6g(sch_1):page68_i92@pure_quanta.q_cap(chips)',
 P_PATH='@t6g_mb_lib.t6g(sch_1):page69_i92@pure_quanta.q_cap(chips)',
 PATH='I92',
 DRAWING='@T6G_MB_LIB.T6G(SCH_1):PAGE68',
 TOLERANCE='20%',
 MATERIAL='X6S',
 PHYS_PAGE='69',
 XY='(-3525,4475)',
 ROT='0',
 VER='1',
 PACK_TYPE='C0402',
 LOCATION='C2214',
 CDS_LIB='pure_quanta',
 CDS_PART_NAME='Q_CAP_C0402-22UF,4V,20%,X6S,CH622KMEB02',
 VOLTAGE='4V',
 PART_NUMBER='CH622KMEB02',
 VALUE='22UF',
 PRIM_FILE='./archive_libs/logical/q_cap/chips/chips.prt';

PART_NAME
 C2215 'Q_CAP_C0402-22UF,4V,20%,X6S,CH622KMEB02':;

SECTION_NUMBER 1
 '@T6G_MB_LIB.T6G(SCH_1):PAGE68_I73@PURE_QUANTA.Q_CAP(CHIPS)':
 C_PATH='@t6g_mb_lib.t6g(sch_1):page68_i73@pure_quanta.q_cap(chips)',
 P_PATH='@t6g_mb_lib.t6g(sch_1):page69_i73@pure_quanta.q_cap(chips)',
 PATH='I73',
 DRAWING='@T6G_MB_LIB.T6G(SCH_1):PAGE68',
 TOLERANCE='20%',
 MATERIAL='X6S',
 PHYS_PAGE='69',
 XY='(-3525,3675)',
 ROT='0',
 VER='1',
 PACK_TYPE='C0402',
 LOCATION='C2215',
 CDS_LIB='pure_quanta',
 CDS_PART_NAME='Q_CAP_C0402-22UF,4V,20%,X6S,CH622KMEB02',
 VOLTAGE='4V',
 PART_NUMBER='CH622KMEB02',
 VALUE='22UF',
 PRIM_FILE='./archive_libs/logical/q_cap/chips/chips.prt';

PART_NAME
 C2216 'Q_CAP_C0402-22UF,4V,20%,X6S,CH622KMEB02':;

SECTION_NUMBER 1
 '@T6G_MB_LIB.T6G(SCH_1):PAGE68_I71@PURE_QUANTA.Q_CAP(CHIPS)':
 C_PATH='@t6g_mb_lib.t6g(sch_1):page68_i71@pure_quanta.q_cap(chips)',
 P_PATH='@t6g_mb_lib.t6g(sch_1):page69_i71@pure_quanta.q_cap(chips)',
 PATH='I71',
 DRAWING='@T6G_MB_LIB.T6G(SCH_1):PAGE68',
 TOLERANCE='20%',
 MATERIAL='X6S',
 PHYS_PAGE='69',
 XY='(-3525,2875)',
 ROT='0',
 VER='1',
 PACK_TYPE='C0402',
 LOCATION='C2216',
 CDS_LIB='pure_quanta',
 CDS_PART_NAME='Q_CAP_C0402-22UF,4V,20%,X6S,CH622KMEB02',
 VOLTAGE='4V',
 PART_NUMBER='CH622KMEB02',
 VALUE='22UF',
 PRIM_FILE='./archive_libs/logical/q_cap/chips/chips.prt';

PART_NAME
 C2217 'Q_CAP_C0402-22UF,4V,20%,X6S,CH622KMEB02':;

SECTION_NUMBER 1
 '@T6G_MB_LIB.T6G(SCH_1):PAGE68_I66@PURE_QUANTA.Q_CAP(CHIPS)':
 C_PATH='@t6g_mb_lib.t6g(sch_1):page68_i66@pure_quanta.q_cap(chips)',
 P_PATH='@t6g_mb_lib.t6g(sch_1):page69_i66@pure_quanta.q_cap(chips)',
 PATH='I66',
 DRAWING='@T6G_MB_LIB.T6G(SCH_1):PAGE68',
 TOLERANCE='20%',
 MATERIAL='X6S',
 PHYS_PAGE='69',
 XY='(-3525,2075)',
 ROT='0',
 VER='1',
 PACK_TYPE='C0402',
 LOCATION='C2217',
 CDS_LIB='pure_quanta',
 CDS_PART_NAME='Q_CAP_C0402-22UF,4V,20%,X6S,CH622KMEB02',
 VOLTAGE='4V',
 PART_NUMBER='CH622KMEB02',
 VALUE='22UF',
 PRIM_FILE='./archive_libs/logical/q_cap/chips/chips.prt';

PART_NAME
 C2219 'Q_CAP_C0402-22UF,4V,20%,X6S,CH622KMEB02':;

SECTION_NUMBER 1
 '@T6G_MB_LIB.T6G(SCH_1):PAGE68_I98@PURE_QUANTA.Q_CAP(CHIPS)':
 C_PATH='@t6g_mb_lib.t6g(sch_1):page68_i98@pure_quanta.q_cap(chips)',
 P_PATH='@t6g_mb_lib.t6g(sch_1):page69_i98@pure_quanta.q_cap(chips)',
 PATH='I98',
 DRAWING='@T6G_MB_LIB.T6G(SCH_1):PAGE68',
 TOLERANCE='20%',
 MATERIAL='X6S',
 PHYS_PAGE='69',
 XY='(-3075,5250)',
 ROT='0',
 VER='1',
 PACK_TYPE='C0402',
 LOCATION='C2219',
 CDS_LIB='pure_quanta',
 CDS_PART_NAME='Q_CAP_C0402-22UF,4V,20%,X6S,CH622KMEB02',
 VOLTAGE='4V',
 PART_NUMBER='CH622KMEB02',
 VALUE='22UF',
 PRIM_FILE='./archive_libs/logical/q_cap/chips/chips.prt';

PART_NAME
 C2220 'Q_CAP_C0402-22UF,4V,20%,X6S,CH622KMEB02':;

SECTION_NUMBER 1
 '@T6G_MB_LIB.T6G(SCH_1):PAGE68_I95@PURE_QUANTA.Q_CAP(CHIPS)':
 C_PATH='@t6g_mb_lib.t6g(sch_1):page68_i95@pure_quanta.q_cap(chips)',
 P_PATH='@t6g_mb_lib.t6g(sch_1):page69_i95@pure_quanta.q_cap(chips)',
 PATH='I95',
 DRAWING='@T6G_MB_LIB.T6G(SCH_1):PAGE68',
 TOLERANCE='20%',
 MATERIAL='X6S',
 PHYS_PAGE='69',
 XY='(-3075,4475)',
 ROT='0',
 VER='1',
 PACK_TYPE='C0402',
 LOCATION='C2220',
 CDS_LIB='pure_quanta',
 CDS_PART_NAME='Q_CAP_C0402-22UF,4V,20%,X6S,CH622KMEB02',
 VOLTAGE='4V',
 PART_NUMBER='CH622KMEB02',
 VALUE='22UF',
 PRIM_FILE='./archive_libs/logical/q_cap/chips/chips.prt';

PART_NAME
 C2221 'Q_CAP_C0402-22UF,4V,20%,X6S,CH622KMEB02':;

SECTION_NUMBER 1
 '@T6G_MB_LIB.T6G(SCH_1):PAGE68_I77@PURE_QUANTA.Q_CAP(CHIPS)':
 C_PATH='@t6g_mb_lib.t6g(sch_1):page68_i77@pure_quanta.q_cap(chips)',
 P_PATH='@t6g_mb_lib.t6g(sch_1):page69_i77@pure_quanta.q_cap(chips)',
 PATH='I77',
 DRAWING='@T6G_MB_LIB.T6G(SCH_1):PAGE68',
 TOLERANCE='20%',
 MATERIAL='X6S',
 PHYS_PAGE='69',
 XY='(-3075,3675)',
 ROT='0',
 VER='1',
 PACK_TYPE='C0402',
 LOCATION='C2221',
 CDS_LIB='pure_quanta',
 CDS_PART_NAME='Q_CAP_C0402-22UF,4V,20%,X6S,CH622KMEB02',
 VOLTAGE='4V',
 PART_NUMBER='CH622KMEB02',
 VALUE='22UF',
 PRIM_FILE='./archive_libs/logical/q_cap/chips/chips.prt';

PART_NAME
 C2222 'Q_CAP_C0402-22UF,4V,20%,X6S,CH622KMEB02':;

SECTION_NUMBER 1
 '@T6G_MB_LIB.T6G(SCH_1):PAGE68_I74@PURE_QUANTA.Q_CAP(CHIPS)':
 C_PATH='@t6g_mb_lib.t6g(sch_1):page68_i74@pure_quanta.q_cap(chips)',
 P_PATH='@t6g_mb_lib.t6g(sch_1):page69_i74@pure_quanta.q_cap(chips)',
 PATH='I74',
 DRAWING='@T6G_MB_LIB.T6G(SCH_1):PAGE68',
 TOLERANCE='20%',
 MATERIAL='X6S',
 PHYS_PAGE='69',
 XY='(-3075,2875)',
 ROT='0',
 VER='1',
 PACK_TYPE='C0402',
 LOCATION='C2222',
 CDS_LIB='pure_quanta',
 CDS_PART_NAME='Q_CAP_C0402-22UF,4V,20%,X6S,CH622KMEB02',
 VOLTAGE='4V',
 PART_NUMBER='CH622KMEB02',
 VALUE='22UF',
 PRIM_FILE='./archive_libs/logical/q_cap/chips/chips.prt';

PART_NAME
 C2223 'Q_CAP_C0402-22UF,4V,20%,X6S,CH622KMEB02':;

SECTION_NUMBER 1
 '@T6G_MB_LIB.T6G(SCH_1):PAGE68_I67@PURE_QUANTA.Q_CAP(CHIPS)':
 C_PATH='@t6g_mb_lib.t6g(sch_1):page68_i67@pure_quanta.q_cap(chips)',
 P_PATH='@t6g_mb_lib.t6g(sch_1):page69_i67@pure_quanta.q_cap(chips)',
 PATH='I67',
 DRAWING='@T6G_MB_LIB.T6G(SCH_1):PAGE68',
 TOLERANCE='20%',
 MATERIAL='X6S',
 PHYS_PAGE='69',
 XY='(-3075,2075)',
 ROT='0',
 VER='1',
 PACK_TYPE='C0402',
 LOCATION='C2223',
 CDS_LIB='pure_quanta',
 CDS_PART_NAME='Q_CAP_C0402-22UF,4V,20%,X6S,CH622KMEB02',
 VOLTAGE='4V',
 PART_NUMBER='CH622KMEB02',
 VALUE='22UF',
 PRIM_FILE='./archive_libs/logical/q_cap/chips/chips.prt';

PART_NAME
 C2225 'Q_CAP_C0402-22UF,4V,20%,X6S,CH622KMEB02':;

SECTION_NUMBER 1
 '@T6G_MB_LIB.T6G(SCH_1):PAGE68_I99@PURE_QUANTA.Q_CAP(CHIPS)':
 C_PATH='@t6g_mb_lib.t6g(sch_1):page68_i99@pure_quanta.q_cap(chips)',
 P_PATH='@t6g_mb_lib.t6g(sch_1):page69_i99@pure_quanta.q_cap(chips)',
 PATH='I99',
 DRAWING='@T6G_MB_LIB.T6G(SCH_1):PAGE68',
 TOLERANCE='20%',
 MATERIAL='X6S',
 PHYS_PAGE='69',
 XY='(-2625,5250)',
 ROT='0',
 VER='1',
 PACK_TYPE='C0402',
 LOCATION='C2225',
 CDS_LIB='pure_quanta',
 CDS_PART_NAME='Q_CAP_C0402-22UF,4V,20%,X6S,CH622KMEB02',
 VOLTAGE='4V',
 PART_NUMBER='CH622KMEB02',
 VALUE='22UF',
 PRIM_FILE='./archive_libs/logical/q_cap/chips/chips.prt';

PART_NAME
 C2226 'Q_CAP_C0402-22UF,4V,20%,X6S,CH622KMEB02':;

SECTION_NUMBER 1
 '@T6G_MB_LIB.T6G(SCH_1):PAGE68_I96@PURE_QUANTA.Q_CAP(CHIPS)':
 C_PATH='@t6g_mb_lib.t6g(sch_1):page68_i96@pure_quanta.q_cap(chips)',
 P_PATH='@t6g_mb_lib.t6g(sch_1):page69_i96@pure_quanta.q_cap(chips)',
 PATH='I96',
 DRAWING='@T6G_MB_LIB.T6G(SCH_1):PAGE68',
 TOLERANCE='20%',
 MATERIAL='X6S',
 PHYS_PAGE='69',
 XY='(-2625,4475)',
 ROT='0',
 VER='1',
 PACK_TYPE='C0402',
 LOCATION='C2226',
 CDS_LIB='pure_quanta',
 CDS_PART_NAME='Q_CAP_C0402-22UF,4V,20%,X6S,CH622KMEB02',
 VOLTAGE='4V',
 PART_NUMBER='CH622KMEB02',
 VALUE='22UF',
 PRIM_FILE='./archive_libs/logical/q_cap/chips/chips.prt';

PART_NAME
 C2227 'Q_CAP_C0402-22UF,4V,20%,X6S,CH622KMEB02':;

SECTION_NUMBER 1
 '@T6G_MB_LIB.T6G(SCH_1):PAGE68_I78@PURE_QUANTA.Q_CAP(CHIPS)':
 C_PATH='@t6g_mb_lib.t6g(sch_1):page68_i78@pure_quanta.q_cap(chips)',
 P_PATH='@t6g_mb_lib.t6g(sch_1):page69_i78@pure_quanta.q_cap(chips)',
 PATH='I78',
 DRAWING='@T6G_MB_LIB.T6G(SCH_1):PAGE68',
 TOLERANCE='20%',
 MATERIAL='X6S',
 PHYS_PAGE='69',
 XY='(-2625,3675)',
 ROT='0',
 VER='1',
 PACK_TYPE='C0402',
 LOCATION='C2227',
 CDS_LIB='pure_quanta',
 CDS_PART_NAME='Q_CAP_C0402-22UF,4V,20%,X6S,CH622KMEB02',
 VOLTAGE='4V',
 PART_NUMBER='CH622KMEB02',
 VALUE='22UF',
 PRIM_FILE='./archive_libs/logical/q_cap/chips/chips.prt';

PART_NAME
 C2228 'Q_CAP_C0402-22UF,4V,20%,X6S,CH622KMEB02':;

SECTION_NUMBER 1
 '@T6G_MB_LIB.T6G(SCH_1):PAGE68_I75@PURE_QUANTA.Q_CAP(CHIPS)':
 C_PATH='@t6g_mb_lib.t6g(sch_1):page68_i75@pure_quanta.q_cap(chips)',
 P_PATH='@t6g_mb_lib.t6g(sch_1):page69_i75@pure_quanta.q_cap(chips)',
 PATH='I75',
 DRAWING='@T6G_MB_LIB.T6G(SCH_1):PAGE68',
 TOLERANCE='20%',
 MATERIAL='X6S',
 PHYS_PAGE='69',
 XY='(-2625,2875)',
 ROT='0',
 VER='1',
 PACK_TYPE='C0402',
 LOCATION='C2228',
 CDS_LIB='pure_quanta',
 CDS_PART_NAME='Q_CAP_C0402-22UF,4V,20%,X6S,CH622KMEB02',
 VOLTAGE='4V',
 PART_NUMBER='CH622KMEB02',
 VALUE='22UF',
 PRIM_FILE='./archive_libs/logical/q_cap/chips/chips.prt';

PART_NAME
 C2229 'Q_CAP_C0402-22UF,4V,20%,X6S,CH622KMEB02':;

SECTION_NUMBER 1
 '@T6G_MB_LIB.T6G(SCH_1):PAGE68_I69@PURE_QUANTA.Q_CAP(CHIPS)':
 C_PATH='@t6g_mb_lib.t6g(sch_1):page68_i69@pure_quanta.q_cap(chips)',
 P_PATH='@t6g_mb_lib.t6g(sch_1):page69_i69@pure_quanta.q_cap(chips)',
 PATH='I69',
 DRAWING='@T6G_MB_LIB.T6G(SCH_1):PAGE68',
 TOLERANCE='20%',
 MATERIAL='X6S',
 PHYS_PAGE='69',
 XY='(-2625,2075)',
 ROT='0',
 VER='1',
 PACK_TYPE='C0402',
 LOCATION='C2229',
 CDS_LIB='pure_quanta',
 CDS_PART_NAME='Q_CAP_C0402-22UF,4V,20%,X6S,CH622KMEB02',
 VOLTAGE='4V',
 PART_NUMBER='CH622KMEB02',
 VALUE='22UF',
 PRIM_FILE='./archive_libs/logical/q_cap/chips/chips.prt';

PART_NAME
 C2231 'Q_CAP_C0402-22UF,4V,20%,X6S,CH622KMEB02':;

SECTION_NUMBER 1
 '@T6G_MB_LIB.T6G(SCH_1):PAGE68_I100@PURE_QUANTA.Q_CAP(CHIPS)':
 C_PATH='@t6g_mb_lib.t6g(sch_1):page68_i100@pure_quanta.q_cap(chips)',
 P_PATH='@t6g_mb_lib.t6g(sch_1):page69_i100@pure_quanta.q_cap(chips)',
 PATH='I100',
 DRAWING='@T6G_MB_LIB.T6G(SCH_1):PAGE68',
 TOLERANCE='20%',
 MATERIAL='X6S',
 PHYS_PAGE='69',
 XY='(-2175,5250)',
 ROT='0',
 VER='1',
 PACK_TYPE='C0402',
 LOCATION='C2231',
 CDS_LIB='pure_quanta',
 CDS_PART_NAME='Q_CAP_C0402-22UF,4V,20%,X6S,CH622KMEB02',
 VOLTAGE='4V',
 PART_NUMBER='CH622KMEB02',
 VALUE='22UF',
 PRIM_FILE='./archive_libs/logical/q_cap/chips/chips.prt';

PART_NAME
 C2232 'Q_CAP_C0402-22UF,4V,20%,X6S,CH622KMEB02':;

SECTION_NUMBER 1
 '@T6G_MB_LIB.T6G(SCH_1):PAGE68_I97@PURE_QUANTA.Q_CAP(CHIPS)':
 C_PATH='@t6g_mb_lib.t6g(sch_1):page68_i97@pure_quanta.q_cap(chips)',
 P_PATH='@t6g_mb_lib.t6g(sch_1):page69_i97@pure_quanta.q_cap(chips)',
 PATH='I97',
 DRAWING='@T6G_MB_LIB.T6G(SCH_1):PAGE68',
 TOLERANCE='20%',
 MATERIAL='X6S',
 PHYS_PAGE='69',
 XY='(-2175,4475)',
 ROT='0',
 VER='1',
 PACK_TYPE='C0402',
 LOCATION='C2232',
 CDS_LIB='pure_quanta',
 CDS_PART_NAME='Q_CAP_C0402-22UF,4V,20%,X6S,CH622KMEB02',
 VOLTAGE='4V',
 PART_NUMBER='CH622KMEB02',
 VALUE='22UF',
 PRIM_FILE='./archive_libs/logical/q_cap/chips/chips.prt';

PART_NAME
 C2233 'Q_CAP_C0402-22UF,4V,20%,X6S,CH622KMEB02':;

SECTION_NUMBER 1
 '@T6G_MB_LIB.T6G(SCH_1):PAGE68_I79@PURE_QUANTA.Q_CAP(CHIPS)':
 C_PATH='@t6g_mb_lib.t6g(sch_1):page68_i79@pure_quanta.q_cap(chips)',
 P_PATH='@t6g_mb_lib.t6g(sch_1):page69_i79@pure_quanta.q_cap(chips)',
 PATH='I79',
 DRAWING='@T6G_MB_LIB.T6G(SCH_1):PAGE68',
 TOLERANCE='20%',
 MATERIAL='X6S',
 PHYS_PAGE='69',
 XY='(-2175,3675)',
 ROT='0',
 VER='1',
 PACK_TYPE='C0402',
 LOCATION='C2233',
 CDS_LIB='pure_quanta',
 CDS_PART_NAME='Q_CAP_C0402-22UF,4V,20%,X6S,CH622KMEB02',
 VOLTAGE='4V',
 PART_NUMBER='CH622KMEB02',
 VALUE='22UF',
 PRIM_FILE='./archive_libs/logical/q_cap/chips/chips.prt';

PART_NAME
 C2234 'Q_CAP_C0402-22UF,4V,20%,X6S,CH622KMEB02':;

SECTION_NUMBER 1
 '@T6G_MB_LIB.T6G(SCH_1):PAGE68_I76@PURE_QUANTA.Q_CAP(CHIPS)':
 C_PATH='@t6g_mb_lib.t6g(sch_1):page68_i76@pure_quanta.q_cap(chips)',
 P_PATH='@t6g_mb_lib.t6g(sch_1):page69_i76@pure_quanta.q_cap(chips)',
 PATH='I76',
 DRAWING='@T6G_MB_LIB.T6G(SCH_1):PAGE68',
 TOLERANCE='20%',
 MATERIAL='X6S',
 PHYS_PAGE='69',
 XY='(-2175,2875)',
 ROT='0',
 VER='1',
 PACK_TYPE='C0402',
 LOCATION='C2234',
 CDS_LIB='pure_quanta',
 CDS_PART_NAME='Q_CAP_C0402-22UF,4V,20%,X6S,CH622KMEB02',
 VOLTAGE='4V',
 PART_NUMBER='CH622KMEB02',
 VALUE='22UF',
 PRIM_FILE='./archive_libs/logical/q_cap/chips/chips.prt';

PART_NAME
 C2237 'Q_CAP_C0402-22UF,4V,20%,X6S,CH622KMEB02':;

SECTION_NUMBER 1
 '@T6G_MB_LIB.T6G(SCH_1):PAGE68_I103@PURE_QUANTA.Q_CAP(CHIPS)':
 C_PATH='@t6g_mb_lib.t6g(sch_1):page68_i103@pure_quanta.q_cap(chips)',
 P_PATH='@t6g_mb_lib.t6g(sch_1):page69_i103@pure_quanta.q_cap(chips)',
 PATH='I103',
 DRAWING='@T6G_MB_LIB.T6G(SCH_1):PAGE68',
 TOLERANCE='20%',
 MATERIAL='X6S',
 PHYS_PAGE='69',
 XY='(-1725,5250)',
 ROT='0',
 VER='1',
 PACK_TYPE='C0402',
 LOCATION='C2237',
 CDS_LIB='pure_quanta',
 CDS_PART_NAME='Q_CAP_C0402-22UF,4V,20%,X6S,CH622KMEB02',
 VOLTAGE='4V',
 PART_NUMBER='CH622KMEB02',
 VALUE='22UF',
 PRIM_FILE='./archive_libs/logical/q_cap/chips/chips.prt';

PART_NAME
 C2238 'Q_CAP_C0402-22UF,4V,20%,X6S,CH622KMEB02':;

SECTION_NUMBER 1
 '@T6G_MB_LIB.T6G(SCH_1):PAGE68_I101@PURE_QUANTA.Q_CAP(CHIPS)':
 C_PATH='@t6g_mb_lib.t6g(sch_1):page68_i101@pure_quanta.q_cap(chips)',
 P_PATH='@t6g_mb_lib.t6g(sch_1):page69_i101@pure_quanta.q_cap(chips)',
 PATH='I101',
 DRAWING='@T6G_MB_LIB.T6G(SCH_1):PAGE68',
 TOLERANCE='20%',
 MATERIAL='X6S',
 PHYS_PAGE='69',
 XY='(-1725,4475)',
 ROT='0',
 VER='1',
 PACK_TYPE='C0402',
 LOCATION='C2238',
 CDS_LIB='pure_quanta',
 CDS_PART_NAME='Q_CAP_C0402-22UF,4V,20%,X6S,CH622KMEB02',
 VOLTAGE='4V',
 PART_NUMBER='CH622KMEB02',
 VALUE='22UF',
 PRIM_FILE='./archive_libs/logical/q_cap/chips/chips.prt';

PART_NAME
 C2239 'Q_CAP_C0402-22UF,4V,20%,X6S,CH622KMEB02':;

SECTION_NUMBER 1
 '@T6G_MB_LIB.T6G(SCH_1):PAGE68_I82@PURE_QUANTA.Q_CAP(CHIPS)':
 C_PATH='@t6g_mb_lib.t6g(sch_1):page68_i82@pure_quanta.q_cap(chips)',
 P_PATH='@t6g_mb_lib.t6g(sch_1):page69_i82@pure_quanta.q_cap(chips)',
 PATH='I82',
 DRAWING='@T6G_MB_LIB.T6G(SCH_1):PAGE68',
 TOLERANCE='20%',
 MATERIAL='X6S',
 PHYS_PAGE='69',
 XY='(-1725,3675)',
 ROT='0',
 VER='1',
 PACK_TYPE='C0402',
 LOCATION='C2239',
 CDS_LIB='pure_quanta',
 CDS_PART_NAME='Q_CAP_C0402-22UF,4V,20%,X6S,CH622KMEB02',
 VOLTAGE='4V',
 PART_NUMBER='CH622KMEB02',
 VALUE='22UF',
 PRIM_FILE='./archive_libs/logical/q_cap/chips/chips.prt';

PART_NAME
 C2240 'Q_CAP_C0402-22UF,4V,20%,X6S,CH622KMEB02':;

SECTION_NUMBER 1
 '@T6G_MB_LIB.T6G(SCH_1):PAGE68_I80@PURE_QUANTA.Q_CAP(CHIPS)':
 C_PATH='@t6g_mb_lib.t6g(sch_1):page68_i80@pure_quanta.q_cap(chips)',
 P_PATH='@t6g_mb_lib.t6g(sch_1):page69_i80@pure_quanta.q_cap(chips)',
 PATH='I80',
 DRAWING='@T6G_MB_LIB.T6G(SCH_1):PAGE68',
 TOLERANCE='20%',
 MATERIAL='X6S',
 PHYS_PAGE='69',
 XY='(-1725,2875)',
 ROT='0',
 VER='1',
 PACK_TYPE='C0402',
 LOCATION='C2240',
 CDS_LIB='pure_quanta',
 CDS_PART_NAME='Q_CAP_C0402-22UF,4V,20%,X6S,CH622KMEB02',
 VOLTAGE='4V',
 PART_NUMBER='CH622KMEB02',
 VALUE='22UF',
 PRIM_FILE='./archive_libs/logical/q_cap/chips/chips.prt';

PART_NAME
 C2243 'Q_CAP_C0402-22UF,4V,20%,X6S,CH622KMEB02':;

SECTION_NUMBER 1
 '@T6G_MB_LIB.T6G(SCH_1):PAGE68_I104@PURE_QUANTA.Q_CAP(CHIPS)':
 C_PATH='@t6g_mb_lib.t6g(sch_1):page68_i104@pure_quanta.q_cap(chips)',
 P_PATH='@t6g_mb_lib.t6g(sch_1):page69_i104@pure_quanta.q_cap(chips)',
 PATH='I104',
 DRAWING='@T6G_MB_LIB.T6G(SCH_1):PAGE68',
 TOLERANCE='20%',
 MATERIAL='X6S',
 PHYS_PAGE='69',
 XY='(-1275,5250)',
 ROT='0',
 VER='1',
 PACK_TYPE='C0402',
 LOCATION='C2243',
 CDS_LIB='pure_quanta',
 CDS_PART_NAME='Q_CAP_C0402-22UF,4V,20%,X6S,CH622KMEB02',
 VOLTAGE='4V',
 PART_NUMBER='CH622KMEB02',
 VALUE='22UF',
 PRIM_FILE='./archive_libs/logical/q_cap/chips/chips.prt';

PART_NAME
 C2244 'Q_CAP_C0402-22UF,4V,20%,X6S,CH622KMEB02':;

SECTION_NUMBER 1
 '@T6G_MB_LIB.T6G(SCH_1):PAGE68_I102@PURE_QUANTA.Q_CAP(CHIPS)':
 C_PATH='@t6g_mb_lib.t6g(sch_1):page68_i102@pure_quanta.q_cap(chips)',
 P_PATH='@t6g_mb_lib.t6g(sch_1):page69_i102@pure_quanta.q_cap(chips)',
 PATH='I102',
 DRAWING='@T6G_MB_LIB.T6G(SCH_1):PAGE68',
 TOLERANCE='20%',
 MATERIAL='X6S',
 PHYS_PAGE='69',
 XY='(-1275,4475)',
 ROT='0',
 VER='1',
 PACK_TYPE='C0402',
 LOCATION='C2244',
 CDS_LIB='pure_quanta',
 CDS_PART_NAME='Q_CAP_C0402-22UF,4V,20%,X6S,CH622KMEB02',
 VOLTAGE='4V',
 PART_NUMBER='CH622KMEB02',
 VALUE='22UF',
 PRIM_FILE='./archive_libs/logical/q_cap/chips/chips.prt';

PART_NAME
 C2245 'Q_CAP_C0402-22UF,4V,20%,X6S,CH622KMEB02':;

SECTION_NUMBER 1
 '@T6G_MB_LIB.T6G(SCH_1):PAGE68_I83@PURE_QUANTA.Q_CAP(CHIPS)':
 C_PATH='@t6g_mb_lib.t6g(sch_1):page68_i83@pure_quanta.q_cap(chips)',
 P_PATH='@t6g_mb_lib.t6g(sch_1):page69_i83@pure_quanta.q_cap(chips)',
 PATH='I83',
 DRAWING='@T6G_MB_LIB.T6G(SCH_1):PAGE68',
 TOLERANCE='20%',
 MATERIAL='X6S',
 PHYS_PAGE='69',
 XY='(-1275,3675)',
 ROT='0',
 VER='1',
 PACK_TYPE='C0402',
 LOCATION='C2245',
 CDS_LIB='pure_quanta',
 CDS_PART_NAME='Q_CAP_C0402-22UF,4V,20%,X6S,CH622KMEB02',
 VOLTAGE='4V',
 PART_NUMBER='CH622KMEB02',
 VALUE='22UF',
 PRIM_FILE='./archive_libs/logical/q_cap/chips/chips.prt';

PART_NAME
 C2246 'Q_CAP_C0402-22UF,4V,20%,X6S,CH622KMEB02':;

SECTION_NUMBER 1
 '@T6G_MB_LIB.T6G(SCH_1):PAGE68_I81@PURE_QUANTA.Q_CAP(CHIPS)':
 C_PATH='@t6g_mb_lib.t6g(sch_1):page68_i81@pure_quanta.q_cap(chips)',
 P_PATH='@t6g_mb_lib.t6g(sch_1):page69_i81@pure_quanta.q_cap(chips)',
 PATH='I81',
 DRAWING='@T6G_MB_LIB.T6G(SCH_1):PAGE68',
 TOLERANCE='20%',
 MATERIAL='X6S',
 PHYS_PAGE='69',
 XY='(-1275,2875)',
 ROT='0',
 VER='1',
 PACK_TYPE='C0402',
 LOCATION='C2246',
 CDS_LIB='pure_quanta',
 CDS_PART_NAME='Q_CAP_C0402-22UF,4V,20%,X6S,CH622KMEB02',
 VOLTAGE='4V',
 PART_NUMBER='CH622KMEB02',
 VALUE='22UF',
 PRIM_FILE='./archive_libs/logical/q_cap/chips/chips.prt';

PART_NAME
 C2248 'Q_CAP_C0402-22UF,4V,20%,X6S,CH622KMEB02':;

SECTION_NUMBER 1
 '@T6G_MB_LIB.T6G(SCH_1):PAGE68_I108@PURE_QUANTA.Q_CAP(CHIPS)':
 C_PATH='@t6g_mb_lib.t6g(sch_1):page68_i108@pure_quanta.q_cap(chips)',
 P_PATH='@t6g_mb_lib.t6g(sch_1):page69_i108@pure_quanta.q_cap(chips)',
 PATH='I108',
 DRAWING='@T6G_MB_LIB.T6G(SCH_1):PAGE68',
 TOLERANCE='20%',
 MATERIAL='X6S',
 PHYS_PAGE='69',
 XY='(-825,5250)',
 ROT='0',
 VER='1',
 PACK_TYPE='C0402',
 LOCATION='C2248',
 CDS_LIB='pure_quanta',
 CDS_PART_NAME='Q_CAP_C0402-22UF,4V,20%,X6S,CH622KMEB02',
 VOLTAGE='4V',
 PART_NUMBER='CH622KMEB02',
 VALUE='22UF',
 PRIM_FILE='./archive_libs/logical/q_cap/chips/chips.prt';

PART_NAME
 C2249 'Q_CAP_C0402-22UF,4V,20%,X6S,CH622KMEB02':;

SECTION_NUMBER 1
 '@T6G_MB_LIB.T6G(SCH_1):PAGE68_I105@PURE_QUANTA.Q_CAP(CHIPS)':
 C_PATH='@t6g_mb_lib.t6g(sch_1):page68_i105@pure_quanta.q_cap(chips)',
 P_PATH='@t6g_mb_lib.t6g(sch_1):page69_i105@pure_quanta.q_cap(chips)',
 PATH='I105',
 DRAWING='@T6G_MB_LIB.T6G(SCH_1):PAGE68',
 TOLERANCE='20%',
 MATERIAL='X6S',
 PHYS_PAGE='69',
 XY='(-825,4475)',
 ROT='0',
 VER='1',
 PACK_TYPE='C0402',
 LOCATION='C2249',
 CDS_LIB='pure_quanta',
 CDS_PART_NAME='Q_CAP_C0402-22UF,4V,20%,X6S,CH622KMEB02',
 VOLTAGE='4V',
 PART_NUMBER='CH622KMEB02',
 VALUE='22UF',
 PRIM_FILE='./archive_libs/logical/q_cap/chips/chips.prt';

PART_NAME
 C2250 'Q_CAP_C0402-22UF,4V,20%,X6S,CH622KMEB02':;

SECTION_NUMBER 1
 '@T6G_MB_LIB.T6G(SCH_1):PAGE68_I87@PURE_QUANTA.Q_CAP(CHIPS)':
 C_PATH='@t6g_mb_lib.t6g(sch_1):page68_i87@pure_quanta.q_cap(chips)',
 P_PATH='@t6g_mb_lib.t6g(sch_1):page69_i87@pure_quanta.q_cap(chips)',
 PATH='I87',
 DRAWING='@T6G_MB_LIB.T6G(SCH_1):PAGE68',
 TOLERANCE='20%',
 MATERIAL='X6S',
 PHYS_PAGE='69',
 XY='(-825,3675)',
 ROT='0',
 VER='1',
 PACK_TYPE='C0402',
 LOCATION='C2250',
 CDS_LIB='pure_quanta',
 CDS_PART_NAME='Q_CAP_C0402-22UF,4V,20%,X6S,CH622KMEB02',
 VOLTAGE='4V',
 PART_NUMBER='CH622KMEB02',
 VALUE='22UF',
 PRIM_FILE='./archive_libs/logical/q_cap/chips/chips.prt';

PART_NAME
 C2251 'Q_CAP_C0402-22UF,4V,20%,X6S,CH622KMEB02':;

SECTION_NUMBER 1
 '@T6G_MB_LIB.T6G(SCH_1):PAGE68_I84@PURE_QUANTA.Q_CAP(CHIPS)':
 C_PATH='@t6g_mb_lib.t6g(sch_1):page68_i84@pure_quanta.q_cap(chips)',
 P_PATH='@t6g_mb_lib.t6g(sch_1):page69_i84@pure_quanta.q_cap(chips)',
 PATH='I84',
 DRAWING='@T6G_MB_LIB.T6G(SCH_1):PAGE68',
 TOLERANCE='20%',
 MATERIAL='X6S',
 PHYS_PAGE='69',
 XY='(-825,2875)',
 ROT='0',
 VER='1',
 PACK_TYPE='C0402',
 LOCATION='C2251',
 CDS_LIB='pure_quanta',
 CDS_PART_NAME='Q_CAP_C0402-22UF,4V,20%,X6S,CH622KMEB02',
 VOLTAGE='4V',
 PART_NUMBER='CH622KMEB02',
 VALUE='22UF',
 PRIM_FILE='./archive_libs/logical/q_cap/chips/chips.prt';

PART_NAME
 C2253 'Q_CAP_C0402-22UF,4V,20%,X6S,CH622KMEB02':;

SECTION_NUMBER 1
 '@T6G_MB_LIB.T6G(SCH_1):PAGE68_I109@PURE_QUANTA.Q_CAP(CHIPS)':
 C_PATH='@t6g_mb_lib.t6g(sch_1):page68_i109@pure_quanta.q_cap(chips)',
 P_PATH='@t6g_mb_lib.t6g(sch_1):page69_i109@pure_quanta.q_cap(chips)',
 PATH='I109',
 DRAWING='@T6G_MB_LIB.T6G(SCH_1):PAGE68',
 TOLERANCE='20%',
 MATERIAL='X6S',
 PHYS_PAGE='69',
 XY='(-425,5250)',
 ROT='0',
 VER='1',
 PACK_TYPE='C0402',
 LOCATION='C2253',
 CDS_LIB='pure_quanta',
 CDS_PART_NAME='Q_CAP_C0402-22UF,4V,20%,X6S,CH622KMEB02',
 VOLTAGE='4V',
 PART_NUMBER='CH622KMEB02',
 VALUE='22UF',
 PRIM_FILE='./archive_libs/logical/q_cap/chips/chips.prt';

PART_NAME
 C2254 'Q_CAP_C0402-22UF,4V,20%,X6S,CH622KMEB02':;

SECTION_NUMBER 1
 '@T6G_MB_LIB.T6G(SCH_1):PAGE68_I106@PURE_QUANTA.Q_CAP(CHIPS)':
 C_PATH='@t6g_mb_lib.t6g(sch_1):page68_i106@pure_quanta.q_cap(chips)',
 P_PATH='@t6g_mb_lib.t6g(sch_1):page69_i106@pure_quanta.q_cap(chips)',
 PATH='I106',
 DRAWING='@T6G_MB_LIB.T6G(SCH_1):PAGE68',
 TOLERANCE='20%',
 MATERIAL='X6S',
 PHYS_PAGE='69',
 XY='(-425,4475)',
 ROT='0',
 VER='1',
 PACK_TYPE='C0402',
 LOCATION='C2254',
 CDS_LIB='pure_quanta',
 CDS_PART_NAME='Q_CAP_C0402-22UF,4V,20%,X6S,CH622KMEB02',
 VOLTAGE='4V',
 PART_NUMBER='CH622KMEB02',
 VALUE='22UF',
 PRIM_FILE='./archive_libs/logical/q_cap/chips/chips.prt';

PART_NAME
 C2255 'Q_CAP_C0402-22UF,4V,20%,X6S,CH622KMEB02':;

SECTION_NUMBER 1
 '@T6G_MB_LIB.T6G(SCH_1):PAGE68_I89@PURE_QUANTA.Q_CAP(CHIPS)':
 C_PATH='@t6g_mb_lib.t6g(sch_1):page68_i89@pure_quanta.q_cap(chips)',
 P_PATH='@t6g_mb_lib.t6g(sch_1):page69_i89@pure_quanta.q_cap(chips)',
 PATH='I89',
 DRAWING='@T6G_MB_LIB.T6G(SCH_1):PAGE68',
 TOLERANCE='20%',
 MATERIAL='X6S',
 PHYS_PAGE='69',
 XY='(-425,3675)',
 ROT='0',
 VER='1',
 PACK_TYPE='C0402',
 LOCATION='C2255',
 CDS_LIB='pure_quanta',
 CDS_PART_NAME='Q_CAP_C0402-22UF,4V,20%,X6S,CH622KMEB02',
 VOLTAGE='4V',
 PART_NUMBER='CH622KMEB02',
 VALUE='22UF',
 PRIM_FILE='./archive_libs/logical/q_cap/chips/chips.prt';

PART_NAME
 C2256 'Q_CAP_C0402-22UF,4V,20%,X6S,CH622KMEB02':;

SECTION_NUMBER 1
 '@T6G_MB_LIB.T6G(SCH_1):PAGE68_I86@PURE_QUANTA.Q_CAP(CHIPS)':
 C_PATH='@t6g_mb_lib.t6g(sch_1):page68_i86@pure_quanta.q_cap(chips)',
 P_PATH='@t6g_mb_lib.t6g(sch_1):page69_i86@pure_quanta.q_cap(chips)',
 PATH='I86',
 DRAWING='@T6G_MB_LIB.T6G(SCH_1):PAGE68',
 TOLERANCE='20%',
 MATERIAL='X6S',
 PHYS_PAGE='69',
 XY='(-425,2875)',
 ROT='0',
 VER='1',
 PACK_TYPE='C0402',
 LOCATION='C2256',
 CDS_LIB='pure_quanta',
 CDS_PART_NAME='Q_CAP_C0402-22UF,4V,20%,X6S,CH622KMEB02',
 VOLTAGE='4V',
 PART_NUMBER='CH622KMEB02',
 VALUE='22UF',
 PRIM_FILE='./archive_libs/logical/q_cap/chips/chips.prt';

PART_NAME
 C2257 'Q_CAP_0402-0.1UF,25V,10%,X7R,CH4104K1B00':;

SECTION_NUMBER 1
 '@T6G_MB_LIB.T6G(SCH_1):PAGE232_I37@PURE_QUANTA.Q_CAP(CHIPS)':
 C_PATH='@t6g_mb_lib.t6g(sch_1):page232_i37@pure_quanta.q_cap(chips)',
 P_PATH='@t6g_mb_lib.t6g(sch_1):page233_i37@pure_quanta.q_cap(chips)',
 PATH='I37',
 DRAWING='@T6G_MB_LIB.T6G(SCH_1):PAGE232',
 TOLERANCE='10%',
 MATERIAL='X7R',
 PHYS_PAGE='233',
 XY='(-5300,5200)',
 ROT='0',
 VER='1',
 PACK_TYPE='0402',
 LOCATION='C2257',
 CDS_LIB='pure_quanta',
 CDS_PART_NAME='Q_CAP_0402-0.1UF,25V,10%,X7R,CH4104K1B00',
 VOLTAGE='25V',
 PART_NUMBER='CH4104K1B00',
 VALUE='0.1UF',
 PRIM_FILE='./archive_libs/logical/q_cap/chips/chips.prt';

PART_NAME
 C2258 'Q_CAP_C0402-22UF,4V,20%,X6S,CH622KMEB02':;

SECTION_NUMBER 1
 '@T6G_MB_LIB.T6G(SCH_1):PAGE71_I9@PURE_QUANTA.Q_CAP(CHIPS)':
 C_PATH='@t6g_mb_lib.t6g(sch_1):page71_i9@pure_quanta.q_cap(chips)',
 P_PATH='@t6g_mb_lib.t6g(sch_1):page72_i9@pure_quanta.q_cap(chips)',
 PATH='I9',
 DRAWING='@T6G_MB_LIB.T6G(SCH_1):PAGE71',
 TOLERANCE='20%',
 MATERIAL='X6S',
 PHYS_PAGE='72',
 XY='(-8525,4900)',
 ROT='0',
 VER='1',
 PACK_TYPE='C0402',
 LOCATION='C2258',
 CDS_LIB='pure_quanta',
 CDS_PART_NAME='Q_CAP_C0402-22UF,4V,20%,X6S,CH622KMEB02',
 VOLTAGE='4V',
 PART_NUMBER='CH622KMEB02',
 VALUE='22UF',
 PRIM_FILE='./archive_libs/logical/q_cap/chips/chips.prt';

PART_NAME
 C2259 'Q_CAP_C0402-22UF,4V,20%,X6S,CH622KMEB02':;

SECTION_NUMBER 1
 '@T6G_MB_LIB.T6G(SCH_1):PAGE71_I7@PURE_QUANTA.Q_CAP(CHIPS)':
 C_PATH='@t6g_mb_lib.t6g(sch_1):page71_i7@pure_quanta.q_cap(chips)',
 P_PATH='@t6g_mb_lib.t6g(sch_1):page72_i7@pure_quanta.q_cap(chips)',
 PATH='I7',
 DRAWING='@T6G_MB_LIB.T6G(SCH_1):PAGE71',
 TOLERANCE='20%',
 MATERIAL='X6S',
 PHYS_PAGE='72',
 XY='(-8525,4100)',
 ROT='0',
 VER='1',
 PACK_TYPE='C0402',
 LOCATION='C2259',
 CDS_LIB='pure_quanta',
 CDS_PART_NAME='Q_CAP_C0402-22UF,4V,20%,X6S,CH622KMEB02',
 VOLTAGE='4V',
 PART_NUMBER='CH622KMEB02',
 VALUE='22UF',
 PRIM_FILE='./archive_libs/logical/q_cap/chips/chips.prt';

PART_NAME
 C2260 'Q_CAP_C0402-22UF,4V,20%,X6S,CH622KMEB02':;

SECTION_NUMBER 1
 '@T6G_MB_LIB.T6G(SCH_1):PAGE71_I53@PURE_QUANTA.Q_CAP(CHIPS)':
 C_PATH='@t6g_mb_lib.t6g(sch_1):page71_i53@pure_quanta.q_cap(chips)',
 P_PATH='@t6g_mb_lib.t6g(sch_1):page72_i53@pure_quanta.q_cap(chips)',
 PATH='I53',
 DRAWING='@T6G_MB_LIB.T6G(SCH_1):PAGE71',
 TOLERANCE='20%',
 MATERIAL='X6S',
 PHYS_PAGE='72',
 XY='(-3600,4975)',
 ROT='0',
 VER='1',
 PACK_TYPE='C0402',
 LOCATION='C2260',
 CDS_LIB='pure_quanta',
 CDS_PART_NAME='Q_CAP_C0402-22UF,4V,20%,X6S,CH622KMEB02',
 VOLTAGE='4V',
 PART_NUMBER='CH622KMEB02',
 VALUE='22UF',
 PRIM_FILE='./archive_libs/logical/q_cap/chips/chips.prt';

PART_NAME
 C2261 'Q_CAP_C0402-22UF,4V,20%,X6S,CH622KMEB02':;

SECTION_NUMBER 1
 '@T6G_MB_LIB.T6G(SCH_1):PAGE71_I3@PURE_QUANTA.Q_CAP(CHIPS)':
 C_PATH='@t6g_mb_lib.t6g(sch_1):page71_i3@pure_quanta.q_cap(chips)',
 P_PATH='@t6g_mb_lib.t6g(sch_1):page72_i3@pure_quanta.q_cap(chips)',
 PATH='I3',
 DRAWING='@T6G_MB_LIB.T6G(SCH_1):PAGE71',
 TOLERANCE='20%',
 MATERIAL='X6S',
 PHYS_PAGE='72',
 XY='(-8500,1575)',
 ROT='0',
 VER='1',
 PACK_TYPE='C0402',
 LOCATION='C2261',
 CDS_LIB='pure_quanta',
 CDS_PART_NAME='Q_CAP_C0402-22UF,4V,20%,X6S,CH622KMEB02',
 VOLTAGE='4V',
 PART_NUMBER='CH622KMEB02',
 VALUE='22UF',
 PRIM_FILE='./archive_libs/logical/q_cap/chips/chips.prt';

PART_NAME
 C2262 'Q_CAP_C0402-22UF,4V,20%,X6S,CH622KMEB02':;

SECTION_NUMBER 1
 '@T6G_MB_LIB.T6G(SCH_1):PAGE71_I1@PURE_QUANTA.Q_CAP(CHIPS)':
 C_PATH='@t6g_mb_lib.t6g(sch_1):page71_i1@pure_quanta.q_cap(chips)',
 P_PATH='@t6g_mb_lib.t6g(sch_1):page72_i1@pure_quanta.q_cap(chips)',
 PATH='I1',
 DRAWING='@T6G_MB_LIB.T6G(SCH_1):PAGE71',
 TOLERANCE='20%',
 MATERIAL='X6S',
 PHYS_PAGE='72',
 XY='(-8500,825)',
 ROT='0',
 VER='1',
 PACK_TYPE='C0402',
 LOCATION='C2262',
 CDS_LIB='pure_quanta',
 CDS_PART_NAME='Q_CAP_C0402-22UF,4V,20%,X6S,CH622KMEB02',
 VOLTAGE='4V',
 PART_NUMBER='CH622KMEB02',
 VALUE='22UF',
 PRIM_FILE='./archive_libs/logical/q_cap/chips/chips.prt';

PART_NAME
 C2263 'Q_CAP_C0402-22UF,4V,20%,X6S,CH622KMEB02':;

SECTION_NUMBER 1
 '@T6G_MB_LIB.T6G(SCH_1):PAGE71_I31@PURE_QUANTA.Q_CAP(CHIPS)':
 C_PATH='@t6g_mb_lib.t6g(sch_1):page71_i31@pure_quanta.q_cap(chips)',
 P_PATH='@t6g_mb_lib.t6g(sch_1):page72_i31@pure_quanta.q_cap(chips)',
 PATH='I31',
 DRAWING='@T6G_MB_LIB.T6G(SCH_1):PAGE71',
 TOLERANCE='20%',
 MATERIAL='X6S',
 PHYS_PAGE='72',
 XY='(-8075,4900)',
 ROT='0',
 VER='1',
 PACK_TYPE='C0402',
 LOCATION='C2263',
 CDS_LIB='pure_quanta',
 CDS_PART_NAME='Q_CAP_C0402-22UF,4V,20%,X6S,CH622KMEB02',
 VOLTAGE='4V',
 PART_NUMBER='CH622KMEB02',
 VALUE='22UF',
 PRIM_FILE='./archive_libs/logical/q_cap/chips/chips.prt';

PART_NAME
 C2264 'Q_CAP_C0402-22UF,4V,20%,X6S,CH622KMEB02':;

SECTION_NUMBER 1
 '@T6G_MB_LIB.T6G(SCH_1):PAGE71_I30@PURE_QUANTA.Q_CAP(CHIPS)':
 C_PATH='@t6g_mb_lib.t6g(sch_1):page71_i30@pure_quanta.q_cap(chips)',
 P_PATH='@t6g_mb_lib.t6g(sch_1):page72_i30@pure_quanta.q_cap(chips)',
 PATH='I30',
 DRAWING='@T6G_MB_LIB.T6G(SCH_1):PAGE71',
 TOLERANCE='20%',
 MATERIAL='X6S',
 PHYS_PAGE='72',
 XY='(-8075,4100)',
 ROT='0',
 VER='1',
 PACK_TYPE='C0402',
 LOCATION='C2264',
 CDS_LIB='pure_quanta',
 CDS_PART_NAME='Q_CAP_C0402-22UF,4V,20%,X6S,CH622KMEB02',
 VOLTAGE='4V',
 PART_NUMBER='CH622KMEB02',
 VALUE='22UF',
 PRIM_FILE='./archive_libs/logical/q_cap/chips/chips.prt';

PART_NAME
 C2265 'Q_CAP_C0402-22UF,4V,20%,X6S,CH622KMEB02':;

SECTION_NUMBER 1
 '@T6G_MB_LIB.T6G(SCH_1):PAGE71_I54@PURE_QUANTA.Q_CAP(CHIPS)':
 C_PATH='@t6g_mb_lib.t6g(sch_1):page71_i54@pure_quanta.q_cap(chips)',
 P_PATH='@t6g_mb_lib.t6g(sch_1):page72_i54@pure_quanta.q_cap(chips)',
 PATH='I54',
 DRAWING='@T6G_MB_LIB.T6G(SCH_1):PAGE71',
 TOLERANCE='20%',
 MATERIAL='X6S',
 PHYS_PAGE='72',
 XY='(-3150,4975)',
 ROT='0',
 VER='1',
 PACK_TYPE='C0402',
 LOCATION='C2265',
 CDS_LIB='pure_quanta',
 CDS_PART_NAME='Q_CAP_C0402-22UF,4V,20%,X6S,CH622KMEB02',
 VOLTAGE='4V',
 PART_NUMBER='CH622KMEB02',
 VALUE='22UF',
 PRIM_FILE='./archive_libs/logical/q_cap/chips/chips.prt';

PART_NAME
 C2266 'Q_CAP_C0402-22UF,4V,20%,X6S,CH622KMEB02':;

SECTION_NUMBER 1
 '@T6G_MB_LIB.T6G(SCH_1):PAGE71_I13@PURE_QUANTA.Q_CAP(CHIPS)':
 C_PATH='@t6g_mb_lib.t6g(sch_1):page71_i13@pure_quanta.q_cap(chips)',
 P_PATH='@t6g_mb_lib.t6g(sch_1):page72_i13@pure_quanta.q_cap(chips)',
 PATH='I13',
 DRAWING='@T6G_MB_LIB.T6G(SCH_1):PAGE71',
 TOLERANCE='20%',
 MATERIAL='X6S',
 PHYS_PAGE='72',
 XY='(-8050,1575)',
 ROT='0',
 VER='1',
 PACK_TYPE='C0402',
 LOCATION='C2266',
 CDS_LIB='pure_quanta',
 CDS_PART_NAME='Q_CAP_C0402-22UF,4V,20%,X6S,CH622KMEB02',
 VOLTAGE='4V',
 PART_NUMBER='CH622KMEB02',
 VALUE='22UF',
 PRIM_FILE='./archive_libs/logical/q_cap/chips/chips.prt';

PART_NAME
 C2267 'Q_CAP_C0402-22UF,4V,20%,X6S,CH622KMEB02':;

SECTION_NUMBER 1
 '@T6G_MB_LIB.T6G(SCH_1):PAGE71_I11@PURE_QUANTA.Q_CAP(CHIPS)':
 C_PATH='@t6g_mb_lib.t6g(sch_1):page71_i11@pure_quanta.q_cap(chips)',
 P_PATH='@t6g_mb_lib.t6g(sch_1):page72_i11@pure_quanta.q_cap(chips)',
 PATH='I11',
 DRAWING='@T6G_MB_LIB.T6G(SCH_1):PAGE71',
 TOLERANCE='20%',
 MATERIAL='X6S',
 PHYS_PAGE='72',
 XY='(-8050,825)',
 ROT='0',
 VER='1',
 PACK_TYPE='C0402',
 LOCATION='C2267',
 CDS_LIB='pure_quanta',
 CDS_PART_NAME='Q_CAP_C0402-22UF,4V,20%,X6S,CH622KMEB02',
 VOLTAGE='4V',
 PART_NUMBER='CH622KMEB02',
 VALUE='22UF',
 PRIM_FILE='./archive_libs/logical/q_cap/chips/chips.prt';

PART_NAME
 C2268 'Q_CAP_C0402-22UF,4V,20%,X6S,CH622KMEB02':;

SECTION_NUMBER 1
 '@T6G_MB_LIB.T6G(SCH_1):PAGE71_I33@PURE_QUANTA.Q_CAP(CHIPS)':
 C_PATH='@t6g_mb_lib.t6g(sch_1):page71_i33@pure_quanta.q_cap(chips)',
 P_PATH='@t6g_mb_lib.t6g(sch_1):page72_i33@pure_quanta.q_cap(chips)',
 PATH='I33',
 DRAWING='@T6G_MB_LIB.T6G(SCH_1):PAGE71',
 TOLERANCE='20%',
 MATERIAL='X6S',
 PHYS_PAGE='72',
 XY='(-7625,4900)',
 ROT='0',
 VER='1',
 PACK_TYPE='C0402',
 LOCATION='C2268',
 CDS_LIB='pure_quanta',
 CDS_PART_NAME='Q_CAP_C0402-22UF,4V,20%,X6S,CH622KMEB02',
 VOLTAGE='4V',
 PART_NUMBER='CH622KMEB02',
 VALUE='22UF',
 PRIM_FILE='./archive_libs/logical/q_cap/chips/chips.prt';

PART_NAME
 C2269 'Q_CAP_C0402-22UF,4V,20%,X6S,CH622KMEB02':;

SECTION_NUMBER 1
 '@T6G_MB_LIB.T6G(SCH_1):PAGE71_I32@PURE_QUANTA.Q_CAP(CHIPS)':
 C_PATH='@t6g_mb_lib.t6g(sch_1):page71_i32@pure_quanta.q_cap(chips)',
 P_PATH='@t6g_mb_lib.t6g(sch_1):page72_i32@pure_quanta.q_cap(chips)',
 PATH='I32',
 DRAWING='@T6G_MB_LIB.T6G(SCH_1):PAGE71',
 TOLERANCE='20%',
 MATERIAL='X6S',
 PHYS_PAGE='72',
 XY='(-7625,4100)',
 ROT='0',
 VER='1',
 PACK_TYPE='C0402',
 LOCATION='C2269',
 CDS_LIB='pure_quanta',
 CDS_PART_NAME='Q_CAP_C0402-22UF,4V,20%,X6S,CH622KMEB02',
 VOLTAGE='4V',
 PART_NUMBER='CH622KMEB02',
 VALUE='22UF',
 PRIM_FILE='./archive_libs/logical/q_cap/chips/chips.prt';

PART_NAME
 C2270 'Q_CAP_C0402-22UF,4V,20%,X6S,CH622KMEB02':;

SECTION_NUMBER 1
 '@T6G_MB_LIB.T6G(SCH_1):PAGE71_I56@PURE_QUANTA.Q_CAP(CHIPS)':
 C_PATH='@t6g_mb_lib.t6g(sch_1):page71_i56@pure_quanta.q_cap(chips)',
 P_PATH='@t6g_mb_lib.t6g(sch_1):page72_i56@pure_quanta.q_cap(chips)',
 PATH='I56',
 DRAWING='@T6G_MB_LIB.T6G(SCH_1):PAGE71',
 TOLERANCE='20%',
 MATERIAL='X6S',
 PHYS_PAGE='72',
 XY='(-2700,4975)',
 ROT='0',
 VER='1',
 PACK_TYPE='C0402',
 LOCATION='C2270',
 CDS_LIB='pure_quanta',
 CDS_PART_NAME='Q_CAP_C0402-22UF,4V,20%,X6S,CH622KMEB02',
 VOLTAGE='4V',
 PART_NUMBER='CH622KMEB02',
 VALUE='22UF',
 PRIM_FILE='./archive_libs/logical/q_cap/chips/chips.prt';

PART_NAME
 C2271 'Q_CAP_C0402-22UF,4V,20%,X6S,CH622KMEB02':;

SECTION_NUMBER 1
 '@T6G_MB_LIB.T6G(SCH_1):PAGE71_I14@PURE_QUANTA.Q_CAP(CHIPS)':
 C_PATH='@t6g_mb_lib.t6g(sch_1):page71_i14@pure_quanta.q_cap(chips)',
 P_PATH='@t6g_mb_lib.t6g(sch_1):page72_i14@pure_quanta.q_cap(chips)',
 PATH='I14',
 DRAWING='@T6G_MB_LIB.T6G(SCH_1):PAGE71',
 TOLERANCE='20%',
 MATERIAL='X6S',
 PHYS_PAGE='72',
 XY='(-7600,1575)',
 ROT='0',
 VER='1',
 PACK_TYPE='C0402',
 LOCATION='C2271',
 CDS_LIB='pure_quanta',
 CDS_PART_NAME='Q_CAP_C0402-22UF,4V,20%,X6S,CH622KMEB02',
 VOLTAGE='4V',
 PART_NUMBER='CH622KMEB02',
 VALUE='22UF',
 PRIM_FILE='./archive_libs/logical/q_cap/chips/chips.prt';

PART_NAME
 C2272 'Q_CAP_C0402-22UF,4V,20%,X6S,CH622KMEB02':;

SECTION_NUMBER 1
 '@T6G_MB_LIB.T6G(SCH_1):PAGE71_I34@PURE_QUANTA.Q_CAP(CHIPS)':
 C_PATH='@t6g_mb_lib.t6g(sch_1):page71_i34@pure_quanta.q_cap(chips)',
 P_PATH='@t6g_mb_lib.t6g(sch_1):page72_i34@pure_quanta.q_cap(chips)',
 PATH='I34',
 DRAWING='@T6G_MB_LIB.T6G(SCH_1):PAGE71',
 TOLERANCE='20%',
 MATERIAL='X6S',
 PHYS_PAGE='72',
 XY='(-7175,4900)',
 ROT='0',
 VER='1',
 PACK_TYPE='C0402',
 LOCATION='C2272',
 CDS_LIB='pure_quanta',
 CDS_PART_NAME='Q_CAP_C0402-22UF,4V,20%,X6S,CH622KMEB02',
 VOLTAGE='4V',
 PART_NUMBER='CH622KMEB02',
 VALUE='22UF',
 PRIM_FILE='./archive_libs/logical/q_cap/chips/chips.prt';

PART_NAME
 C2273 'Q_CAP_C0402-22UF,4V,20%,X6S,CH622KMEB02':;

SECTION_NUMBER 1
 '@T6G_MB_LIB.T6G(SCH_1):PAGE71_I35@PURE_QUANTA.Q_CAP(CHIPS)':
 C_PATH='@t6g_mb_lib.t6g(sch_1):page71_i35@pure_quanta.q_cap(chips)',
 P_PATH='@t6g_mb_lib.t6g(sch_1):page72_i35@pure_quanta.q_cap(chips)',
 PATH='I35',
 DRAWING='@T6G_MB_LIB.T6G(SCH_1):PAGE71',
 TOLERANCE='20%',
 MATERIAL='X6S',
 PHYS_PAGE='72',
 XY='(-7175,4100)',
 ROT='0',
 VER='1',
 PACK_TYPE='C0402',
 LOCATION='C2273',
 CDS_LIB='pure_quanta',
 CDS_PART_NAME='Q_CAP_C0402-22UF,4V,20%,X6S,CH622KMEB02',
 VOLTAGE='4V',
 PART_NUMBER='CH622KMEB02',
 VALUE='22UF',
 PRIM_FILE='./archive_libs/logical/q_cap/chips/chips.prt';

PART_NAME
 C2274 'Q_CAP_C0402-22UF,4V,20%,X6S,CH622KMEB02':;

SECTION_NUMBER 1
 '@T6G_MB_LIB.T6G(SCH_1):PAGE71_I57@PURE_QUANTA.Q_CAP(CHIPS)':
 C_PATH='@t6g_mb_lib.t6g(sch_1):page71_i57@pure_quanta.q_cap(chips)',
 P_PATH='@t6g_mb_lib.t6g(sch_1):page72_i57@pure_quanta.q_cap(chips)',
 PATH='I57',
 DRAWING='@T6G_MB_LIB.T6G(SCH_1):PAGE71',
 TOLERANCE='20%',
 MATERIAL='X6S',
 PHYS_PAGE='72',
 XY='(-2250,4975)',
 ROT='0',
 VER='1',
 PACK_TYPE='C0402',
 LOCATION='C2274',
 CDS_LIB='pure_quanta',
 CDS_PART_NAME='Q_CAP_C0402-22UF,4V,20%,X6S,CH622KMEB02',
 VOLTAGE='4V',
 PART_NUMBER='CH622KMEB02',
 VALUE='22UF',
 PRIM_FILE='./archive_libs/logical/q_cap/chips/chips.prt';

PART_NAME
 C2275 'Q_CAP_C0402-22UF,4V,20%,X6S,CH622KMEB02':;

SECTION_NUMBER 1
 '@T6G_MB_LIB.T6G(SCH_1):PAGE71_I19@PURE_QUANTA.Q_CAP(CHIPS)':
 C_PATH='@t6g_mb_lib.t6g(sch_1):page71_i19@pure_quanta.q_cap(chips)',
 P_PATH='@t6g_mb_lib.t6g(sch_1):page72_i19@pure_quanta.q_cap(chips)',
 PATH='I19',
 DRAWING='@T6G_MB_LIB.T6G(SCH_1):PAGE71',
 TOLERANCE='20%',
 MATERIAL='X6S',
 PHYS_PAGE='72',
 XY='(-7150,1575)',
 ROT='0',
 VER='1',
 PACK_TYPE='C0402',
 LOCATION='C2275',
 CDS_LIB='pure_quanta',
 CDS_PART_NAME='Q_CAP_C0402-22UF,4V,20%,X6S,CH622KMEB02',
 VOLTAGE='4V',
 PART_NUMBER='CH622KMEB02',
 VALUE='22UF',
 PRIM_FILE='./archive_libs/logical/q_cap/chips/chips.prt';

PART_NAME
 C2276 'Q_CAP_C0402-22UF,4V,20%,X6S,CH622KMEB02':;

SECTION_NUMBER 1
 '@T6G_MB_LIB.T6G(SCH_1):PAGE71_I62@PURE_QUANTA.Q_CAP(CHIPS)':
 C_PATH='@t6g_mb_lib.t6g(sch_1):page71_i62@pure_quanta.q_cap(chips)',
 P_PATH='@t6g_mb_lib.t6g(sch_1):page72_i62@pure_quanta.q_cap(chips)',
 PATH='I62',
 DRAWING='@T6G_MB_LIB.T6G(SCH_1):PAGE71',
 TOLERANCE='20%',
 MATERIAL='X6S',
 PHYS_PAGE='72',
 XY='(-6725,4900)',
 ROT='0',
 VER='1',
 PACK_TYPE='C0402',
 LOCATION='C2276',
 CDS_LIB='pure_quanta',
 CDS_PART_NAME='Q_CAP_C0402-22UF,4V,20%,X6S,CH622KMEB02',
 VOLTAGE='4V',
 PART_NUMBER='CH622KMEB02',
 VALUE='22UF',
 PRIM_FILE='./archive_libs/logical/q_cap/chips/chips.prt';

PART_NAME
 C2277 'Q_CAP_C0402-22UF,4V,20%,X6S,CH622KMEB02':;

SECTION_NUMBER 1
 '@T6G_MB_LIB.T6G(SCH_1):PAGE71_I36@PURE_QUANTA.Q_CAP(CHIPS)':
 C_PATH='@t6g_mb_lib.t6g(sch_1):page71_i36@pure_quanta.q_cap(chips)',
 P_PATH='@t6g_mb_lib.t6g(sch_1):page72_i36@pure_quanta.q_cap(chips)',
 PATH='I36',
 DRAWING='@T6G_MB_LIB.T6G(SCH_1):PAGE71',
 TOLERANCE='20%',
 MATERIAL='X6S',
 PHYS_PAGE='72',
 XY='(-6725,4100)',
 ROT='0',
 VER='1',
 PACK_TYPE='C0402',
 LOCATION='C2277',
 CDS_LIB='pure_quanta',
 CDS_PART_NAME='Q_CAP_C0402-22UF,4V,20%,X6S,CH622KMEB02',
 VOLTAGE='4V',
 PART_NUMBER='CH622KMEB02',
 VALUE='22UF',
 PRIM_FILE='./archive_libs/logical/q_cap/chips/chips.prt';

PART_NAME
 C2278 'Q_CAP_C0402-22UF,4V,20%,X6S,CH622KMEB02':;

SECTION_NUMBER 1
 '@T6G_MB_LIB.T6G(SCH_1):PAGE71_I58@PURE_QUANTA.Q_CAP(CHIPS)':
 C_PATH='@t6g_mb_lib.t6g(sch_1):page71_i58@pure_quanta.q_cap(chips)',
 P_PATH='@t6g_mb_lib.t6g(sch_1):page72_i58@pure_quanta.q_cap(chips)',
 PATH='I58',
 DRAWING='@T6G_MB_LIB.T6G(SCH_1):PAGE71',
 TOLERANCE='20%',
 MATERIAL='X6S',
 PHYS_PAGE='72',
 XY='(-1800,4975)',
 ROT='0',
 VER='1',
 PACK_TYPE='C0402',
 LOCATION='C2278',
 CDS_LIB='pure_quanta',
 CDS_PART_NAME='Q_CAP_C0402-22UF,4V,20%,X6S,CH622KMEB02',
 VOLTAGE='4V',
 PART_NUMBER='CH622KMEB02',
 VALUE='22UF',
 PRIM_FILE='./archive_libs/logical/q_cap/chips/chips.prt';

PART_NAME
 C2279 'Q_CAP_C0402-22UF,4V,20%,X6S,CH622KMEB02':;

SECTION_NUMBER 1
 '@T6G_MB_LIB.T6G(SCH_1):PAGE71_I20@PURE_QUANTA.Q_CAP(CHIPS)':
 C_PATH='@t6g_mb_lib.t6g(sch_1):page71_i20@pure_quanta.q_cap(chips)',
 P_PATH='@t6g_mb_lib.t6g(sch_1):page72_i20@pure_quanta.q_cap(chips)',
 PATH='I20',
 DRAWING='@T6G_MB_LIB.T6G(SCH_1):PAGE71',
 TOLERANCE='20%',
 MATERIAL='X6S',
 PHYS_PAGE='72',
 XY='(-6700,1575)',
 ROT='0',
 VER='1',
 PACK_TYPE='C0402',
 LOCATION='C2279',
 CDS_LIB='pure_quanta',
 CDS_PART_NAME='Q_CAP_C0402-22UF,4V,20%,X6S,CH622KMEB02',
 VOLTAGE='4V',
 PART_NUMBER='CH622KMEB02',
 VALUE='22UF',
 PRIM_FILE='./archive_libs/logical/q_cap/chips/chips.prt';

PART_NAME
 C2280 'Q_CAP_C0402-22UF,4V,20%,X6S,CH622KMEB02':;

SECTION_NUMBER 1
 '@T6G_MB_LIB.T6G(SCH_1):PAGE71_I38@PURE_QUANTA.Q_CAP(CHIPS)':
 C_PATH='@t6g_mb_lib.t6g(sch_1):page71_i38@pure_quanta.q_cap(chips)',
 P_PATH='@t6g_mb_lib.t6g(sch_1):page72_i38@pure_quanta.q_cap(chips)',
 PATH='I38',
 DRAWING='@T6G_MB_LIB.T6G(SCH_1):PAGE71',
 TOLERANCE='20%',
 MATERIAL='X6S',
 PHYS_PAGE='72',
 XY='(-6275,4900)',
 ROT='0',
 VER='1',
 PACK_TYPE='C0402',
 LOCATION='C2280',
 CDS_LIB='pure_quanta',
 CDS_PART_NAME='Q_CAP_C0402-22UF,4V,20%,X6S,CH622KMEB02',
 VOLTAGE='4V',
 PART_NUMBER='CH622KMEB02',
 VALUE='22UF',
 PRIM_FILE='./archive_libs/logical/q_cap/chips/chips.prt';

PART_NAME
 C2281 'Q_CAP_C0402-22UF,4V,20%,X6S,CH622KMEB02':;

SECTION_NUMBER 1
 '@T6G_MB_LIB.T6G(SCH_1):PAGE71_I37@PURE_QUANTA.Q_CAP(CHIPS)':
 C_PATH='@t6g_mb_lib.t6g(sch_1):page71_i37@pure_quanta.q_cap(chips)',
 P_PATH='@t6g_mb_lib.t6g(sch_1):page72_i37@pure_quanta.q_cap(chips)',
 PATH='I37',
 DRAWING='@T6G_MB_LIB.T6G(SCH_1):PAGE71',
 TOLERANCE='20%',
 MATERIAL='X6S',
 PHYS_PAGE='72',
 XY='(-6275,4100)',
 ROT='0',
 VER='1',
 PACK_TYPE='C0402',
 LOCATION='C2281',
 CDS_LIB='pure_quanta',
 CDS_PART_NAME='Q_CAP_C0402-22UF,4V,20%,X6S,CH622KMEB02',
 VOLTAGE='4V',
 PART_NUMBER='CH622KMEB02',
 VALUE='22UF',
 PRIM_FILE='./archive_libs/logical/q_cap/chips/chips.prt';

PART_NAME
 C2282 'Q_CAP_C0402-22UF,4V,20%,X6S,CH622KMEB02':;

SECTION_NUMBER 1
 '@T6G_MB_LIB.T6G(SCH_1):PAGE71_I21@PURE_QUANTA.Q_CAP(CHIPS)':
 C_PATH='@t6g_mb_lib.t6g(sch_1):page71_i21@pure_quanta.q_cap(chips)',
 P_PATH='@t6g_mb_lib.t6g(sch_1):page72_i21@pure_quanta.q_cap(chips)',
 PATH='I21',
 DRAWING='@T6G_MB_LIB.T6G(SCH_1):PAGE71',
 TOLERANCE='20%',
 MATERIAL='X6S',
 PHYS_PAGE='72',
 XY='(-6250,1575)',
 ROT='0',
 VER='1',
 PACK_TYPE='C0402',
 LOCATION='C2282',
 CDS_LIB='pure_quanta',
 CDS_PART_NAME='Q_CAP_C0402-22UF,4V,20%,X6S,CH622KMEB02',
 VOLTAGE='4V',
 PART_NUMBER='CH622KMEB02',
 VALUE='22UF',
 PRIM_FILE='./archive_libs/logical/q_cap/chips/chips.prt';

PART_NAME
 C2283 'Q_CAP_C0402-22UF,4V,20%,X6S,CH622KMEB02':;

SECTION_NUMBER 1
 '@T6G_MB_LIB.T6G(SCH_1):PAGE71_I40@PURE_QUANTA.Q_CAP(CHIPS)':
 C_PATH='@t6g_mb_lib.t6g(sch_1):page71_i40@pure_quanta.q_cap(chips)',
 P_PATH='@t6g_mb_lib.t6g(sch_1):page72_i40@pure_quanta.q_cap(chips)',
 PATH='I40',
 DRAWING='@T6G_MB_LIB.T6G(SCH_1):PAGE71',
 TOLERANCE='20%',
 MATERIAL='X6S',
 PHYS_PAGE='72',
 XY='(-5825,4900)',
 ROT='0',
 VER='1',
 PACK_TYPE='C0402',
 LOCATION='C2283',
 CDS_LIB='pure_quanta',
 CDS_PART_NAME='Q_CAP_C0402-22UF,4V,20%,X6S,CH622KMEB02',
 VOLTAGE='4V',
 PART_NUMBER='CH622KMEB02',
 VALUE='22UF',
 PRIM_FILE='./archive_libs/logical/q_cap/chips/chips.prt';

PART_NAME
 C2284 'Q_CAP_C0402-22UF,4V,20%,X6S,CH622KMEB02':;

SECTION_NUMBER 1
 '@T6G_MB_LIB.T6G(SCH_1):PAGE71_I39@PURE_QUANTA.Q_CAP(CHIPS)':
 C_PATH='@t6g_mb_lib.t6g(sch_1):page71_i39@pure_quanta.q_cap(chips)',
 P_PATH='@t6g_mb_lib.t6g(sch_1):page72_i39@pure_quanta.q_cap(chips)',
 PATH='I39',
 DRAWING='@T6G_MB_LIB.T6G(SCH_1):PAGE71',
 TOLERANCE='20%',
 MATERIAL='X6S',
 PHYS_PAGE='72',
 XY='(-5825,4100)',
 ROT='0',
 VER='1',
 PACK_TYPE='C0402',
 LOCATION='C2284',
 CDS_LIB='pure_quanta',
 CDS_PART_NAME='Q_CAP_C0402-22UF,4V,20%,X6S,CH622KMEB02',
 VOLTAGE='4V',
 PART_NUMBER='CH622KMEB02',
 VALUE='22UF',
 PRIM_FILE='./archive_libs/logical/q_cap/chips/chips.prt';

PART_NAME
 C2285 'Q_CAP_C0402-22UF,4V,20%,X6S,CH622KMEB02':;

SECTION_NUMBER 1
 '@T6G_MB_LIB.T6G(SCH_1):PAGE71_I24@PURE_QUANTA.Q_CAP(CHIPS)':
 C_PATH='@t6g_mb_lib.t6g(sch_1):page71_i24@pure_quanta.q_cap(chips)',
 P_PATH='@t6g_mb_lib.t6g(sch_1):page72_i24@pure_quanta.q_cap(chips)',
 PATH='I24',
 DRAWING='@T6G_MB_LIB.T6G(SCH_1):PAGE71',
 TOLERANCE='20%',
 MATERIAL='X6S',
 PHYS_PAGE='72',
 XY='(-5800,1575)',
 ROT='0',
 VER='1',
 PACK_TYPE='C0402',
 LOCATION='C2285',
 CDS_LIB='pure_quanta',
 CDS_PART_NAME='Q_CAP_C0402-22UF,4V,20%,X6S,CH622KMEB02',
 VOLTAGE='4V',
 PART_NUMBER='CH622KMEB02',
 VALUE='22UF',
 PRIM_FILE='./archive_libs/logical/q_cap/chips/chips.prt';

PART_NAME
 C2286 'Q_CAP_C0402-22UF,4V,20%,X6S,CH622KMEB02':;

SECTION_NUMBER 1
 '@T6G_MB_LIB.T6G(SCH_1):PAGE71_I42@PURE_QUANTA.Q_CAP(CHIPS)':
 C_PATH='@t6g_mb_lib.t6g(sch_1):page71_i42@pure_quanta.q_cap(chips)',
 P_PATH='@t6g_mb_lib.t6g(sch_1):page72_i42@pure_quanta.q_cap(chips)',
 PATH='I42',
 DRAWING='@T6G_MB_LIB.T6G(SCH_1):PAGE71',
 TOLERANCE='20%',
 MATERIAL='X6S',
 PHYS_PAGE='72',
 XY='(-5375,4900)',
 ROT='0',
 VER='1',
 PACK_TYPE='C0402',
 LOCATION='C2286',
 CDS_LIB='pure_quanta',
 CDS_PART_NAME='Q_CAP_C0402-22UF,4V,20%,X6S,CH622KMEB02',
 VOLTAGE='4V',
 PART_NUMBER='CH622KMEB02',
 VALUE='22UF',
 PRIM_FILE='./archive_libs/logical/q_cap/chips/chips.prt';

PART_NAME
 C2287 'Q_CAP_C0402-22UF,4V,20%,X6S,CH622KMEB02':;

SECTION_NUMBER 1
 '@T6G_MB_LIB.T6G(SCH_1):PAGE71_I25@PURE_QUANTA.Q_CAP(CHIPS)':
 C_PATH='@t6g_mb_lib.t6g(sch_1):page71_i25@pure_quanta.q_cap(chips)',
 P_PATH='@t6g_mb_lib.t6g(sch_1):page72_i25@pure_quanta.q_cap(chips)',
 PATH='I25',
 DRAWING='@T6G_MB_LIB.T6G(SCH_1):PAGE71',
 TOLERANCE='20%',
 MATERIAL='X6S',
 PHYS_PAGE='72',
 XY='(-5350,1575)',
 ROT='0',
 VER='1',
 PACK_TYPE='C0402',
 LOCATION='C2287',
 CDS_LIB='pure_quanta',
 CDS_PART_NAME='Q_CAP_C0402-22UF,4V,20%,X6S,CH622KMEB02',
 VOLTAGE='4V',
 PART_NUMBER='CH622KMEB02',
 VALUE='22UF',
 PRIM_FILE='./archive_libs/logical/q_cap/chips/chips.prt';

PART_NAME
 C2288 'Q_CAP_C0402-22UF,4V,20%,X6S,CH622KMEB02':;

SECTION_NUMBER 1
 '@T6G_MB_LIB.T6G(SCH_1):PAGE71_I44@PURE_QUANTA.Q_CAP(CHIPS)':
 C_PATH='@t6g_mb_lib.t6g(sch_1):page71_i44@pure_quanta.q_cap(chips)',
 P_PATH='@t6g_mb_lib.t6g(sch_1):page72_i44@pure_quanta.q_cap(chips)',
 PATH='I44',
 DRAWING='@T6G_MB_LIB.T6G(SCH_1):PAGE71',
 TOLERANCE='20%',
 MATERIAL='X6S',
 PHYS_PAGE='72',
 XY='(-4925,4900)',
 ROT='0',
 VER='1',
 PACK_TYPE='C0402',
 LOCATION='C2288',
 CDS_LIB='pure_quanta',
 CDS_PART_NAME='Q_CAP_C0402-22UF,4V,20%,X6S,CH622KMEB02',
 VOLTAGE='4V',
 PART_NUMBER='CH622KMEB02',
 VALUE='22UF',
 PRIM_FILE='./archive_libs/logical/q_cap/chips/chips.prt';

PART_NAME
 C2289 'Q_CAP_C0402-22UF,4V,20%,X6S,CH622KMEB02':;

SECTION_NUMBER 1
 '@T6G_MB_LIB.T6G(SCH_1):PAGE71_I26@PURE_QUANTA.Q_CAP(CHIPS)':
 C_PATH='@t6g_mb_lib.t6g(sch_1):page71_i26@pure_quanta.q_cap(chips)',
 P_PATH='@t6g_mb_lib.t6g(sch_1):page72_i26@pure_quanta.q_cap(chips)',
 PATH='I26',
 DRAWING='@T6G_MB_LIB.T6G(SCH_1):PAGE71',
 TOLERANCE='20%',
 MATERIAL='X6S',
 PHYS_PAGE='72',
 XY='(-4900,1575)',
 ROT='0',
 VER='1',
 PACK_TYPE='C0402',
 LOCATION='C2289',
 CDS_LIB='pure_quanta',
 CDS_PART_NAME='Q_CAP_C0402-22UF,4V,20%,X6S,CH622KMEB02',
 VOLTAGE='4V',
 PART_NUMBER='CH622KMEB02',
 VALUE='22UF',
 PRIM_FILE='./archive_libs/logical/q_cap/chips/chips.prt';

PART_NAME
 C2290 'Q_CAP_C0402-22UF,4V,20%,X6S,CH622KMEB02':;

SECTION_NUMBER 1
 '@T6G_MB_LIB.T6G(SCH_1):PAGE71_I47@PURE_QUANTA.Q_CAP(CHIPS)':
 C_PATH='@t6g_mb_lib.t6g(sch_1):page71_i47@pure_quanta.q_cap(chips)',
 P_PATH='@t6g_mb_lib.t6g(sch_1):page72_i47@pure_quanta.q_cap(chips)',
 PATH='I47',
 DRAWING='@T6G_MB_LIB.T6G(SCH_1):PAGE71',
 TOLERANCE='20%',
 MATERIAL='X6S',
 PHYS_PAGE='72',
 XY='(-4525,4900)',
 ROT='0',
 VER='1',
 PACK_TYPE='C0402',
 LOCATION='C2290',
 CDS_LIB='pure_quanta',
 CDS_PART_NAME='Q_CAP_C0402-22UF,4V,20%,X6S,CH622KMEB02',
 VOLTAGE='4V',
 PART_NUMBER='CH622KMEB02',
 VALUE='22UF',
 PRIM_FILE='./archive_libs/logical/q_cap/chips/chips.prt';

PART_NAME
 C2291 'Q_CAP_C0402-22UF,4V,20%,X6S,CH622KMEB02':;

SECTION_NUMBER 1
 '@T6G_MB_LIB.T6G(SCH_1):PAGE71_I28@PURE_QUANTA.Q_CAP(CHIPS)':
 C_PATH='@t6g_mb_lib.t6g(sch_1):page71_i28@pure_quanta.q_cap(chips)',
 P_PATH='@t6g_mb_lib.t6g(sch_1):page72_i28@pure_quanta.q_cap(chips)',
 PATH='I28',
 DRAWING='@T6G_MB_LIB.T6G(SCH_1):PAGE71',
 TOLERANCE='20%',
 MATERIAL='X6S',
 PHYS_PAGE='72',
 XY='(-4500,1575)',
 ROT='0',
 VER='1',
 PACK_TYPE='C0402',
 LOCATION='C2291',
 CDS_LIB='pure_quanta',
 CDS_PART_NAME='Q_CAP_C0402-22UF,4V,20%,X6S,CH622KMEB02',
 VOLTAGE='4V',
 PART_NUMBER='CH622KMEB02',
 VALUE='22UF',
 PRIM_FILE='./archive_libs/logical/q_cap/chips/chips.prt';

PART_NAME
 C2292 'Q_CAP_C0402-22UF,4V,20%,X6S,CH622KMEB02':;

SECTION_NUMBER 1
 '@T6G_MB_LIB.T6G(SCH_1):PAGE71_I49@PURE_QUANTA.Q_CAP(CHIPS)':
 C_PATH='@t6g_mb_lib.t6g(sch_1):page71_i49@pure_quanta.q_cap(chips)',
 P_PATH='@t6g_mb_lib.t6g(sch_1):page72_i49@pure_quanta.q_cap(chips)',
 PATH='I49',
 DRAWING='@T6G_MB_LIB.T6G(SCH_1):PAGE71',
 TOLERANCE='20%',
 MATERIAL='X6S',
 PHYS_PAGE='72',
 XY='(-3600,3375)',
 ROT='0',
 VER='1',
 PACK_TYPE='C0402',
 LOCATION='C2292',
 CDS_LIB='pure_quanta',
 CDS_PART_NAME='Q_CAP_C0402-22UF,4V,20%,X6S,CH622KMEB02',
 VOLTAGE='4V',
 PART_NUMBER='CH622KMEB02',
 VALUE='22UF',
 PRIM_FILE='./archive_libs/logical/q_cap/chips/chips.prt';

PART_NAME
 C2293 'Q_CAP_C0402-22UF,4V,20%,X6S,CH622KMEB02':;

SECTION_NUMBER 1
 '@T6G_MB_LIB.T6G(SCH_1):PAGE71_I50@PURE_QUANTA.Q_CAP(CHIPS)':
 C_PATH='@t6g_mb_lib.t6g(sch_1):page71_i50@pure_quanta.q_cap(chips)',
 P_PATH='@t6g_mb_lib.t6g(sch_1):page72_i50@pure_quanta.q_cap(chips)',
 PATH='I50',
 DRAWING='@T6G_MB_LIB.T6G(SCH_1):PAGE71',
 TOLERANCE='20%',
 MATERIAL='X6S',
 PHYS_PAGE='72',
 XY='(-3150,3375)',
 ROT='0',
 VER='1',
 PACK_TYPE='C0402',
 LOCATION='C2293',
 CDS_LIB='pure_quanta',
 CDS_PART_NAME='Q_CAP_C0402-22UF,4V,20%,X6S,CH622KMEB02',
 VOLTAGE='4V',
 PART_NUMBER='CH622KMEB02',
 VALUE='22UF',
 PRIM_FILE='./archive_libs/logical/q_cap/chips/chips.prt';

PART_NAME
 C2294 'Q_CAP_C0402-22UF,4V,20%,X6S,CH622KMEB02':;

SECTION_NUMBER 1
 '@T6G_MB_LIB.T6G(SCH_1):PAGE72_I17@PURE_QUANTA.Q_CAP(CHIPS)':
 C_PATH='@t6g_mb_lib.t6g(sch_1):page72_i17@pure_quanta.q_cap(chips)',
 P_PATH='@t6g_mb_lib.t6g(sch_1):page73_i17@pure_quanta.q_cap(chips)',
 PATH='I17',
 DRAWING='@T6G_MB_LIB.T6G(SCH_1):PAGE72',
 TOLERANCE='20%',
 MATERIAL='X6S',
 PHYS_PAGE='73',
 XY='(-9400,4500)',
 ROT='0',
 VER='1',
 PACK_TYPE='C0402',
 LOCATION='C2294',
 CDS_LIB='pure_quanta',
 CDS_PART_NAME='Q_CAP_C0402-22UF,4V,20%,X6S,CH622KMEB02',
 VOLTAGE='4V',
 PART_NUMBER='CH622KMEB02',
 VALUE='22UF',
 PRIM_FILE='./archive_libs/logical/q_cap/chips/chips.prt';

PART_NAME
 C2295 'Q_CAP_C0402-22UF,4V,20%,X6S,CH622KMEB02':;

SECTION_NUMBER 1
 '@T6G_MB_LIB.T6G(SCH_1):PAGE72_I9@PURE_QUANTA.Q_CAP(CHIPS)':
 C_PATH='@t6g_mb_lib.t6g(sch_1):page72_i9@pure_quanta.q_cap(chips)',
 P_PATH='@t6g_mb_lib.t6g(sch_1):page73_i9@pure_quanta.q_cap(chips)',
 PATH='I9',
 DRAWING='@T6G_MB_LIB.T6G(SCH_1):PAGE72',
 TOLERANCE='20%',
 MATERIAL='X6S',
 PHYS_PAGE='73',
 XY='(-9400,3725)',
 ROT='0',
 VER='1',
 PACK_TYPE='C0402',
 LOCATION='C2295',
 CDS_LIB='pure_quanta',
 CDS_PART_NAME='Q_CAP_C0402-22UF,4V,20%,X6S,CH622KMEB02',
 VOLTAGE='4V',
 PART_NUMBER='CH622KMEB02',
 VALUE='22UF',
 PRIM_FILE='./archive_libs/logical/q_cap/chips/chips.prt';

PART_NAME
 C2296 'Q_CAP_C0402-22UF,4V,20%,X6S,CH622KMEB02':;

SECTION_NUMBER 1
 '@T6G_MB_LIB.T6G(SCH_1):PAGE72_I7@PURE_QUANTA.Q_CAP(CHIPS)':
 C_PATH='@t6g_mb_lib.t6g(sch_1):page72_i7@pure_quanta.q_cap(chips)',
 P_PATH='@t6g_mb_lib.t6g(sch_1):page73_i7@pure_quanta.q_cap(chips)',
 PATH='I7',
 DRAWING='@T6G_MB_LIB.T6G(SCH_1):PAGE72',
 TOLERANCE='20%',
 MATERIAL='X6S',
 PHYS_PAGE='73',
 XY='(-9400,2925)',
 ROT='0',
 VER='1',
 PACK_TYPE='C0402',
 LOCATION='C2296',
 CDS_LIB='pure_quanta',
 CDS_PART_NAME='Q_CAP_C0402-22UF,4V,20%,X6S,CH622KMEB02',
 VOLTAGE='4V',
 PART_NUMBER='CH622KMEB02',
 VALUE='22UF',
 PRIM_FILE='./archive_libs/logical/q_cap/chips/chips.prt';

PART_NAME
 C2297 'Q_CAP_C0402-22UF,4V,20%,X6S,CH622KMEB02':;

SECTION_NUMBER 1
 '@T6G_MB_LIB.T6G(SCH_1):PAGE72_I5@PURE_QUANTA.Q_CAP(CHIPS)':
 C_PATH='@t6g_mb_lib.t6g(sch_1):page72_i5@pure_quanta.q_cap(chips)',
 P_PATH='@t6g_mb_lib.t6g(sch_1):page73_i5@pure_quanta.q_cap(chips)',
 PATH='I5',
 DRAWING='@T6G_MB_LIB.T6G(SCH_1):PAGE72',
 TOLERANCE='20%',
 MATERIAL='X6S',
 PHYS_PAGE='73',
 XY='(-9400,2125)',
 ROT='0',
 VER='1',
 PACK_TYPE='C0402',
 LOCATION='C2297',
 CDS_LIB='pure_quanta',
 CDS_PART_NAME='Q_CAP_C0402-22UF,4V,20%,X6S,CH622KMEB02',
 VOLTAGE='4V',
 PART_NUMBER='CH622KMEB02',
 VALUE='22UF',
 PRIM_FILE='./archive_libs/logical/q_cap/chips/chips.prt';

PART_NAME
 C2298 'Q_CAP_C0402-22UF,4V,20%,X6S,CH622KMEB02':;

SECTION_NUMBER 1
 '@T6G_MB_LIB.T6G(SCH_1):PAGE72_I1@PURE_QUANTA.Q_CAP(CHIPS)':
 C_PATH='@t6g_mb_lib.t6g(sch_1):page72_i1@pure_quanta.q_cap(chips)',
 P_PATH='@t6g_mb_lib.t6g(sch_1):page73_i1@pure_quanta.q_cap(chips)',
 PATH='I1',
 DRAWING='@T6G_MB_LIB.T6G(SCH_1):PAGE72',
 TOLERANCE='20%',
 MATERIAL='X6S',
 PHYS_PAGE='73',
 XY='(-9400,1325)',
 ROT='0',
 VER='1',
 PACK_TYPE='C0402',
 LOCATION='C2298',
 CDS_LIB='pure_quanta',
 CDS_PART_NAME='Q_CAP_C0402-22UF,4V,20%,X6S,CH622KMEB02',
 VOLTAGE='4V',
 PART_NUMBER='CH622KMEB02',
 VALUE='22UF',
 PRIM_FILE='./archive_libs/logical/q_cap/chips/chips.prt';

PART_NAME
 C2300 'Q_CAP_C0402-22UF,4V,20%,X6S,CH622KMEB02':;

SECTION_NUMBER 1
 '@T6G_MB_LIB.T6G(SCH_1):PAGE72_I19@PURE_QUANTA.Q_CAP(CHIPS)':
 C_PATH='@t6g_mb_lib.t6g(sch_1):page72_i19@pure_quanta.q_cap(chips)',
 P_PATH='@t6g_mb_lib.t6g(sch_1):page73_i19@pure_quanta.q_cap(chips)',
 PATH='I19',
 DRAWING='@T6G_MB_LIB.T6G(SCH_1):PAGE72',
 TOLERANCE='20%',
 MATERIAL='X6S',
 PHYS_PAGE='73',
 XY='(-8950,4500)',
 ROT='0',
 VER='1',
 PACK_TYPE='C0402',
 LOCATION='C2300',
 CDS_LIB='pure_quanta',
 CDS_PART_NAME='Q_CAP_C0402-22UF,4V,20%,X6S,CH622KMEB02',
 VOLTAGE='4V',
 PART_NUMBER='CH622KMEB02',
 VALUE='22UF',
 PRIM_FILE='./archive_libs/logical/q_cap/chips/chips.prt';

PART_NAME
 C2301 'Q_CAP_C0402-22UF,4V,20%,X6S,CH622KMEB02':;

SECTION_NUMBER 1
 '@T6G_MB_LIB.T6G(SCH_1):PAGE72_I13@PURE_QUANTA.Q_CAP(CHIPS)':
 C_PATH='@t6g_mb_lib.t6g(sch_1):page72_i13@pure_quanta.q_cap(chips)',
 P_PATH='@t6g_mb_lib.t6g(sch_1):page73_i13@pure_quanta.q_cap(chips)',
 PATH='I13',
 DRAWING='@T6G_MB_LIB.T6G(SCH_1):PAGE72',
 TOLERANCE='20%',
 MATERIAL='X6S',
 PHYS_PAGE='73',
 XY='(-8950,3725)',
 ROT='0',
 VER='1',
 PACK_TYPE='C0402',
 LOCATION='C2301',
 CDS_LIB='pure_quanta',
 CDS_PART_NAME='Q_CAP_C0402-22UF,4V,20%,X6S,CH622KMEB02',
 VOLTAGE='4V',
 PART_NUMBER='CH622KMEB02',
 VALUE='22UF',
 PRIM_FILE='./archive_libs/logical/q_cap/chips/chips.prt';

PART_NAME
 C2302 'Q_CAP_C0402-22UF,4V,20%,X6S,CH622KMEB02':;

SECTION_NUMBER 1
 '@T6G_MB_LIB.T6G(SCH_1):PAGE72_I12@PURE_QUANTA.Q_CAP(CHIPS)':
 C_PATH='@t6g_mb_lib.t6g(sch_1):page72_i12@pure_quanta.q_cap(chips)',
 P_PATH='@t6g_mb_lib.t6g(sch_1):page73_i12@pure_quanta.q_cap(chips)',
 PATH='I12',
 DRAWING='@T6G_MB_LIB.T6G(SCH_1):PAGE72',
 TOLERANCE='20%',
 MATERIAL='X6S',
 PHYS_PAGE='73',
 XY='(-8950,2925)',
 ROT='0',
 VER='1',
 PACK_TYPE='C0402',
 LOCATION='C2302',
 CDS_LIB='pure_quanta',
 CDS_PART_NAME='Q_CAP_C0402-22UF,4V,20%,X6S,CH622KMEB02',
 VOLTAGE='4V',
 PART_NUMBER='CH622KMEB02',
 VALUE='22UF',
 PRIM_FILE='./archive_libs/logical/q_cap/chips/chips.prt';

PART_NAME
 C2303 'Q_CAP_C0402-22UF,4V,20%,X6S,CH622KMEB02':;

SECTION_NUMBER 1
 '@T6G_MB_LIB.T6G(SCH_1):PAGE72_I10@PURE_QUANTA.Q_CAP(CHIPS)':
 C_PATH='@t6g_mb_lib.t6g(sch_1):page72_i10@pure_quanta.q_cap(chips)',
 P_PATH='@t6g_mb_lib.t6g(sch_1):page73_i10@pure_quanta.q_cap(chips)',
 PATH='I10',
 DRAWING='@T6G_MB_LIB.T6G(SCH_1):PAGE72',
 TOLERANCE='20%',
 MATERIAL='X6S',
 PHYS_PAGE='73',
 XY='(-8950,2125)',
 ROT='0',
 VER='1',
 PACK_TYPE='C0402',
 LOCATION='C2303',
 CDS_LIB='pure_quanta',
 CDS_PART_NAME='Q_CAP_C0402-22UF,4V,20%,X6S,CH622KMEB02',
 VOLTAGE='4V',
 PART_NUMBER='CH622KMEB02',
 VALUE='22UF',
 PRIM_FILE='./archive_libs/logical/q_cap/chips/chips.prt';

PART_NAME
 C2304 'Q_CAP_C0402-22UF,4V,20%,X6S,CH622KMEB02':;

SECTION_NUMBER 1
 '@T6G_MB_LIB.T6G(SCH_1):PAGE72_I3@PURE_QUANTA.Q_CAP(CHIPS)':
 C_PATH='@t6g_mb_lib.t6g(sch_1):page72_i3@pure_quanta.q_cap(chips)',
 P_PATH='@t6g_mb_lib.t6g(sch_1):page73_i3@pure_quanta.q_cap(chips)',
 PATH='I3',
 DRAWING='@T6G_MB_LIB.T6G(SCH_1):PAGE72',
 TOLERANCE='20%',
 MATERIAL='X6S',
 PHYS_PAGE='73',
 XY='(-8950,1325)',
 ROT='0',
 VER='1',
 PACK_TYPE='C0402',
 LOCATION='C2304',
 CDS_LIB='pure_quanta',
 CDS_PART_NAME='Q_CAP_C0402-22UF,4V,20%,X6S,CH622KMEB02',
 VOLTAGE='4V',
 PART_NUMBER='CH622KMEB02',
 VALUE='22UF',
 PRIM_FILE='./archive_libs/logical/q_cap/chips/chips.prt';

PART_NAME
 C2306 'Q_CAP_C0402-22UF,4V,20%,X6S,CH622KMEB02':;

SECTION_NUMBER 1
 '@T6G_MB_LIB.T6G(SCH_1):PAGE72_I20@PURE_QUANTA.Q_CAP(CHIPS)':
 C_PATH='@t6g_mb_lib.t6g(sch_1):page72_i20@pure_quanta.q_cap(chips)',
 P_PATH='@t6g_mb_lib.t6g(sch_1):page73_i20@pure_quanta.q_cap(chips)',
 PATH='I20',
 DRAWING='@T6G_MB_LIB.T6G(SCH_1):PAGE72',
 TOLERANCE='20%',
 MATERIAL='X6S',
 PHYS_PAGE='73',
 XY='(-8500,4500)',
 ROT='0',
 VER='1',
 PACK_TYPE='C0402',
 LOCATION='C2306',
 CDS_LIB='pure_quanta',
 CDS_PART_NAME='Q_CAP_C0402-22UF,4V,20%,X6S,CH622KMEB02',
 VOLTAGE='4V',
 PART_NUMBER='CH622KMEB02',
 VALUE='22UF',
 PRIM_FILE='./archive_libs/logical/q_cap/chips/chips.prt';

PART_NAME
 C2307 'Q_CAP_C0402-22UF,4V,20%,X6S,CH622KMEB02':;

SECTION_NUMBER 1
 '@T6G_MB_LIB.T6G(SCH_1):PAGE72_I15@PURE_QUANTA.Q_CAP(CHIPS)':
 C_PATH='@t6g_mb_lib.t6g(sch_1):page72_i15@pure_quanta.q_cap(chips)',
 P_PATH='@t6g_mb_lib.t6g(sch_1):page73_i15@pure_quanta.q_cap(chips)',
 PATH='I15',
 DRAWING='@T6G_MB_LIB.T6G(SCH_1):PAGE72',
 TOLERANCE='20%',
 MATERIAL='X6S',
 PHYS_PAGE='73',
 XY='(-8500,3725)',
 ROT='0',
 VER='1',
 PACK_TYPE='C0402',
 LOCATION='C2307',
 CDS_LIB='pure_quanta',
 CDS_PART_NAME='Q_CAP_C0402-22UF,4V,20%,X6S,CH622KMEB02',
 VOLTAGE='4V',
 PART_NUMBER='CH622KMEB02',
 VALUE='22UF',
 PRIM_FILE='./archive_libs/logical/q_cap/chips/chips.prt';

PART_NAME
 C2308 'Q_CAP_C0402-22UF,4V,20%,X6S,CH622KMEB02':;

SECTION_NUMBER 1
 '@T6G_MB_LIB.T6G(SCH_1):PAGE72_I14@PURE_QUANTA.Q_CAP(CHIPS)':
 C_PATH='@t6g_mb_lib.t6g(sch_1):page72_i14@pure_quanta.q_cap(chips)',
 P_PATH='@t6g_mb_lib.t6g(sch_1):page73_i14@pure_quanta.q_cap(chips)',
 PATH='I14',
 DRAWING='@T6G_MB_LIB.T6G(SCH_1):PAGE72',
 TOLERANCE='20%',
 MATERIAL='X6S',
 PHYS_PAGE='73',
 XY='(-8500,2925)',
 ROT='0',
 VER='1',
 PACK_TYPE='C0402',
 LOCATION='C2308',
 CDS_LIB='pure_quanta',
 CDS_PART_NAME='Q_CAP_C0402-22UF,4V,20%,X6S,CH622KMEB02',
 VOLTAGE='4V',
 PART_NUMBER='CH622KMEB02',
 VALUE='22UF',
 PRIM_FILE='./archive_libs/logical/q_cap/chips/chips.prt';

PART_NAME
 C2309 'Q_CAP_C0402-22UF,4V,20%,X6S,CH622KMEB02':;

SECTION_NUMBER 1
 '@T6G_MB_LIB.T6G(SCH_1):PAGE72_I11@PURE_QUANTA.Q_CAP(CHIPS)':
 C_PATH='@t6g_mb_lib.t6g(sch_1):page72_i11@pure_quanta.q_cap(chips)',
 P_PATH='@t6g_mb_lib.t6g(sch_1):page73_i11@pure_quanta.q_cap(chips)',
 PATH='I11',
 DRAWING='@T6G_MB_LIB.T6G(SCH_1):PAGE72',
 TOLERANCE='20%',
 MATERIAL='X6S',
 PHYS_PAGE='73',
 XY='(-8500,2125)',
 ROT='0',
 VER='1',
 PACK_TYPE='C0402',
 LOCATION='C2309',
 CDS_LIB='pure_quanta',
 CDS_PART_NAME='Q_CAP_C0402-22UF,4V,20%,X6S,CH622KMEB02',
 VOLTAGE='4V',
 PART_NUMBER='CH622KMEB02',
 VALUE='22UF',
 PRIM_FILE='./archive_libs/logical/q_cap/chips/chips.prt';

PART_NAME
 C2310 'Q_CAP_C0402-22UF,4V,20%,X6S,CH622KMEB02':;

SECTION_NUMBER 1
 '@T6G_MB_LIB.T6G(SCH_1):PAGE72_I4@PURE_QUANTA.Q_CAP(CHIPS)':
 C_PATH='@t6g_mb_lib.t6g(sch_1):page72_i4@pure_quanta.q_cap(chips)',
 P_PATH='@t6g_mb_lib.t6g(sch_1):page73_i4@pure_quanta.q_cap(chips)',
 PATH='I4',
 DRAWING='@T6G_MB_LIB.T6G(SCH_1):PAGE72',
 TOLERANCE='20%',
 MATERIAL='X6S',
 PHYS_PAGE='73',
 XY='(-8500,1325)',
 ROT='0',
 VER='1',
 PACK_TYPE='C0402',
 LOCATION='C2310',
 CDS_LIB='pure_quanta',
 CDS_PART_NAME='Q_CAP_C0402-22UF,4V,20%,X6S,CH622KMEB02',
 VOLTAGE='4V',
 PART_NUMBER='CH622KMEB02',
 VALUE='22UF',
 PRIM_FILE='./archive_libs/logical/q_cap/chips/chips.prt';

PART_NAME
 C2312 'Q_CAP_C0402-22UF,4V,20%,X6S,CH622KMEB02':;

SECTION_NUMBER 1
 '@T6G_MB_LIB.T6G(SCH_1):PAGE72_I59@PURE_QUANTA.Q_CAP(CHIPS)':
 C_PATH='@t6g_mb_lib.t6g(sch_1):page72_i59@pure_quanta.q_cap(chips)',
 P_PATH='@t6g_mb_lib.t6g(sch_1):page73_i59@pure_quanta.q_cap(chips)',
 PATH='I59',
 DRAWING='@T6G_MB_LIB.T6G(SCH_1):PAGE72',
 TOLERANCE='20%',
 MATERIAL='X6S',
 PHYS_PAGE='73',
 XY='(-8050,4500)',
 ROT='0',
 VER='1',
 PACK_TYPE='C0402',
 LOCATION='C2312',
 CDS_LIB='pure_quanta',
 CDS_PART_NAME='Q_CAP_C0402-22UF,4V,20%,X6S,CH622KMEB02',
 VOLTAGE='4V',
 PART_NUMBER='CH622KMEB02',
 VALUE='22UF',
 PRIM_FILE='./archive_libs/logical/q_cap/chips/chips.prt';

PART_NAME
 C2313 'Q_CAP_C0402-22UF,4V,20%,X6S,CH622KMEB02':;

SECTION_NUMBER 1
 '@T6G_MB_LIB.T6G(SCH_1):PAGE72_I28@PURE_QUANTA.Q_CAP(CHIPS)':
 C_PATH='@t6g_mb_lib.t6g(sch_1):page72_i28@pure_quanta.q_cap(chips)',
 P_PATH='@t6g_mb_lib.t6g(sch_1):page73_i28@pure_quanta.q_cap(chips)',
 PATH='I28',
 DRAWING='@T6G_MB_LIB.T6G(SCH_1):PAGE72',
 TOLERANCE='20%',
 MATERIAL='X6S',
 PHYS_PAGE='73',
 XY='(-8050,3725)',
 ROT='0',
 VER='1',
 PACK_TYPE='C0402',
 LOCATION='C2313',
 CDS_LIB='pure_quanta',
 CDS_PART_NAME='Q_CAP_C0402-22UF,4V,20%,X6S,CH622KMEB02',
 VOLTAGE='4V',
 PART_NUMBER='CH622KMEB02',
 VALUE='22UF',
 PRIM_FILE='./archive_libs/logical/q_cap/chips/chips.prt';

PART_NAME
 C2314 'Q_CAP_C0402-22UF,4V,20%,X6S,CH622KMEB02':;

SECTION_NUMBER 1
 '@T6G_MB_LIB.T6G(SCH_1):PAGE72_I27@PURE_QUANTA.Q_CAP(CHIPS)':
 C_PATH='@t6g_mb_lib.t6g(sch_1):page72_i27@pure_quanta.q_cap(chips)',
 P_PATH='@t6g_mb_lib.t6g(sch_1):page73_i27@pure_quanta.q_cap(chips)',
 PATH='I27',
 DRAWING='@T6G_MB_LIB.T6G(SCH_1):PAGE72',
 TOLERANCE='20%',
 MATERIAL='X6S',
 PHYS_PAGE='73',
 XY='(-8050,2925)',
 ROT='0',
 VER='1',
 PACK_TYPE='C0402',
 LOCATION='C2314',
 CDS_LIB='pure_quanta',
 CDS_PART_NAME='Q_CAP_C0402-22UF,4V,20%,X6S,CH622KMEB02',
 VOLTAGE='4V',
 PART_NUMBER='CH622KMEB02',
 VALUE='22UF',
 PRIM_FILE='./archive_libs/logical/q_cap/chips/chips.prt';

PART_NAME
 C2315 'Q_CAP_C0402-22UF,4V,20%,X6S,CH622KMEB02':;

SECTION_NUMBER 1
 '@T6G_MB_LIB.T6G(SCH_1):PAGE72_I24@PURE_QUANTA.Q_CAP(CHIPS)':
 C_PATH='@t6g_mb_lib.t6g(sch_1):page72_i24@pure_quanta.q_cap(chips)',
 P_PATH='@t6g_mb_lib.t6g(sch_1):page73_i24@pure_quanta.q_cap(chips)',
 PATH='I24',
 DRAWING='@T6G_MB_LIB.T6G(SCH_1):PAGE72',
 TOLERANCE='20%',
 MATERIAL='X6S',
 PHYS_PAGE='73',
 XY='(-8050,2125)',
 ROT='0',
 VER='1',
 PACK_TYPE='C0402',
 LOCATION='C2315',
 CDS_LIB='pure_quanta',
 CDS_PART_NAME='Q_CAP_C0402-22UF,4V,20%,X6S,CH622KMEB02',
 VOLTAGE='4V',
 PART_NUMBER='CH622KMEB02',
 VALUE='22UF',
 PRIM_FILE='./archive_libs/logical/q_cap/chips/chips.prt';

PART_NAME
 C2316 'Q_CAP_C0402-22UF,4V,20%,X6S,CH622KMEB02':;

SECTION_NUMBER 1
 '@T6G_MB_LIB.T6G(SCH_1):PAGE72_I21@PURE_QUANTA.Q_CAP(CHIPS)':
 C_PATH='@t6g_mb_lib.t6g(sch_1):page72_i21@pure_quanta.q_cap(chips)',
 P_PATH='@t6g_mb_lib.t6g(sch_1):page73_i21@pure_quanta.q_cap(chips)',
 PATH='I21',
 DRAWING='@T6G_MB_LIB.T6G(SCH_1):PAGE72',
 TOLERANCE='20%',
 MATERIAL='X6S',
 PHYS_PAGE='73',
 XY='(-8050,1325)',
 ROT='0',
 VER='1',
 PACK_TYPE='C0402',
 LOCATION='C2316',
 CDS_LIB='pure_quanta',
 CDS_PART_NAME='Q_CAP_C0402-22UF,4V,20%,X6S,CH622KMEB02',
 VOLTAGE='4V',
 PART_NUMBER='CH622KMEB02',
 VALUE='22UF',
 PRIM_FILE='./archive_libs/logical/q_cap/chips/chips.prt';

PART_NAME
 C2317 'Q_CAP_C0402-1UF,25V,10%,X6S,CH5104KEB02':
 ROOM='USB3_HUB1_CYP';

SECTION_NUMBER 1
 '@T6G_MB_LIB.T6G(SCH_1):PAGE153_I25@PURE_QUANTA.Q_CAP(CHIPS)':
 C_PATH='@t6g_mb_lib.t6g(sch_1):page153_i25@pure_quanta.q_cap(chips)',
 P_PATH='@t6g_mb_lib.t6g(sch_1):page176_i25@pure_quanta.q_cap(chips)',
 PATH='I25',
 DRAWING='@T6G_MB_LIB.T6G(SCH_1):PAGE153',
 TOLERANCE='10%',
 MATERIAL='X6S',
 PHYS_PAGE='176',
 XY='(-6350,425)',
 ROT='0',
 VER='1',
 PACK_TYPE='C0402',
 LOCATION='C2317',
 CDS_LIB='pure_quanta',
 CDS_PART_NAME='Q_CAP_C0402-1UF,25V,10%,X6S,CH5104KEB02',
 VOLTAGE='25V',
 ROOM='USB3_HUB1_CYP',
 PART_NUMBER='CH5104KEB02',
 VALUE='1UF',
 PRIM_FILE='./archive_libs/logical/q_cap/chips/chips.prt';

PART_NAME
 C2318 'Q_CAP_C0402-22UF,4V,20%,X6S,CH622KMEB02':;

SECTION_NUMBER 1
 '@T6G_MB_LIB.T6G(SCH_1):PAGE72_I60@PURE_QUANTA.Q_CAP(CHIPS)':
 C_PATH='@t6g_mb_lib.t6g(sch_1):page72_i60@pure_quanta.q_cap(chips)',
 P_PATH='@t6g_mb_lib.t6g(sch_1):page73_i60@pure_quanta.q_cap(chips)',
 PATH='I60',
 DRAWING='@T6G_MB_LIB.T6G(SCH_1):PAGE72',
 TOLERANCE='20%',
 MATERIAL='X6S',
 PHYS_PAGE='73',
 XY='(-7600,4500)',
 ROT='0',
 VER='1',
 PACK_TYPE='C0402',
 LOCATION='C2318',
 CDS_LIB='pure_quanta',
 CDS_PART_NAME='Q_CAP_C0402-22UF,4V,20%,X6S,CH622KMEB02',
 VOLTAGE='4V',
 PART_NUMBER='CH622KMEB02',
 VALUE='22UF',
 PRIM_FILE='./archive_libs/logical/q_cap/chips/chips.prt';

PART_NAME
 C2319 'Q_CAP_C0402-22UF,4V,20%,X6S,CH622KMEB02':;

SECTION_NUMBER 1
 '@T6G_MB_LIB.T6G(SCH_1):PAGE72_I31@PURE_QUANTA.Q_CAP(CHIPS)':
 C_PATH='@t6g_mb_lib.t6g(sch_1):page72_i31@pure_quanta.q_cap(chips)',
 P_PATH='@t6g_mb_lib.t6g(sch_1):page73_i31@pure_quanta.q_cap(chips)',
 PATH='I31',
 DRAWING='@T6G_MB_LIB.T6G(SCH_1):PAGE72',
 TOLERANCE='20%',
 MATERIAL='X6S',
 PHYS_PAGE='73',
 XY='(-7600,3725)',
 ROT='0',
 VER='1',
 PACK_TYPE='C0402',
 LOCATION='C2319',
 CDS_LIB='pure_quanta',
 CDS_PART_NAME='Q_CAP_C0402-22UF,4V,20%,X6S,CH622KMEB02',
 VOLTAGE='4V',
 PART_NUMBER='CH622KMEB02',
 VALUE='22UF',
 PRIM_FILE='./archive_libs/logical/q_cap/chips/chips.prt';

PART_NAME
 C2320 'Q_CAP_C0402-22UF,4V,20%,X6S,CH622KMEB02':;

SECTION_NUMBER 1
 '@T6G_MB_LIB.T6G(SCH_1):PAGE72_I29@PURE_QUANTA.Q_CAP(CHIPS)':
 C_PATH='@t6g_mb_lib.t6g(sch_1):page72_i29@pure_quanta.q_cap(chips)',
 P_PATH='@t6g_mb_lib.t6g(sch_1):page73_i29@pure_quanta.q_cap(chips)',
 PATH='I29',
 DRAWING='@T6G_MB_LIB.T6G(SCH_1):PAGE72',
 TOLERANCE='20%',
 MATERIAL='X6S',
 PHYS_PAGE='73',
 XY='(-7600,2925)',
 ROT='0',
 VER='1',
 PACK_TYPE='C0402',
 LOCATION='C2320',
 CDS_LIB='pure_quanta',
 CDS_PART_NAME='Q_CAP_C0402-22UF,4V,20%,X6S,CH622KMEB02',
 VOLTAGE='4V',
 PART_NUMBER='CH622KMEB02',
 VALUE='22UF',
 PRIM_FILE='./archive_libs/logical/q_cap/chips/chips.prt';

PART_NAME
 C2321 'Q_CAP_C0402-22UF,4V,20%,X6S,CH622KMEB02':;

SECTION_NUMBER 1
 '@T6G_MB_LIB.T6G(SCH_1):PAGE72_I25@PURE_QUANTA.Q_CAP(CHIPS)':
 C_PATH='@t6g_mb_lib.t6g(sch_1):page72_i25@pure_quanta.q_cap(chips)',
 P_PATH='@t6g_mb_lib.t6g(sch_1):page73_i25@pure_quanta.q_cap(chips)',
 PATH='I25',
 DRAWING='@T6G_MB_LIB.T6G(SCH_1):PAGE72',
 TOLERANCE='20%',
 MATERIAL='X6S',
 PHYS_PAGE='73',
 XY='(-7600,2125)',
 ROT='0',
 VER='1',
 PACK_TYPE='C0402',
 LOCATION='C2321',
 CDS_LIB='pure_quanta',
 CDS_PART_NAME='Q_CAP_C0402-22UF,4V,20%,X6S,CH622KMEB02',
 VOLTAGE='4V',
 PART_NUMBER='CH622KMEB02',
 VALUE='22UF',
 PRIM_FILE='./archive_libs/logical/q_cap/chips/chips.prt';

PART_NAME
 C2322 'Q_CAP_C0402-22UF,4V,20%,X6S,CH622KMEB02':;

SECTION_NUMBER 1
 '@T6G_MB_LIB.T6G(SCH_1):PAGE72_I23@PURE_QUANTA.Q_CAP(CHIPS)':
 C_PATH='@t6g_mb_lib.t6g(sch_1):page72_i23@pure_quanta.q_cap(chips)',
 P_PATH='@t6g_mb_lib.t6g(sch_1):page73_i23@pure_quanta.q_cap(chips)',
 PATH='I23',
 DRAWING='@T6G_MB_LIB.T6G(SCH_1):PAGE72',
 TOLERANCE='20%',
 MATERIAL='X6S',
 PHYS_PAGE='73',
 XY='(-7600,1325)',
 ROT='0',
 VER='1',
 PACK_TYPE='C0402',
 LOCATION='C2322',
 CDS_LIB='pure_quanta',
 CDS_PART_NAME='Q_CAP_C0402-22UF,4V,20%,X6S,CH622KMEB02',
 VOLTAGE='4V',
 PART_NUMBER='CH622KMEB02',
 VALUE='22UF',
 PRIM_FILE='./archive_libs/logical/q_cap/chips/chips.prt';

PART_NAME
 C2324 'Q_CAP_C0402-22UF,4V,20%,X6S,CH622KMEB02':;

SECTION_NUMBER 1
 '@T6G_MB_LIB.T6G(SCH_1):PAGE72_I61@PURE_QUANTA.Q_CAP(CHIPS)':
 C_PATH='@t6g_mb_lib.t6g(sch_1):page72_i61@pure_quanta.q_cap(chips)',
 P_PATH='@t6g_mb_lib.t6g(sch_1):page73_i61@pure_quanta.q_cap(chips)',
 PATH='I61',
 DRAWING='@T6G_MB_LIB.T6G(SCH_1):PAGE72',
 TOLERANCE='20%',
 MATERIAL='X6S',
 PHYS_PAGE='73',
 XY='(-7150,4500)',
 ROT='0',
 VER='1',
 PACK_TYPE='C0402',
 LOCATION='C2324',
 CDS_LIB='pure_quanta',
 CDS_PART_NAME='Q_CAP_C0402-22UF,4V,20%,X6S,CH622KMEB02',
 VOLTAGE='4V',
 PART_NUMBER='CH622KMEB02',
 VALUE='22UF',
 PRIM_FILE='./archive_libs/logical/q_cap/chips/chips.prt';

PART_NAME
 C2325 'Q_CAP_C0402-22UF,4V,20%,X6S,CH622KMEB02':;

SECTION_NUMBER 1
 '@T6G_MB_LIB.T6G(SCH_1):PAGE72_I32@PURE_QUANTA.Q_CAP(CHIPS)':
 C_PATH='@t6g_mb_lib.t6g(sch_1):page72_i32@pure_quanta.q_cap(chips)',
 P_PATH='@t6g_mb_lib.t6g(sch_1):page73_i32@pure_quanta.q_cap(chips)',
 PATH='I32',
 DRAWING='@T6G_MB_LIB.T6G(SCH_1):PAGE72',
 TOLERANCE='20%',
 MATERIAL='X6S',
 PHYS_PAGE='73',
 XY='(-7150,3725)',
 ROT='0',
 VER='1',
 PACK_TYPE='C0402',
 LOCATION='C2325',
 CDS_LIB='pure_quanta',
 CDS_PART_NAME='Q_CAP_C0402-22UF,4V,20%,X6S,CH622KMEB02',
 VOLTAGE='4V',
 PART_NUMBER='CH622KMEB02',
 VALUE='22UF',
 PRIM_FILE='./archive_libs/logical/q_cap/chips/chips.prt';

PART_NAME
 C2326 'Q_CAP_C0402-22UF,4V,20%,X6S,CH622KMEB02':;

SECTION_NUMBER 1
 '@T6G_MB_LIB.T6G(SCH_1):PAGE72_I30@PURE_QUANTA.Q_CAP(CHIPS)':
 C_PATH='@t6g_mb_lib.t6g(sch_1):page72_i30@pure_quanta.q_cap(chips)',
 P_PATH='@t6g_mb_lib.t6g(sch_1):page73_i30@pure_quanta.q_cap(chips)',
 PATH='I30',
 DRAWING='@T6G_MB_LIB.T6G(SCH_1):PAGE72',
 TOLERANCE='20%',
 MATERIAL='X6S',
 PHYS_PAGE='73',
 XY='(-7150,2925)',
 ROT='0',
 VER='1',
 PACK_TYPE='C0402',
 LOCATION='C2326',
 CDS_LIB='pure_quanta',
 CDS_PART_NAME='Q_CAP_C0402-22UF,4V,20%,X6S,CH622KMEB02',
 VOLTAGE='4V',
 PART_NUMBER='CH622KMEB02',
 VALUE='22UF',
 PRIM_FILE='./archive_libs/logical/q_cap/chips/chips.prt';

PART_NAME
 C2327 'Q_CAP_C0402-22UF,4V,20%,X6S,CH622KMEB02':;

SECTION_NUMBER 1
 '@T6G_MB_LIB.T6G(SCH_1):PAGE72_I26@PURE_QUANTA.Q_CAP(CHIPS)':
 C_PATH='@t6g_mb_lib.t6g(sch_1):page72_i26@pure_quanta.q_cap(chips)',
 P_PATH='@t6g_mb_lib.t6g(sch_1):page73_i26@pure_quanta.q_cap(chips)',
 PATH='I26',
 DRAWING='@T6G_MB_LIB.T6G(SCH_1):PAGE72',
 TOLERANCE='20%',
 MATERIAL='X6S',
 PHYS_PAGE='73',
 XY='(-7150,2125)',
 ROT='0',
 VER='1',
 PACK_TYPE='C0402',
 LOCATION='C2327',
 CDS_LIB='pure_quanta',
 CDS_PART_NAME='Q_CAP_C0402-22UF,4V,20%,X6S,CH622KMEB02',
 VOLTAGE='4V',
 PART_NUMBER='CH622KMEB02',
 VALUE='22UF',
 PRIM_FILE='./archive_libs/logical/q_cap/chips/chips.prt';

PART_NAME
 C2328 'Q_CAP_C0402-10UF,6.3V,20%,X6S,CH6101MEB01':;

SECTION_NUMBER 1
 '@T6G_MB_LIB.T6G(SCH_1):PAGE160_I71@PURE_QUANTA.Q_CAP(CHIPS)':
 C_PATH='@t6g_mb_lib.t6g(sch_1):page160_i71@pure_quanta.q_cap(chips)',
 P_PATH='@t6g_mb_lib.t6g(sch_1):page182_i71@pure_quanta.q_cap(chips)',
 PATH='I71',
 DRAWING='@T6G_MB_LIB.T6G(SCH_1):PAGE160',
 TOLERANCE='20%',
 MATERIAL='X6S',
 PHYS_PAGE='182',
 XY='(-4925,5525)',
 ROT='0',
 VER='1',
 PACK_TYPE='C0402',
 LOCATION='C2328',
 CDS_LIB='pure_quanta',
 CDS_PART_NAME='Q_CAP_C0402-10UF,6.3V,20%,X6S,CH6101MEB01',
 VOLTAGE='6.3V',
 PART_NUMBER='CH6101MEB01',
 VALUE='10UF',
 PRIM_FILE='./archive_libs/logical/q_cap/chips/chips.prt';

PART_NAME
 C2329 'Q_CAP_0402-0.1UF,25V,10%,X7R,CH4104K1B00':;

SECTION_NUMBER 1
 '@T6G_MB_LIB.T6G(SCH_1):PAGE160_I40@PURE_QUANTA.Q_CAP(CHIPS)':
 C_PATH='@t6g_mb_lib.t6g(sch_1):page160_i40@pure_quanta.q_cap(chips)',
 P_PATH='@t6g_mb_lib.t6g(sch_1):page182_i40@pure_quanta.q_cap(chips)',
 PATH='I40',
 DRAWING='@T6G_MB_LIB.T6G(SCH_1):PAGE160',
 TOLERANCE='10%',
 MATERIAL='X7R',
 PHYS_PAGE='182',
 XY='(-4575,5525)',
 ROT='0',
 VER='1',
 PACK_TYPE='0402',
 LOCATION='C2329',
 CDS_LIB='pure_quanta',
 CDS_PART_NAME='Q_CAP_0402-0.1UF,25V,10%,X7R,CH4104K1B00',
 VOLTAGE='25V',
 PART_NUMBER='CH4104K1B00',
 VALUE='0.1UF',
 PRIM_FILE='./archive_libs/logical/q_cap/chips/chips.prt';

PART_NAME
 C2330 'Q_CAP_C0402-22UF,4V,20%,X6S,CH622KMEB02':;

SECTION_NUMBER 1
 '@T6G_MB_LIB.T6G(SCH_1):PAGE72_I62@PURE_QUANTA.Q_CAP(CHIPS)':
 C_PATH='@t6g_mb_lib.t6g(sch_1):page72_i62@pure_quanta.q_cap(chips)',
 P_PATH='@t6g_mb_lib.t6g(sch_1):page73_i62@pure_quanta.q_cap(chips)',
 PATH='I62',
 DRAWING='@T6G_MB_LIB.T6G(SCH_1):PAGE72',
 TOLERANCE='20%',
 MATERIAL='X6S',
 PHYS_PAGE='73',
 XY='(-6700,4500)',
 ROT='0',
 VER='1',
 PACK_TYPE='C0402',
 LOCATION='C2330',
 CDS_LIB='pure_quanta',
 CDS_PART_NAME='Q_CAP_C0402-22UF,4V,20%,X6S,CH622KMEB02',
 VOLTAGE='4V',
 PART_NUMBER='CH622KMEB02',
 VALUE='22UF',
 PRIM_FILE='./archive_libs/logical/q_cap/chips/chips.prt';

PART_NAME
 C2331 'Q_CAP_C0402-22UF,4V,20%,X6S,CH622KMEB02':;

SECTION_NUMBER 1
 '@T6G_MB_LIB.T6G(SCH_1):PAGE72_I36@PURE_QUANTA.Q_CAP(CHIPS)':
 C_PATH='@t6g_mb_lib.t6g(sch_1):page72_i36@pure_quanta.q_cap(chips)',
 P_PATH='@t6g_mb_lib.t6g(sch_1):page73_i36@pure_quanta.q_cap(chips)',
 PATH='I36',
 DRAWING='@T6G_MB_LIB.T6G(SCH_1):PAGE72',
 TOLERANCE='20%',
 MATERIAL='X6S',
 PHYS_PAGE='73',
 XY='(-6700,3725)',
 ROT='0',
 VER='1',
 PACK_TYPE='C0402',
 LOCATION='C2331',
 CDS_LIB='pure_quanta',
 CDS_PART_NAME='Q_CAP_C0402-22UF,4V,20%,X6S,CH622KMEB02',
 VOLTAGE='4V',
 PART_NUMBER='CH622KMEB02',
 VALUE='22UF',
 PRIM_FILE='./archive_libs/logical/q_cap/chips/chips.prt';

PART_NAME
 C2332 'Q_CAP_C0402-22UF,4V,20%,X6S,CH622KMEB02':;

SECTION_NUMBER 1
 '@T6G_MB_LIB.T6G(SCH_1):PAGE72_I35@PURE_QUANTA.Q_CAP(CHIPS)':
 C_PATH='@t6g_mb_lib.t6g(sch_1):page72_i35@pure_quanta.q_cap(chips)',
 P_PATH='@t6g_mb_lib.t6g(sch_1):page73_i35@pure_quanta.q_cap(chips)',
 PATH='I35',
 DRAWING='@T6G_MB_LIB.T6G(SCH_1):PAGE72',
 TOLERANCE='20%',
 MATERIAL='X6S',
 PHYS_PAGE='73',
 XY='(-6700,2925)',
 ROT='0',
 VER='1',
 PACK_TYPE='C0402',
 LOCATION='C2332',
 CDS_LIB='pure_quanta',
 CDS_PART_NAME='Q_CAP_C0402-22UF,4V,20%,X6S,CH622KMEB02',
 VOLTAGE='4V',
 PART_NUMBER='CH622KMEB02',
 VALUE='22UF',
 PRIM_FILE='./archive_libs/logical/q_cap/chips/chips.prt';

PART_NAME
 C2333 'Q_CAP_C0402-22UF,4V,20%,X6S,CH622KMEB02':;

SECTION_NUMBER 1
 '@T6G_MB_LIB.T6G(SCH_1):PAGE72_I33@PURE_QUANTA.Q_CAP(CHIPS)':
 C_PATH='@t6g_mb_lib.t6g(sch_1):page72_i33@pure_quanta.q_cap(chips)',
 P_PATH='@t6g_mb_lib.t6g(sch_1):page73_i33@pure_quanta.q_cap(chips)',
 PATH='I33',
 DRAWING='@T6G_MB_LIB.T6G(SCH_1):PAGE72',
 TOLERANCE='20%',
 MATERIAL='X6S',
 PHYS_PAGE='73',
 XY='(-6700,2125)',
 ROT='0',
 VER='1',
 PACK_TYPE='C0402',
 LOCATION='C2333',
 CDS_LIB='pure_quanta',
 CDS_PART_NAME='Q_CAP_C0402-22UF,4V,20%,X6S,CH622KMEB02',
 VOLTAGE='4V',
 PART_NUMBER='CH622KMEB02',
 VALUE='22UF',
 PRIM_FILE='./archive_libs/logical/q_cap/chips/chips.prt';

PART_NAME
 C2334 'Q_CAP_0402-0.1UF,25V,10%,X7R,CH4104K1B00':;

SECTION_NUMBER 1
 '@T6G_MB_LIB.T6G(SCH_1):PAGE160_I20@PURE_QUANTA.Q_CAP(CHIPS)':
 C_PATH='@t6g_mb_lib.t6g(sch_1):page160_i20@pure_quanta.q_cap(chips)',
 P_PATH='@t6g_mb_lib.t6g(sch_1):page182_i20@pure_quanta.q_cap(chips)',
 PATH='I20',
 DRAWING='@T6G_MB_LIB.T6G(SCH_1):PAGE160',
 TOLERANCE='10%',
 MATERIAL='X7R',
 PHYS_PAGE='182',
 XY='(-7150,5875)',
 ROT='0',
 VER='1',
 PACK_TYPE='0402',
 LOCATION='C2334',
 CDS_LIB='pure_quanta',
 CDS_PART_NAME='Q_CAP_0402-0.1UF,25V,10%,X7R,CH4104K1B00',
 VOLTAGE='25V',
 PART_NUMBER='CH4104K1B00',
 VALUE='0.1UF',
 PRIM_FILE='./archive_libs/logical/q_cap/chips/chips.prt';

PART_NAME
 C2335 'Q_CAP_C0402-22UF,4V,20%,X6S,CH622KMEB02':;

SECTION_NUMBER 1
 '@T6G_MB_LIB.T6G(SCH_1):PAGE72_I63@PURE_QUANTA.Q_CAP(CHIPS)':
 C_PATH='@t6g_mb_lib.t6g(sch_1):page72_i63@pure_quanta.q_cap(chips)',
 P_PATH='@t6g_mb_lib.t6g(sch_1):page73_i63@pure_quanta.q_cap(chips)',
 PATH='I63',
 DRAWING='@T6G_MB_LIB.T6G(SCH_1):PAGE72',
 TOLERANCE='20%',
 MATERIAL='X6S',
 PHYS_PAGE='73',
 XY='(-6250,4500)',
 ROT='0',
 VER='1',
 PACK_TYPE='C0402',
 LOCATION='C2335',
 CDS_LIB='pure_quanta',
 CDS_PART_NAME='Q_CAP_C0402-22UF,4V,20%,X6S,CH622KMEB02',
 VOLTAGE='4V',
 PART_NUMBER='CH622KMEB02',
 VALUE='22UF',
 PRIM_FILE='./archive_libs/logical/q_cap/chips/chips.prt';

PART_NAME
 C2336 'Q_CAP_C0402-22UF,4V,20%,X6S,CH622KMEB02':;

SECTION_NUMBER 1
 '@T6G_MB_LIB.T6G(SCH_1):PAGE72_I38@PURE_QUANTA.Q_CAP(CHIPS)':
 C_PATH='@t6g_mb_lib.t6g(sch_1):page72_i38@pure_quanta.q_cap(chips)',
 P_PATH='@t6g_mb_lib.t6g(sch_1):page73_i38@pure_quanta.q_cap(chips)',
 PATH='I38',
 DRAWING='@T6G_MB_LIB.T6G(SCH_1):PAGE72',
 TOLERANCE='20%',
 MATERIAL='X6S',
 PHYS_PAGE='73',
 XY='(-6250,3725)',
 ROT='0',
 VER='1',
 PACK_TYPE='C0402',
 LOCATION='C2336',
 CDS_LIB='pure_quanta',
 CDS_PART_NAME='Q_CAP_C0402-22UF,4V,20%,X6S,CH622KMEB02',
 VOLTAGE='4V',
 PART_NUMBER='CH622KMEB02',
 VALUE='22UF',
 PRIM_FILE='./archive_libs/logical/q_cap/chips/chips.prt';

PART_NAME
 C2337 'Q_CAP_C0402-22UF,4V,20%,X6S,CH622KMEB02':;

SECTION_NUMBER 1
 '@T6G_MB_LIB.T6G(SCH_1):PAGE72_I37@PURE_QUANTA.Q_CAP(CHIPS)':
 C_PATH='@t6g_mb_lib.t6g(sch_1):page72_i37@pure_quanta.q_cap(chips)',
 P_PATH='@t6g_mb_lib.t6g(sch_1):page73_i37@pure_quanta.q_cap(chips)',
 PATH='I37',
 DRAWING='@T6G_MB_LIB.T6G(SCH_1):PAGE72',
 TOLERANCE='20%',
 MATERIAL='X6S',
 PHYS_PAGE='73',
 XY='(-6250,2925)',
 ROT='0',
 VER='1',
 PACK_TYPE='C0402',
 LOCATION='C2337',
 CDS_LIB='pure_quanta',
 CDS_PART_NAME='Q_CAP_C0402-22UF,4V,20%,X6S,CH622KMEB02',
 VOLTAGE='4V',
 PART_NUMBER='CH622KMEB02',
 VALUE='22UF',
 PRIM_FILE='./archive_libs/logical/q_cap/chips/chips.prt';

PART_NAME
 C2338 'Q_CAP_C0402-22UF,4V,20%,X6S,CH622KMEB02':;

SECTION_NUMBER 1
 '@T6G_MB_LIB.T6G(SCH_1):PAGE72_I34@PURE_QUANTA.Q_CAP(CHIPS)':
 C_PATH='@t6g_mb_lib.t6g(sch_1):page72_i34@pure_quanta.q_cap(chips)',
 P_PATH='@t6g_mb_lib.t6g(sch_1):page73_i34@pure_quanta.q_cap(chips)',
 PATH='I34',
 DRAWING='@T6G_MB_LIB.T6G(SCH_1):PAGE72',
 TOLERANCE='20%',
 MATERIAL='X6S',
 PHYS_PAGE='73',
 XY='(-6250,2125)',
 ROT='0',
 VER='1',
 PACK_TYPE='C0402',
 LOCATION='C2338',
 CDS_LIB='pure_quanta',
 CDS_PART_NAME='Q_CAP_C0402-22UF,4V,20%,X6S,CH622KMEB02',
 VOLTAGE='4V',
 PART_NUMBER='CH622KMEB02',
 VALUE='22UF',
 PRIM_FILE='./archive_libs/logical/q_cap/chips/chips.prt';

PART_NAME
 C2339 'Q_CAP_0402-0.1UF,25V,10%,X7R,CH4104K1B00':;

SECTION_NUMBER 1
 '@T6G_MB_LIB.T6G(SCH_1):PAGE160_I47@PURE_QUANTA.Q_CAP(CHIPS)':
 C_PATH='@t6g_mb_lib.t6g(sch_1):page160_i47@pure_quanta.q_cap(chips)',
 P_PATH='@t6g_mb_lib.t6g(sch_1):page182_i47@pure_quanta.q_cap(chips)',
 PATH='I47',
 DRAWING='@T6G_MB_LIB.T6G(SCH_1):PAGE160',
 TOLERANCE='10%',
 MATERIAL='X7R',
 PHYS_PAGE='182',
 XY='(-3550,5525)',
 ROT='0',
 VER='1',
 PACK_TYPE='0402',
 LOCATION='C2339',
 CDS_LIB='pure_quanta',
 CDS_PART_NAME='Q_CAP_0402-0.1UF,25V,10%,X7R,CH4104K1B00',
 VOLTAGE='25V',
 PART_NUMBER='CH4104K1B00',
 VALUE='0.1UF',
 PRIM_FILE='./archive_libs/logical/q_cap/chips/chips.prt';

PART_NAME
 C2340 'Q_CAP_C0402-22UF,4V,20%,X6S,CH622KMEB02':;

SECTION_NUMBER 1
 '@T6G_MB_LIB.T6G(SCH_1):PAGE72_I64@PURE_QUANTA.Q_CAP(CHIPS)':
 C_PATH='@t6g_mb_lib.t6g(sch_1):page72_i64@pure_quanta.q_cap(chips)',
 P_PATH='@t6g_mb_lib.t6g(sch_1):page73_i64@pure_quanta.q_cap(chips)',
 PATH='I64',
 DRAWING='@T6G_MB_LIB.T6G(SCH_1):PAGE72',
 TOLERANCE='20%',
 MATERIAL='X6S',
 PHYS_PAGE='73',
 XY='(-5800,4500)',
 ROT='0',
 VER='1',
 PACK_TYPE='C0402',
 LOCATION='C2340',
 CDS_LIB='pure_quanta',
 CDS_PART_NAME='Q_CAP_C0402-22UF,4V,20%,X6S,CH622KMEB02',
 VOLTAGE='4V',
 PART_NUMBER='CH622KMEB02',
 VALUE='22UF',
 PRIM_FILE='./archive_libs/logical/q_cap/chips/chips.prt';

PART_NAME
 C2341 'Q_CAP_C0402-22UF,4V,20%,X6S,CH622KMEB02':;

SECTION_NUMBER 1
 '@T6G_MB_LIB.T6G(SCH_1):PAGE72_I47@PURE_QUANTA.Q_CAP(CHIPS)':
 C_PATH='@t6g_mb_lib.t6g(sch_1):page72_i47@pure_quanta.q_cap(chips)',
 P_PATH='@t6g_mb_lib.t6g(sch_1):page73_i47@pure_quanta.q_cap(chips)',
 PATH='I47',
 DRAWING='@T6G_MB_LIB.T6G(SCH_1):PAGE72',
 TOLERANCE='20%',
 MATERIAL='X6S',
 PHYS_PAGE='73',
 XY='(-5800,3725)',
 ROT='0',
 VER='1',
 PACK_TYPE='C0402',
 LOCATION='C2341',
 CDS_LIB='pure_quanta',
 CDS_PART_NAME='Q_CAP_C0402-22UF,4V,20%,X6S,CH622KMEB02',
 VOLTAGE='4V',
 PART_NUMBER='CH622KMEB02',
 VALUE='22UF',
 PRIM_FILE='./archive_libs/logical/q_cap/chips/chips.prt';

PART_NAME
 C2342 'Q_CAP_C0402-22UF,4V,20%,X6S,CH622KMEB02':;

SECTION_NUMBER 1
 '@T6G_MB_LIB.T6G(SCH_1):PAGE72_I46@PURE_QUANTA.Q_CAP(CHIPS)':
 C_PATH='@t6g_mb_lib.t6g(sch_1):page72_i46@pure_quanta.q_cap(chips)',
 P_PATH='@t6g_mb_lib.t6g(sch_1):page73_i46@pure_quanta.q_cap(chips)',
 PATH='I46',
 DRAWING='@T6G_MB_LIB.T6G(SCH_1):PAGE72',
 TOLERANCE='20%',
 MATERIAL='X6S',
 PHYS_PAGE='73',
 XY='(-5800,2925)',
 ROT='0',
 VER='1',
 PACK_TYPE='C0402',
 LOCATION='C2342',
 CDS_LIB='pure_quanta',
 CDS_PART_NAME='Q_CAP_C0402-22UF,4V,20%,X6S,CH622KMEB02',
 VOLTAGE='4V',
 PART_NUMBER='CH622KMEB02',
 VALUE='22UF',
 PRIM_FILE='./archive_libs/logical/q_cap/chips/chips.prt';

PART_NAME
 C2343 'Q_CAP_C0402-22UF,4V,20%,X6S,CH622KMEB02':;

SECTION_NUMBER 1
 '@T6G_MB_LIB.T6G(SCH_1):PAGE72_I42@PURE_QUANTA.Q_CAP(CHIPS)':
 C_PATH='@t6g_mb_lib.t6g(sch_1):page72_i42@pure_quanta.q_cap(chips)',
 P_PATH='@t6g_mb_lib.t6g(sch_1):page73_i42@pure_quanta.q_cap(chips)',
 PATH='I42',
 DRAWING='@T6G_MB_LIB.T6G(SCH_1):PAGE72',
 TOLERANCE='20%',
 MATERIAL='X6S',
 PHYS_PAGE='73',
 XY='(-5800,2125)',
 ROT='0',
 VER='1',
 PACK_TYPE='C0402',
 LOCATION='C2343',
 CDS_LIB='pure_quanta',
 CDS_PART_NAME='Q_CAP_C0402-22UF,4V,20%,X6S,CH622KMEB02',
 VOLTAGE='4V',
 PART_NUMBER='CH622KMEB02',
 VALUE='22UF',
 PRIM_FILE='./archive_libs/logical/q_cap/chips/chips.prt';

PART_NAME
 C2344 'Q_CAP_0402-0.1UF,25V,10%,X7R,CH4104K1B00':;

SECTION_NUMBER 1
 '@T6G_MB_LIB.T6G(SCH_1):PAGE337_I53@PURE_QUANTA.Q_CAP(CHIPS)':
 C_PATH='@t6g_mb_lib.t6g(sch_1):page337_i53@pure_quanta.q_cap(chips)',
 P_PATH='@t6g_mb_lib.t6g(sch_1):page133_i53@pure_quanta.q_cap(chips)',
 PATH='I53',
 DRAWING='@T6G_MB_LIB.T6G(SCH_1):PAGE337',
 TOLERANCE='10%',
 MATERIAL='X7R',
 PHYS_PAGE='133',
 XY='(-2525,3550)',
 ROT='0',
 VER='1',
 PACK_TYPE='0402',
 LOCATION='C2344',
 CDS_LIB='pure_quanta',
 CDS_PART_NAME='Q_CAP_0402-0.1UF,25V,10%,X7R,CH4104K1B00',
 VOLTAGE='25V',
 PART_NUMBER='CH4104K1B00',
 VALUE='0.1UF',
 PRIM_FILE='./archive_libs/logical/q_cap/chips/chips.prt';

PART_NAME
 C2345 'Q_CAP_C0402-22UF,4V,20%,X6S,CH622KMEB02':;

SECTION_NUMBER 1
 '@T6G_MB_LIB.T6G(SCH_1):PAGE72_I66@PURE_QUANTA.Q_CAP(CHIPS)':
 C_PATH='@t6g_mb_lib.t6g(sch_1):page72_i66@pure_quanta.q_cap(chips)',
 P_PATH='@t6g_mb_lib.t6g(sch_1):page73_i66@pure_quanta.q_cap(chips)',
 PATH='I66',
 DRAWING='@T6G_MB_LIB.T6G(SCH_1):PAGE72',
 TOLERANCE='20%',
 MATERIAL='X6S',
 PHYS_PAGE='73',
 XY='(-5400,4500)',
 ROT='0',
 VER='1',
 PACK_TYPE='C0402',
 LOCATION='C2345',
 CDS_LIB='pure_quanta',
 CDS_PART_NAME='Q_CAP_C0402-22UF,4V,20%,X6S,CH622KMEB02',
 VOLTAGE='4V',
 PART_NUMBER='CH622KMEB02',
 VALUE='22UF',
 PRIM_FILE='./archive_libs/logical/q_cap/chips/chips.prt';

PART_NAME
 C2346 'Q_CAP_C0402-22UF,4V,20%,X6S,CH622KMEB02':;

SECTION_NUMBER 1
 '@T6G_MB_LIB.T6G(SCH_1):PAGE72_I50@PURE_QUANTA.Q_CAP(CHIPS)':
 C_PATH='@t6g_mb_lib.t6g(sch_1):page72_i50@pure_quanta.q_cap(chips)',
 P_PATH='@t6g_mb_lib.t6g(sch_1):page73_i50@pure_quanta.q_cap(chips)',
 PATH='I50',
 DRAWING='@T6G_MB_LIB.T6G(SCH_1):PAGE72',
 TOLERANCE='20%',
 MATERIAL='X6S',
 PHYS_PAGE='73',
 XY='(-5400,3725)',
 ROT='0',
 VER='1',
 PACK_TYPE='C0402',
 LOCATION='C2346',
 CDS_LIB='pure_quanta',
 CDS_PART_NAME='Q_CAP_C0402-22UF,4V,20%,X6S,CH622KMEB02',
 VOLTAGE='4V',
 PART_NUMBER='CH622KMEB02',
 VALUE='22UF',
 PRIM_FILE='./archive_libs/logical/q_cap/chips/chips.prt';

PART_NAME
 C2347 'Q_CAP_C0402-22UF,4V,20%,X6S,CH622KMEB02':;

SECTION_NUMBER 1
 '@T6G_MB_LIB.T6G(SCH_1):PAGE72_I48@PURE_QUANTA.Q_CAP(CHIPS)':
 C_PATH='@t6g_mb_lib.t6g(sch_1):page72_i48@pure_quanta.q_cap(chips)',
 P_PATH='@t6g_mb_lib.t6g(sch_1):page73_i48@pure_quanta.q_cap(chips)',
 PATH='I48',
 DRAWING='@T6G_MB_LIB.T6G(SCH_1):PAGE72',
 TOLERANCE='20%',
 MATERIAL='X6S',
 PHYS_PAGE='73',
 XY='(-5400,2925)',
 ROT='0',
 VER='1',
 PACK_TYPE='C0402',
 LOCATION='C2347',
 CDS_LIB='pure_quanta',
 CDS_PART_NAME='Q_CAP_C0402-22UF,4V,20%,X6S,CH622KMEB02',
 VOLTAGE='4V',
 PART_NUMBER='CH622KMEB02',
 VALUE='22UF',
 PRIM_FILE='./archive_libs/logical/q_cap/chips/chips.prt';

PART_NAME
 C2348 'Q_CAP_C0402-22UF,4V,20%,X6S,CH622KMEB02':;

SECTION_NUMBER 1
 '@T6G_MB_LIB.T6G(SCH_1):PAGE72_I44@PURE_QUANTA.Q_CAP(CHIPS)':
 C_PATH='@t6g_mb_lib.t6g(sch_1):page72_i44@pure_quanta.q_cap(chips)',
 P_PATH='@t6g_mb_lib.t6g(sch_1):page73_i44@pure_quanta.q_cap(chips)',
 PATH='I44',
 DRAWING='@T6G_MB_LIB.T6G(SCH_1):PAGE72',
 TOLERANCE='20%',
 MATERIAL='X6S',
 PHYS_PAGE='73',
 XY='(-5400,2125)',
 ROT='0',
 VER='1',
 PACK_TYPE='C0402',
 LOCATION='C2348',
 CDS_LIB='pure_quanta',
 CDS_PART_NAME='Q_CAP_C0402-22UF,4V,20%,X6S,CH622KMEB02',
 VOLTAGE='4V',
 PART_NUMBER='CH622KMEB02',
 VALUE='22UF',
 PRIM_FILE='./archive_libs/logical/q_cap/chips/chips.prt';

PART_NAME
 C2350 'Q_CAP_C0402-22UF,4V,20%,X6S,CH622KMEB02':;

SECTION_NUMBER 1
 '@T6G_MB_LIB.T6G(SCH_1):PAGE72_I110@PURE_QUANTA.Q_CAP(CHIPS)':
 C_PATH='@t6g_mb_lib.t6g(sch_1):page72_i110@pure_quanta.q_cap(chips)',
 P_PATH='@t6g_mb_lib.t6g(sch_1):page73_i110@pure_quanta.q_cap(chips)',
 PATH='I110',
 DRAWING='@T6G_MB_LIB.T6G(SCH_1):PAGE72',
 TOLERANCE='20%',
 MATERIAL='X6S',
 PHYS_PAGE='73',
 XY='(-4825,4500)',
 ROT='0',
 VER='1',
 PACK_TYPE='C0402',
 LOCATION='C2350',
 CDS_LIB='pure_quanta',
 CDS_PART_NAME='Q_CAP_C0402-22UF,4V,20%,X6S,CH622KMEB02',
 VOLTAGE='4V',
 PART_NUMBER='CH622KMEB02',
 VALUE='22UF',
 PRIM_FILE='./archive_libs/logical/q_cap/chips/chips.prt';

PART_NAME
 C2351 'Q_CAP_C0402-22UF,4V,20%,X6S,CH622KMEB02':;

SECTION_NUMBER 1
 '@T6G_MB_LIB.T6G(SCH_1):PAGE72_I56@PURE_QUANTA.Q_CAP(CHIPS)':
 C_PATH='@t6g_mb_lib.t6g(sch_1):page72_i56@pure_quanta.q_cap(chips)',
 P_PATH='@t6g_mb_lib.t6g(sch_1):page73_i56@pure_quanta.q_cap(chips)',
 PATH='I56',
 DRAWING='@T6G_MB_LIB.T6G(SCH_1):PAGE72',
 TOLERANCE='20%',
 MATERIAL='X6S',
 PHYS_PAGE='73',
 XY='(-4825,3725)',
 ROT='0',
 VER='1',
 PACK_TYPE='C0402',
 LOCATION='C2351',
 CDS_LIB='pure_quanta',
 CDS_PART_NAME='Q_CAP_C0402-22UF,4V,20%,X6S,CH622KMEB02',
 VOLTAGE='4V',
 PART_NUMBER='CH622KMEB02',
 VALUE='22UF',
 PRIM_FILE='./archive_libs/logical/q_cap/chips/chips.prt';

PART_NAME
 C2352 'Q_CAP_C0402-22UF,4V,20%,X6S,CH622KMEB02':;

SECTION_NUMBER 1
 '@T6G_MB_LIB.T6G(SCH_1):PAGE72_I55@PURE_QUANTA.Q_CAP(CHIPS)':
 C_PATH='@t6g_mb_lib.t6g(sch_1):page72_i55@pure_quanta.q_cap(chips)',
 P_PATH='@t6g_mb_lib.t6g(sch_1):page73_i55@pure_quanta.q_cap(chips)',
 PATH='I55',
 DRAWING='@T6G_MB_LIB.T6G(SCH_1):PAGE72',
 TOLERANCE='20%',
 MATERIAL='X6S',
 PHYS_PAGE='73',
 XY='(-4825,2925)',
 ROT='0',
 VER='1',
 PACK_TYPE='C0402',
 LOCATION='C2352',
 CDS_LIB='pure_quanta',
 CDS_PART_NAME='Q_CAP_C0402-22UF,4V,20%,X6S,CH622KMEB02',
 VOLTAGE='4V',
 PART_NUMBER='CH622KMEB02',
 VALUE='22UF',
 PRIM_FILE='./archive_libs/logical/q_cap/chips/chips.prt';

PART_NAME
 C2353 'Q_CAP_C0402-22UF,4V,20%,X6S,CH622KMEB02':;

SECTION_NUMBER 1
 '@T6G_MB_LIB.T6G(SCH_1):PAGE72_I51@PURE_QUANTA.Q_CAP(CHIPS)':
 C_PATH='@t6g_mb_lib.t6g(sch_1):page72_i51@pure_quanta.q_cap(chips)',
 P_PATH='@t6g_mb_lib.t6g(sch_1):page73_i51@pure_quanta.q_cap(chips)',
 PATH='I51',
 DRAWING='@T6G_MB_LIB.T6G(SCH_1):PAGE72',
 TOLERANCE='20%',
 MATERIAL='X6S',
 PHYS_PAGE='73',
 XY='(-4825,2125)',
 ROT='0',
 VER='1',
 PACK_TYPE='C0402',
 LOCATION='C2353',
 CDS_LIB='pure_quanta',
 CDS_PART_NAME='Q_CAP_C0402-22UF,4V,20%,X6S,CH622KMEB02',
 VOLTAGE='4V',
 PART_NUMBER='CH622KMEB02',
 VALUE='22UF',
 PRIM_FILE='./archive_libs/logical/q_cap/chips/chips.prt';

PART_NAME
 C2354 'Q_CAP_C0402-22UF,4V,20%,X6S,CH622KMEB02':;

SECTION_NUMBER 1
 '@T6G_MB_LIB.T6G(SCH_1):PAGE72_I40@PURE_QUANTA.Q_CAP(CHIPS)':
 C_PATH='@t6g_mb_lib.t6g(sch_1):page72_i40@pure_quanta.q_cap(chips)',
 P_PATH='@t6g_mb_lib.t6g(sch_1):page73_i40@pure_quanta.q_cap(chips)',
 PATH='I40',
 DRAWING='@T6G_MB_LIB.T6G(SCH_1):PAGE72',
 TOLERANCE='20%',
 MATERIAL='X6S',
 PHYS_PAGE='73',
 XY='(-4825,1325)',
 ROT='0',
 VER='1',
 PACK_TYPE='C0402',
 LOCATION='C2354',
 CDS_LIB='pure_quanta',
 CDS_PART_NAME='Q_CAP_C0402-22UF,4V,20%,X6S,CH622KMEB02',
 VOLTAGE='4V',
 PART_NUMBER='CH622KMEB02',
 VALUE='22UF',
 PRIM_FILE='./archive_libs/logical/q_cap/chips/chips.prt';

PART_NAME
 C2356 'Q_CAP_C0402-22UF,4V,20%,X6S,CH622KMEB02':;

SECTION_NUMBER 1
 '@T6G_MB_LIB.T6G(SCH_1):PAGE72_I68@PURE_QUANTA.Q_CAP(CHIPS)':
 C_PATH='@t6g_mb_lib.t6g(sch_1):page72_i68@pure_quanta.q_cap(chips)',
 P_PATH='@t6g_mb_lib.t6g(sch_1):page73_i68@pure_quanta.q_cap(chips)',
 PATH='I68',
 DRAWING='@T6G_MB_LIB.T6G(SCH_1):PAGE72',
 TOLERANCE='20%',
 MATERIAL='X6S',
 PHYS_PAGE='73',
 XY='(-4375,4500)',
 ROT='0',
 VER='1',
 PACK_TYPE='C0402',
 LOCATION='C2356',
 CDS_LIB='pure_quanta',
 CDS_PART_NAME='Q_CAP_C0402-22UF,4V,20%,X6S,CH622KMEB02',
 VOLTAGE='4V',
 PART_NUMBER='CH622KMEB02',
 VALUE='22UF',
 PRIM_FILE='./archive_libs/logical/q_cap/chips/chips.prt';

PART_NAME
 C2357 'Q_CAP_C0402-22UF,4V,20%,X6S,CH622KMEB02':;

SECTION_NUMBER 1
 '@T6G_MB_LIB.T6G(SCH_1):PAGE72_I58@PURE_QUANTA.Q_CAP(CHIPS)':
 C_PATH='@t6g_mb_lib.t6g(sch_1):page72_i58@pure_quanta.q_cap(chips)',
 P_PATH='@t6g_mb_lib.t6g(sch_1):page73_i58@pure_quanta.q_cap(chips)',
 PATH='I58',
 DRAWING='@T6G_MB_LIB.T6G(SCH_1):PAGE72',
 TOLERANCE='20%',
 MATERIAL='X6S',
 PHYS_PAGE='73',
 XY='(-4375,3725)',
 ROT='0',
 VER='1',
 PACK_TYPE='C0402',
 LOCATION='C2357',
 CDS_LIB='pure_quanta',
 CDS_PART_NAME='Q_CAP_C0402-22UF,4V,20%,X6S,CH622KMEB02',
 VOLTAGE='4V',
 PART_NUMBER='CH622KMEB02',
 VALUE='22UF',
 PRIM_FILE='./archive_libs/logical/q_cap/chips/chips.prt';

PART_NAME
 C2358 'Q_CAP_C0402-22UF,4V,20%,X6S,CH622KMEB02':;

SECTION_NUMBER 1
 '@T6G_MB_LIB.T6G(SCH_1):PAGE72_I57@PURE_QUANTA.Q_CAP(CHIPS)':
 C_PATH='@t6g_mb_lib.t6g(sch_1):page72_i57@pure_quanta.q_cap(chips)',
 P_PATH='@t6g_mb_lib.t6g(sch_1):page73_i57@pure_quanta.q_cap(chips)',
 PATH='I57',
 DRAWING='@T6G_MB_LIB.T6G(SCH_1):PAGE72',
 TOLERANCE='20%',
 MATERIAL='X6S',
 PHYS_PAGE='73',
 XY='(-4375,2925)',
 ROT='0',
 VER='1',
 PACK_TYPE='C0402',
 LOCATION='C2358',
 CDS_LIB='pure_quanta',
 CDS_PART_NAME='Q_CAP_C0402-22UF,4V,20%,X6S,CH622KMEB02',
 VOLTAGE='4V',
 PART_NUMBER='CH622KMEB02',
 VALUE='22UF',
 PRIM_FILE='./archive_libs/logical/q_cap/chips/chips.prt';

PART_NAME
 C2359 'Q_CAP_C0402-22UF,4V,20%,X6S,CH622KMEB02':;

SECTION_NUMBER 1
 '@T6G_MB_LIB.T6G(SCH_1):PAGE72_I53@PURE_QUANTA.Q_CAP(CHIPS)':
 C_PATH='@t6g_mb_lib.t6g(sch_1):page72_i53@pure_quanta.q_cap(chips)',
 P_PATH='@t6g_mb_lib.t6g(sch_1):page73_i53@pure_quanta.q_cap(chips)',
 PATH='I53',
 DRAWING='@T6G_MB_LIB.T6G(SCH_1):PAGE72',
 TOLERANCE='20%',
 MATERIAL='X6S',
 PHYS_PAGE='73',
 XY='(-4375,2125)',
 ROT='0',
 VER='1',
 PACK_TYPE='C0402',
 LOCATION='C2359',
 CDS_LIB='pure_quanta',
 CDS_PART_NAME='Q_CAP_C0402-22UF,4V,20%,X6S,CH622KMEB02',
 VOLTAGE='4V',
 PART_NUMBER='CH622KMEB02',
 VALUE='22UF',
 PRIM_FILE='./archive_libs/logical/q_cap/chips/chips.prt';

PART_NAME
 C2360 'Q_CAP_C0402-22UF,4V,20%,X6S,CH622KMEB02':;

SECTION_NUMBER 1
 '@T6G_MB_LIB.T6G(SCH_1):PAGE72_I41@PURE_QUANTA.Q_CAP(CHIPS)':
 C_PATH='@t6g_mb_lib.t6g(sch_1):page72_i41@pure_quanta.q_cap(chips)',
 P_PATH='@t6g_mb_lib.t6g(sch_1):page73_i41@pure_quanta.q_cap(chips)',
 PATH='I41',
 DRAWING='@T6G_MB_LIB.T6G(SCH_1):PAGE72',
 TOLERANCE='20%',
 MATERIAL='X6S',
 PHYS_PAGE='73',
 XY='(-4375,1325)',
 ROT='0',
 VER='1',
 PACK_TYPE='C0402',
 LOCATION='C2360',
 CDS_LIB='pure_quanta',
 CDS_PART_NAME='Q_CAP_C0402-22UF,4V,20%,X6S,CH622KMEB02',
 VOLTAGE='4V',
 PART_NUMBER='CH622KMEB02',
 VALUE='22UF',
 PRIM_FILE='./archive_libs/logical/q_cap/chips/chips.prt';

PART_NAME
 C2362 'Q_CAP_C0402-22UF,4V,20%,X6S,CH622KMEB02':;

SECTION_NUMBER 1
 '@T6G_MB_LIB.T6G(SCH_1):PAGE72_I101@PURE_QUANTA.Q_CAP(CHIPS)':
 C_PATH='@t6g_mb_lib.t6g(sch_1):page72_i101@pure_quanta.q_cap(chips)',
 P_PATH='@t6g_mb_lib.t6g(sch_1):page73_i101@pure_quanta.q_cap(chips)',
 PATH='I101',
 DRAWING='@T6G_MB_LIB.T6G(SCH_1):PAGE72',
 TOLERANCE='20%',
 MATERIAL='X6S',
 PHYS_PAGE='73',
 XY='(-3925,4500)',
 ROT='0',
 VER='1',
 PACK_TYPE='C0402',
 LOCATION='C2362',
 CDS_LIB='pure_quanta',
 CDS_PART_NAME='Q_CAP_C0402-22UF,4V,20%,X6S,CH622KMEB02',
 VOLTAGE='4V',
 PART_NUMBER='CH622KMEB02',
 VALUE='22UF',
 PRIM_FILE='./archive_libs/logical/q_cap/chips/chips.prt';

PART_NAME
 C2363 'Q_CAP_C0402-22UF,4V,20%,X6S,CH622KMEB02':;

SECTION_NUMBER 1
 '@T6G_MB_LIB.T6G(SCH_1):PAGE72_I77@PURE_QUANTA.Q_CAP(CHIPS)':
 C_PATH='@t6g_mb_lib.t6g(sch_1):page72_i77@pure_quanta.q_cap(chips)',
 P_PATH='@t6g_mb_lib.t6g(sch_1):page73_i77@pure_quanta.q_cap(chips)',
 PATH='I77',
 DRAWING='@T6G_MB_LIB.T6G(SCH_1):PAGE72',
 TOLERANCE='20%',
 MATERIAL='X6S',
 PHYS_PAGE='73',
 XY='(-3925,3725)',
 ROT='0',
 VER='1',
 PACK_TYPE='C0402',
 LOCATION='C2363',
 CDS_LIB='pure_quanta',
 CDS_PART_NAME='Q_CAP_C0402-22UF,4V,20%,X6S,CH622KMEB02',
 VOLTAGE='4V',
 PART_NUMBER='CH622KMEB02',
 VALUE='22UF',
 PRIM_FILE='./archive_libs/logical/q_cap/chips/chips.prt';

PART_NAME
 C2364 'Q_CAP_C0402-22UF,4V,20%,X6S,CH622KMEB02':;

SECTION_NUMBER 1
 '@T6G_MB_LIB.T6G(SCH_1):PAGE72_I76@PURE_QUANTA.Q_CAP(CHIPS)':
 C_PATH='@t6g_mb_lib.t6g(sch_1):page72_i76@pure_quanta.q_cap(chips)',
 P_PATH='@t6g_mb_lib.t6g(sch_1):page73_i76@pure_quanta.q_cap(chips)',
 PATH='I76',
 DRAWING='@T6G_MB_LIB.T6G(SCH_1):PAGE72',
 TOLERANCE='20%',
 MATERIAL='X6S',
 PHYS_PAGE='73',
 XY='(-3925,2925)',
 ROT='0',
 VER='1',
 PACK_TYPE='C0402',
 LOCATION='C2364',
 CDS_LIB='pure_quanta',
 CDS_PART_NAME='Q_CAP_C0402-22UF,4V,20%,X6S,CH622KMEB02',
 VOLTAGE='4V',
 PART_NUMBER='CH622KMEB02',
 VALUE='22UF',
 PRIM_FILE='./archive_libs/logical/q_cap/chips/chips.prt';

PART_NAME
 C2365 'Q_CAP_C0402-22UF,4V,20%,X6S,CH622KMEB02':;

SECTION_NUMBER 1
 '@T6G_MB_LIB.T6G(SCH_1):PAGE72_I74@PURE_QUANTA.Q_CAP(CHIPS)':
 C_PATH='@t6g_mb_lib.t6g(sch_1):page72_i74@pure_quanta.q_cap(chips)',
 P_PATH='@t6g_mb_lib.t6g(sch_1):page73_i74@pure_quanta.q_cap(chips)',
 PATH='I74',
 DRAWING='@T6G_MB_LIB.T6G(SCH_1):PAGE72',
 TOLERANCE='20%',
 MATERIAL='X6S',
 PHYS_PAGE='73',
 XY='(-3925,2125)',
 ROT='0',
 VER='1',
 PACK_TYPE='C0402',
 LOCATION='C2365',
 CDS_LIB='pure_quanta',
 CDS_PART_NAME='Q_CAP_C0402-22UF,4V,20%,X6S,CH622KMEB02',
 VOLTAGE='4V',
 PART_NUMBER='CH622KMEB02',
 VALUE='22UF',
 PRIM_FILE='./archive_libs/logical/q_cap/chips/chips.prt';

PART_NAME
 C2366 'Q_CAP_C0402-22UF,4V,20%,X6S,CH622KMEB02':;

SECTION_NUMBER 1
 '@T6G_MB_LIB.T6G(SCH_1):PAGE72_I70@PURE_QUANTA.Q_CAP(CHIPS)':
 C_PATH='@t6g_mb_lib.t6g(sch_1):page72_i70@pure_quanta.q_cap(chips)',
 P_PATH='@t6g_mb_lib.t6g(sch_1):page73_i70@pure_quanta.q_cap(chips)',
 PATH='I70',
 DRAWING='@T6G_MB_LIB.T6G(SCH_1):PAGE72',
 TOLERANCE='20%',
 MATERIAL='X6S',
 PHYS_PAGE='73',
 XY='(-3925,1325)',
 ROT='0',
 VER='1',
 PACK_TYPE='C0402',
 LOCATION='C2366',
 CDS_LIB='pure_quanta',
 CDS_PART_NAME='Q_CAP_C0402-22UF,4V,20%,X6S,CH622KMEB02',
 VOLTAGE='4V',
 PART_NUMBER='CH622KMEB02',
 VALUE='22UF',
 PRIM_FILE='./archive_libs/logical/q_cap/chips/chips.prt';

PART_NAME
 C2368 'Q_CAP_C0402-22UF,4V,20%,X6S,CH622KMEB02':;

SECTION_NUMBER 1
 '@T6G_MB_LIB.T6G(SCH_1):PAGE72_I102@PURE_QUANTA.Q_CAP(CHIPS)':
 C_PATH='@t6g_mb_lib.t6g(sch_1):page72_i102@pure_quanta.q_cap(chips)',
 P_PATH='@t6g_mb_lib.t6g(sch_1):page73_i102@pure_quanta.q_cap(chips)',
 PATH='I102',
 DRAWING='@T6G_MB_LIB.T6G(SCH_1):PAGE72',
 TOLERANCE='20%',
 MATERIAL='X6S',
 PHYS_PAGE='73',
 XY='(-3475,4500)',
 ROT='0',
 VER='1',
 PACK_TYPE='C0402',
 LOCATION='C2368',
 CDS_LIB='pure_quanta',
 CDS_PART_NAME='Q_CAP_C0402-22UF,4V,20%,X6S,CH622KMEB02',
 VOLTAGE='4V',
 PART_NUMBER='CH622KMEB02',
 VALUE='22UF',
 PRIM_FILE='./archive_libs/logical/q_cap/chips/chips.prt';

PART_NAME
 C2369 'Q_CAP_C0402-22UF,4V,20%,X6S,CH622KMEB02':;

SECTION_NUMBER 1
 '@T6G_MB_LIB.T6G(SCH_1):PAGE72_I79@PURE_QUANTA.Q_CAP(CHIPS)':
 C_PATH='@t6g_mb_lib.t6g(sch_1):page72_i79@pure_quanta.q_cap(chips)',
 P_PATH='@t6g_mb_lib.t6g(sch_1):page73_i79@pure_quanta.q_cap(chips)',
 PATH='I79',
 DRAWING='@T6G_MB_LIB.T6G(SCH_1):PAGE72',
 TOLERANCE='20%',
 MATERIAL='X6S',
 PHYS_PAGE='73',
 XY='(-3475,3725)',
 ROT='0',
 VER='1',
 PACK_TYPE='C0402',
 LOCATION='C2369',
 CDS_LIB='pure_quanta',
 CDS_PART_NAME='Q_CAP_C0402-22UF,4V,20%,X6S,CH622KMEB02',
 VOLTAGE='4V',
 PART_NUMBER='CH622KMEB02',
 VALUE='22UF',
 PRIM_FILE='./archive_libs/logical/q_cap/chips/chips.prt';

PART_NAME
 C2370 'Q_CAP_C0402-22UF,4V,20%,X6S,CH622KMEB02':;

SECTION_NUMBER 1
 '@T6G_MB_LIB.T6G(SCH_1):PAGE72_I78@PURE_QUANTA.Q_CAP(CHIPS)':
 C_PATH='@t6g_mb_lib.t6g(sch_1):page72_i78@pure_quanta.q_cap(chips)',
 P_PATH='@t6g_mb_lib.t6g(sch_1):page73_i78@pure_quanta.q_cap(chips)',
 PATH='I78',
 DRAWING='@T6G_MB_LIB.T6G(SCH_1):PAGE72',
 TOLERANCE='20%',
 MATERIAL='X6S',
 PHYS_PAGE='73',
 XY='(-3475,2925)',
 ROT='0',
 VER='1',
 PACK_TYPE='C0402',
 LOCATION='C2370',
 CDS_LIB='pure_quanta',
 CDS_PART_NAME='Q_CAP_C0402-22UF,4V,20%,X6S,CH622KMEB02',
 VOLTAGE='4V',
 PART_NUMBER='CH622KMEB02',
 VALUE='22UF',
 PRIM_FILE='./archive_libs/logical/q_cap/chips/chips.prt';

PART_NAME
 C2371 'Q_CAP_C0402-22UF,4V,20%,X6S,CH622KMEB02':;

SECTION_NUMBER 1
 '@T6G_MB_LIB.T6G(SCH_1):PAGE72_I75@PURE_QUANTA.Q_CAP(CHIPS)':
 C_PATH='@t6g_mb_lib.t6g(sch_1):page72_i75@pure_quanta.q_cap(chips)',
 P_PATH='@t6g_mb_lib.t6g(sch_1):page73_i75@pure_quanta.q_cap(chips)',
 PATH='I75',
 DRAWING='@T6G_MB_LIB.T6G(SCH_1):PAGE72',
 TOLERANCE='20%',
 MATERIAL='X6S',
 PHYS_PAGE='73',
 XY='(-3475,2125)',
 ROT='0',
 VER='1',
 PACK_TYPE='C0402',
 LOCATION='C2371',
 CDS_LIB='pure_quanta',
 CDS_PART_NAME='Q_CAP_C0402-22UF,4V,20%,X6S,CH622KMEB02',
 VOLTAGE='4V',
 PART_NUMBER='CH622KMEB02',
 VALUE='22UF',
 PRIM_FILE='./archive_libs/logical/q_cap/chips/chips.prt';

PART_NAME
 C2372 'Q_CAP_C0402-22UF,4V,20%,X6S,CH622KMEB02':;

SECTION_NUMBER 1
 '@T6G_MB_LIB.T6G(SCH_1):PAGE72_I71@PURE_QUANTA.Q_CAP(CHIPS)':
 C_PATH='@t6g_mb_lib.t6g(sch_1):page72_i71@pure_quanta.q_cap(chips)',
 P_PATH='@t6g_mb_lib.t6g(sch_1):page73_i71@pure_quanta.q_cap(chips)',
 PATH='I71',
 DRAWING='@T6G_MB_LIB.T6G(SCH_1):PAGE72',
 TOLERANCE='20%',
 MATERIAL='X6S',
 PHYS_PAGE='73',
 XY='(-3475,1325)',
 ROT='0',
 VER='1',
 PACK_TYPE='C0402',
 LOCATION='C2372',
 CDS_LIB='pure_quanta',
 CDS_PART_NAME='Q_CAP_C0402-22UF,4V,20%,X6S,CH622KMEB02',
 VOLTAGE='4V',
 PART_NUMBER='CH622KMEB02',
 VALUE='22UF',
 PRIM_FILE='./archive_libs/logical/q_cap/chips/chips.prt';

PART_NAME
 C2374 'Q_CAP_C0402-22UF,4V,20%,X6S,CH622KMEB02':;

SECTION_NUMBER 1
 '@T6G_MB_LIB.T6G(SCH_1):PAGE72_I103@PURE_QUANTA.Q_CAP(CHIPS)':
 C_PATH='@t6g_mb_lib.t6g(sch_1):page72_i103@pure_quanta.q_cap(chips)',
 P_PATH='@t6g_mb_lib.t6g(sch_1):page73_i103@pure_quanta.q_cap(chips)',
 PATH='I103',
 DRAWING='@T6G_MB_LIB.T6G(SCH_1):PAGE72',
 TOLERANCE='20%',
 MATERIAL='X6S',
 PHYS_PAGE='73',
 XY='(-3025,4500)',
 ROT='0',
 VER='1',
 PACK_TYPE='C0402',
 LOCATION='C2374',
 CDS_LIB='pure_quanta',
 CDS_PART_NAME='Q_CAP_C0402-22UF,4V,20%,X6S,CH622KMEB02',
 VOLTAGE='4V',
 PART_NUMBER='CH622KMEB02',
 VALUE='22UF',
 PRIM_FILE='./archive_libs/logical/q_cap/chips/chips.prt';

PART_NAME
 C2375 'Q_CAP_C0402-22UF,4V,20%,X6S,CH622KMEB02':;

SECTION_NUMBER 1
 '@T6G_MB_LIB.T6G(SCH_1):PAGE72_I85@PURE_QUANTA.Q_CAP(CHIPS)':
 C_PATH='@t6g_mb_lib.t6g(sch_1):page72_i85@pure_quanta.q_cap(chips)',
 P_PATH='@t6g_mb_lib.t6g(sch_1):page73_i85@pure_quanta.q_cap(chips)',
 PATH='I85',
 DRAWING='@T6G_MB_LIB.T6G(SCH_1):PAGE72',
 TOLERANCE='20%',
 MATERIAL='X6S',
 PHYS_PAGE='73',
 XY='(-3025,3725)',
 ROT='0',
 VER='1',
 PACK_TYPE='C0402',
 LOCATION='C2375',
 CDS_LIB='pure_quanta',
 CDS_PART_NAME='Q_CAP_C0402-22UF,4V,20%,X6S,CH622KMEB02',
 VOLTAGE='4V',
 PART_NUMBER='CH622KMEB02',
 VALUE='22UF',
 PRIM_FILE='./archive_libs/logical/q_cap/chips/chips.prt';

PART_NAME
 C2376 'Q_CAP_C0402-22UF,4V,20%,X6S,CH622KMEB02':;

SECTION_NUMBER 1
 '@T6G_MB_LIB.T6G(SCH_1):PAGE72_I80@PURE_QUANTA.Q_CAP(CHIPS)':
 C_PATH='@t6g_mb_lib.t6g(sch_1):page72_i80@pure_quanta.q_cap(chips)',
 P_PATH='@t6g_mb_lib.t6g(sch_1):page73_i80@pure_quanta.q_cap(chips)',
 PATH='I80',
 DRAWING='@T6G_MB_LIB.T6G(SCH_1):PAGE72',
 TOLERANCE='20%',
 MATERIAL='X6S',
 PHYS_PAGE='73',
 XY='(-3025,2925)',
 ROT='0',
 VER='1',
 PACK_TYPE='C0402',
 LOCATION='C2376',
 CDS_LIB='pure_quanta',
 CDS_PART_NAME='Q_CAP_C0402-22UF,4V,20%,X6S,CH622KMEB02',
 VOLTAGE='4V',
 PART_NUMBER='CH622KMEB02',
 VALUE='22UF',
 PRIM_FILE='./archive_libs/logical/q_cap/chips/chips.prt';

PART_NAME
 C2377 'Q_CAP_C0402-22UF,4V,20%,X6S,CH622KMEB02':;

SECTION_NUMBER 1
 '@T6G_MB_LIB.T6G(SCH_1):PAGE72_I81@PURE_QUANTA.Q_CAP(CHIPS)':
 C_PATH='@t6g_mb_lib.t6g(sch_1):page72_i81@pure_quanta.q_cap(chips)',
 P_PATH='@t6g_mb_lib.t6g(sch_1):page73_i81@pure_quanta.q_cap(chips)',
 PATH='I81',
 DRAWING='@T6G_MB_LIB.T6G(SCH_1):PAGE72',
 TOLERANCE='20%',
 MATERIAL='X6S',
 PHYS_PAGE='73',
 XY='(-3025,2125)',
 ROT='0',
 VER='1',
 PACK_TYPE='C0402',
 LOCATION='C2377',
 CDS_LIB='pure_quanta',
 CDS_PART_NAME='Q_CAP_C0402-22UF,4V,20%,X6S,CH622KMEB02',
 VOLTAGE='4V',
 PART_NUMBER='CH622KMEB02',
 VALUE='22UF',
 PRIM_FILE='./archive_libs/logical/q_cap/chips/chips.prt';

PART_NAME
 C2378 'Q_CAP_C0402-22UF,4V,20%,X6S,CH622KMEB02':;

SECTION_NUMBER 1
 '@T6G_MB_LIB.T6G(SCH_1):PAGE72_I72@PURE_QUANTA.Q_CAP(CHIPS)':
 C_PATH='@t6g_mb_lib.t6g(sch_1):page72_i72@pure_quanta.q_cap(chips)',
 P_PATH='@t6g_mb_lib.t6g(sch_1):page73_i72@pure_quanta.q_cap(chips)',
 PATH='I72',
 DRAWING='@T6G_MB_LIB.T6G(SCH_1):PAGE72',
 TOLERANCE='20%',
 MATERIAL='X6S',
 PHYS_PAGE='73',
 XY='(-3025,1325)',
 ROT='0',
 VER='1',
 PACK_TYPE='C0402',
 LOCATION='C2378',
 CDS_LIB='pure_quanta',
 CDS_PART_NAME='Q_CAP_C0402-22UF,4V,20%,X6S,CH622KMEB02',
 VOLTAGE='4V',
 PART_NUMBER='CH622KMEB02',
 VALUE='22UF',
 PRIM_FILE='./archive_libs/logical/q_cap/chips/chips.prt';

PART_NAME
 C2380 'Q_CAP_C0402-22UF,4V,20%,X6S,CH622KMEB02':;

SECTION_NUMBER 1
 '@T6G_MB_LIB.T6G(SCH_1):PAGE72_I104@PURE_QUANTA.Q_CAP(CHIPS)':
 C_PATH='@t6g_mb_lib.t6g(sch_1):page72_i104@pure_quanta.q_cap(chips)',
 P_PATH='@t6g_mb_lib.t6g(sch_1):page73_i104@pure_quanta.q_cap(chips)',
 PATH='I104',
 DRAWING='@T6G_MB_LIB.T6G(SCH_1):PAGE72',
 TOLERANCE='20%',
 MATERIAL='X6S',
 PHYS_PAGE='73',
 XY='(-2575,4500)',
 ROT='0',
 VER='1',
 PACK_TYPE='C0402',
 LOCATION='C2380',
 CDS_LIB='pure_quanta',
 CDS_PART_NAME='Q_CAP_C0402-22UF,4V,20%,X6S,CH622KMEB02',
 VOLTAGE='4V',
 PART_NUMBER='CH622KMEB02',
 VALUE='22UF',
 PRIM_FILE='./archive_libs/logical/q_cap/chips/chips.prt';

PART_NAME
 C2381 'Q_CAP_C0402-22UF,4V,20%,X6S,CH622KMEB02':;

SECTION_NUMBER 1
 '@T6G_MB_LIB.T6G(SCH_1):PAGE72_I86@PURE_QUANTA.Q_CAP(CHIPS)':
 C_PATH='@t6g_mb_lib.t6g(sch_1):page72_i86@pure_quanta.q_cap(chips)',
 P_PATH='@t6g_mb_lib.t6g(sch_1):page73_i86@pure_quanta.q_cap(chips)',
 PATH='I86',
 DRAWING='@T6G_MB_LIB.T6G(SCH_1):PAGE72',
 TOLERANCE='20%',
 MATERIAL='X6S',
 PHYS_PAGE='73',
 XY='(-2575,3725)',
 ROT='0',
 VER='1',
 PACK_TYPE='C0402',
 LOCATION='C2381',
 CDS_LIB='pure_quanta',
 CDS_PART_NAME='Q_CAP_C0402-22UF,4V,20%,X6S,CH622KMEB02',
 VOLTAGE='4V',
 PART_NUMBER='CH622KMEB02',
 VALUE='22UF',
 PRIM_FILE='./archive_libs/logical/q_cap/chips/chips.prt';

PART_NAME
 C2382 'Q_CAP_C0402-22UF,4V,20%,X6S,CH622KMEB02':;

SECTION_NUMBER 1
 '@T6G_MB_LIB.T6G(SCH_1):PAGE72_I84@PURE_QUANTA.Q_CAP(CHIPS)':
 C_PATH='@t6g_mb_lib.t6g(sch_1):page72_i84@pure_quanta.q_cap(chips)',
 P_PATH='@t6g_mb_lib.t6g(sch_1):page73_i84@pure_quanta.q_cap(chips)',
 PATH='I84',
 DRAWING='@T6G_MB_LIB.T6G(SCH_1):PAGE72',
 TOLERANCE='20%',
 MATERIAL='X6S',
 PHYS_PAGE='73',
 XY='(-2575,2925)',
 ROT='0',
 VER='1',
 PACK_TYPE='C0402',
 LOCATION='C2382',
 CDS_LIB='pure_quanta',
 CDS_PART_NAME='Q_CAP_C0402-22UF,4V,20%,X6S,CH622KMEB02',
 VOLTAGE='4V',
 PART_NUMBER='CH622KMEB02',
 VALUE='22UF',
 PRIM_FILE='./archive_libs/logical/q_cap/chips/chips.prt';

PART_NAME
 C2383 'Q_CAP_C0402-22UF,4V,20%,X6S,CH622KMEB02':;

SECTION_NUMBER 1
 '@T6G_MB_LIB.T6G(SCH_1):PAGE72_I82@PURE_QUANTA.Q_CAP(CHIPS)':
 C_PATH='@t6g_mb_lib.t6g(sch_1):page72_i82@pure_quanta.q_cap(chips)',
 P_PATH='@t6g_mb_lib.t6g(sch_1):page73_i82@pure_quanta.q_cap(chips)',
 PATH='I82',
 DRAWING='@T6G_MB_LIB.T6G(SCH_1):PAGE72',
 TOLERANCE='20%',
 MATERIAL='X6S',
 PHYS_PAGE='73',
 XY='(-2575,2125)',
 ROT='0',
 VER='1',
 PACK_TYPE='C0402',
 LOCATION='C2383',
 CDS_LIB='pure_quanta',
 CDS_PART_NAME='Q_CAP_C0402-22UF,4V,20%,X6S,CH622KMEB02',
 VOLTAGE='4V',
 PART_NUMBER='CH622KMEB02',
 VALUE='22UF',
 PRIM_FILE='./archive_libs/logical/q_cap/chips/chips.prt';

PART_NAME
 C2386 'Q_CAP_C0402-22UF,4V,20%,X6S,CH622KMEB02':;

SECTION_NUMBER 1
 '@T6G_MB_LIB.T6G(SCH_1):PAGE72_I105@PURE_QUANTA.Q_CAP(CHIPS)':
 C_PATH='@t6g_mb_lib.t6g(sch_1):page72_i105@pure_quanta.q_cap(chips)',
 P_PATH='@t6g_mb_lib.t6g(sch_1):page73_i105@pure_quanta.q_cap(chips)',
 PATH='I105',
 DRAWING='@T6G_MB_LIB.T6G(SCH_1):PAGE72',
 TOLERANCE='20%',
 MATERIAL='X6S',
 PHYS_PAGE='73',
 XY='(-2125,4500)',
 ROT='0',
 VER='1',
 PACK_TYPE='C0402',
 LOCATION='C2386',
 CDS_LIB='pure_quanta',
 CDS_PART_NAME='Q_CAP_C0402-22UF,4V,20%,X6S,CH622KMEB02',
 VOLTAGE='4V',
 PART_NUMBER='CH622KMEB02',
 VALUE='22UF',
 PRIM_FILE='./archive_libs/logical/q_cap/chips/chips.prt';

PART_NAME
 C2387 'Q_CAP_C0402-22UF,4V,20%,X6S,CH622KMEB02':;

SECTION_NUMBER 1
 '@T6G_MB_LIB.T6G(SCH_1):PAGE72_I88@PURE_QUANTA.Q_CAP(CHIPS)':
 C_PATH='@t6g_mb_lib.t6g(sch_1):page72_i88@pure_quanta.q_cap(chips)',
 P_PATH='@t6g_mb_lib.t6g(sch_1):page73_i88@pure_quanta.q_cap(chips)',
 PATH='I88',
 DRAWING='@T6G_MB_LIB.T6G(SCH_1):PAGE72',
 TOLERANCE='20%',
 MATERIAL='X6S',
 PHYS_PAGE='73',
 XY='(-2125,3725)',
 ROT='0',
 VER='1',
 PACK_TYPE='C0402',
 LOCATION='C2387',
 CDS_LIB='pure_quanta',
 CDS_PART_NAME='Q_CAP_C0402-22UF,4V,20%,X6S,CH622KMEB02',
 VOLTAGE='4V',
 PART_NUMBER='CH622KMEB02',
 VALUE='22UF',
 PRIM_FILE='./archive_libs/logical/q_cap/chips/chips.prt';

PART_NAME
 C2388 'Q_CAP_C0402-22UF,4V,20%,X6S,CH622KMEB02':;

SECTION_NUMBER 1
 '@T6G_MB_LIB.T6G(SCH_1):PAGE72_I87@PURE_QUANTA.Q_CAP(CHIPS)':
 C_PATH='@t6g_mb_lib.t6g(sch_1):page72_i87@pure_quanta.q_cap(chips)',
 P_PATH='@t6g_mb_lib.t6g(sch_1):page73_i87@pure_quanta.q_cap(chips)',
 PATH='I87',
 DRAWING='@T6G_MB_LIB.T6G(SCH_1):PAGE72',
 TOLERANCE='20%',
 MATERIAL='X6S',
 PHYS_PAGE='73',
 XY='(-2125,2925)',
 ROT='0',
 VER='1',
 PACK_TYPE='C0402',
 LOCATION='C2388',
 CDS_LIB='pure_quanta',
 CDS_PART_NAME='Q_CAP_C0402-22UF,4V,20%,X6S,CH622KMEB02',
 VOLTAGE='4V',
 PART_NUMBER='CH622KMEB02',
 VALUE='22UF',
 PRIM_FILE='./archive_libs/logical/q_cap/chips/chips.prt';

PART_NAME
 C2389 'Q_CAP_C0402-22UF,4V,20%,X6S,CH622KMEB02':;

SECTION_NUMBER 1
 '@T6G_MB_LIB.T6G(SCH_1):PAGE72_I83@PURE_QUANTA.Q_CAP(CHIPS)':
 C_PATH='@t6g_mb_lib.t6g(sch_1):page72_i83@pure_quanta.q_cap(chips)',
 P_PATH='@t6g_mb_lib.t6g(sch_1):page73_i83@pure_quanta.q_cap(chips)',
 PATH='I83',
 DRAWING='@T6G_MB_LIB.T6G(SCH_1):PAGE72',
 TOLERANCE='20%',
 MATERIAL='X6S',
 PHYS_PAGE='73',
 XY='(-2125,2125)',
 ROT='0',
 VER='1',
 PACK_TYPE='C0402',
 LOCATION='C2389',
 CDS_LIB='pure_quanta',
 CDS_PART_NAME='Q_CAP_C0402-22UF,4V,20%,X6S,CH622KMEB02',
 VOLTAGE='4V',
 PART_NUMBER='CH622KMEB02',
 VALUE='22UF',
 PRIM_FILE='./archive_libs/logical/q_cap/chips/chips.prt';

PART_NAME
 C2392 'Q_CAP_C0402-22UF,4V,20%,X6S,CH622KMEB02':;

SECTION_NUMBER 1
 '@T6G_MB_LIB.T6G(SCH_1):PAGE72_I106@PURE_QUANTA.Q_CAP(CHIPS)':
 C_PATH='@t6g_mb_lib.t6g(sch_1):page72_i106@pure_quanta.q_cap(chips)',
 P_PATH='@t6g_mb_lib.t6g(sch_1):page73_i106@pure_quanta.q_cap(chips)',
 PATH='I106',
 DRAWING='@T6G_MB_LIB.T6G(SCH_1):PAGE72',
 TOLERANCE='20%',
 MATERIAL='X6S',
 PHYS_PAGE='73',
 XY='(-1675,4500)',
 ROT='0',
 VER='1',
 PACK_TYPE='C0402',
 LOCATION='C2392',
 CDS_LIB='pure_quanta',
 CDS_PART_NAME='Q_CAP_C0402-22UF,4V,20%,X6S,CH622KMEB02',
 VOLTAGE='4V',
 PART_NUMBER='CH622KMEB02',
 VALUE='22UF',
 PRIM_FILE='./archive_libs/logical/q_cap/chips/chips.prt';

PART_NAME
 C2393 'Q_CAP_C0402-22UF,4V,20%,X6S,CH622KMEB02':;

SECTION_NUMBER 1
 '@T6G_MB_LIB.T6G(SCH_1):PAGE72_I92@PURE_QUANTA.Q_CAP(CHIPS)':
 C_PATH='@t6g_mb_lib.t6g(sch_1):page72_i92@pure_quanta.q_cap(chips)',
 P_PATH='@t6g_mb_lib.t6g(sch_1):page73_i92@pure_quanta.q_cap(chips)',
 PATH='I92',
 DRAWING='@T6G_MB_LIB.T6G(SCH_1):PAGE72',
 TOLERANCE='20%',
 MATERIAL='X6S',
 PHYS_PAGE='73',
 XY='(-1675,3725)',
 ROT='0',
 VER='1',
 PACK_TYPE='C0402',
 LOCATION='C2393',
 CDS_LIB='pure_quanta',
 CDS_PART_NAME='Q_CAP_C0402-22UF,4V,20%,X6S,CH622KMEB02',
 VOLTAGE='4V',
 PART_NUMBER='CH622KMEB02',
 VALUE='22UF',
 PRIM_FILE='./archive_libs/logical/q_cap/chips/chips.prt';

PART_NAME
 C2394 'Q_CAP_C0402-22UF,4V,20%,X6S,CH622KMEB02':;

SECTION_NUMBER 1
 '@T6G_MB_LIB.T6G(SCH_1):PAGE72_I91@PURE_QUANTA.Q_CAP(CHIPS)':
 C_PATH='@t6g_mb_lib.t6g(sch_1):page72_i91@pure_quanta.q_cap(chips)',
 P_PATH='@t6g_mb_lib.t6g(sch_1):page73_i91@pure_quanta.q_cap(chips)',
 PATH='I91',
 DRAWING='@T6G_MB_LIB.T6G(SCH_1):PAGE72',
 TOLERANCE='20%',
 MATERIAL='X6S',
 PHYS_PAGE='73',
 XY='(-1675,2925)',
 ROT='0',
 VER='1',
 PACK_TYPE='C0402',
 LOCATION='C2394',
 CDS_LIB='pure_quanta',
 CDS_PART_NAME='Q_CAP_C0402-22UF,4V,20%,X6S,CH622KMEB02',
 VOLTAGE='4V',
 PART_NUMBER='CH622KMEB02',
 VALUE='22UF',
 PRIM_FILE='./archive_libs/logical/q_cap/chips/chips.prt';

PART_NAME
 C2395 'Q_CAP_C0402-22UF,4V,20%,X6S,CH622KMEB02':;

SECTION_NUMBER 1
 '@T6G_MB_LIB.T6G(SCH_1):PAGE72_I89@PURE_QUANTA.Q_CAP(CHIPS)':
 C_PATH='@t6g_mb_lib.t6g(sch_1):page72_i89@pure_quanta.q_cap(chips)',
 P_PATH='@t6g_mb_lib.t6g(sch_1):page73_i89@pure_quanta.q_cap(chips)',
 PATH='I89',
 DRAWING='@T6G_MB_LIB.T6G(SCH_1):PAGE72',
 TOLERANCE='20%',
 MATERIAL='X6S',
 PHYS_PAGE='73',
 XY='(-1675,2125)',
 ROT='0',
 VER='1',
 PACK_TYPE='C0402',
 LOCATION='C2395',
 CDS_LIB='pure_quanta',
 CDS_PART_NAME='Q_CAP_C0402-22UF,4V,20%,X6S,CH622KMEB02',
 VOLTAGE='4V',
 PART_NUMBER='CH622KMEB02',
 VALUE='22UF',
 PRIM_FILE='./archive_libs/logical/q_cap/chips/chips.prt';

PART_NAME
 C2397 'Q_CAP_C0402-22UF,4V,20%,X6S,CH622KMEB02':;

SECTION_NUMBER 1
 '@T6G_MB_LIB.T6G(SCH_1):PAGE72_I107@PURE_QUANTA.Q_CAP(CHIPS)':
 C_PATH='@t6g_mb_lib.t6g(sch_1):page72_i107@pure_quanta.q_cap(chips)',
 P_PATH='@t6g_mb_lib.t6g(sch_1):page73_i107@pure_quanta.q_cap(chips)',
 PATH='I107',
 DRAWING='@T6G_MB_LIB.T6G(SCH_1):PAGE72',
 TOLERANCE='20%',
 MATERIAL='X6S',
 PHYS_PAGE='73',
 XY='(-1225,4500)',
 ROT='0',
 VER='1',
 PACK_TYPE='C0402',
 LOCATION='C2397',
 CDS_LIB='pure_quanta',
 CDS_PART_NAME='Q_CAP_C0402-22UF,4V,20%,X6S,CH622KMEB02',
 VOLTAGE='4V',
 PART_NUMBER='CH622KMEB02',
 VALUE='22UF',
 PRIM_FILE='./archive_libs/logical/q_cap/chips/chips.prt';

PART_NAME
 C2398 'Q_CAP_C0402-22UF,4V,20%,X6S,CH622KMEB02':;

SECTION_NUMBER 1
 '@T6G_MB_LIB.T6G(SCH_1):PAGE72_I94@PURE_QUANTA.Q_CAP(CHIPS)':
 C_PATH='@t6g_mb_lib.t6g(sch_1):page72_i94@pure_quanta.q_cap(chips)',
 P_PATH='@t6g_mb_lib.t6g(sch_1):page73_i94@pure_quanta.q_cap(chips)',
 PATH='I94',
 DRAWING='@T6G_MB_LIB.T6G(SCH_1):PAGE72',
 TOLERANCE='20%',
 MATERIAL='X6S',
 PHYS_PAGE='73',
 XY='(-1225,3725)',
 ROT='0',
 VER='1',
 PACK_TYPE='C0402',
 LOCATION='C2398',
 CDS_LIB='pure_quanta',
 CDS_PART_NAME='Q_CAP_C0402-22UF,4V,20%,X6S,CH622KMEB02',
 VOLTAGE='4V',
 PART_NUMBER='CH622KMEB02',
 VALUE='22UF',
 PRIM_FILE='./archive_libs/logical/q_cap/chips/chips.prt';

PART_NAME
 C2399 'Q_CAP_C0402-22UF,4V,20%,X6S,CH622KMEB02':;

SECTION_NUMBER 1
 '@T6G_MB_LIB.T6G(SCH_1):PAGE72_I93@PURE_QUANTA.Q_CAP(CHIPS)':
 C_PATH='@t6g_mb_lib.t6g(sch_1):page72_i93@pure_quanta.q_cap(chips)',
 P_PATH='@t6g_mb_lib.t6g(sch_1):page73_i93@pure_quanta.q_cap(chips)',
 PATH='I93',
 DRAWING='@T6G_MB_LIB.T6G(SCH_1):PAGE72',
 TOLERANCE='20%',
 MATERIAL='X6S',
 PHYS_PAGE='73',
 XY='(-1225,2925)',
 ROT='0',
 VER='1',
 PACK_TYPE='C0402',
 LOCATION='C2399',
 CDS_LIB='pure_quanta',
 CDS_PART_NAME='Q_CAP_C0402-22UF,4V,20%,X6S,CH622KMEB02',
 VOLTAGE='4V',
 PART_NUMBER='CH622KMEB02',
 VALUE='22UF',
 PRIM_FILE='./archive_libs/logical/q_cap/chips/chips.prt';

PART_NAME
 C2400 'Q_CAP_C0402-22UF,4V,20%,X6S,CH622KMEB02':;

SECTION_NUMBER 1
 '@T6G_MB_LIB.T6G(SCH_1):PAGE72_I90@PURE_QUANTA.Q_CAP(CHIPS)':
 C_PATH='@t6g_mb_lib.t6g(sch_1):page72_i90@pure_quanta.q_cap(chips)',
 P_PATH='@t6g_mb_lib.t6g(sch_1):page73_i90@pure_quanta.q_cap(chips)',
 PATH='I90',
 DRAWING='@T6G_MB_LIB.T6G(SCH_1):PAGE72',
 TOLERANCE='20%',
 MATERIAL='X6S',
 PHYS_PAGE='73',
 XY='(-1225,2125)',
 ROT='0',
 VER='1',
 PACK_TYPE='C0402',
 LOCATION='C2400',
 CDS_LIB='pure_quanta',
 CDS_PART_NAME='Q_CAP_C0402-22UF,4V,20%,X6S,CH622KMEB02',
 VOLTAGE='4V',
 PART_NUMBER='CH622KMEB02',
 VALUE='22UF',
 PRIM_FILE='./archive_libs/logical/q_cap/chips/chips.prt';

PART_NAME
 C2402 'Q_CAP_C0402-22UF,4V,20%,X6S,CH622KMEB02':;

SECTION_NUMBER 1
 '@T6G_MB_LIB.T6G(SCH_1):PAGE72_I109@PURE_QUANTA.Q_CAP(CHIPS)':
 C_PATH='@t6g_mb_lib.t6g(sch_1):page72_i109@pure_quanta.q_cap(chips)',
 P_PATH='@t6g_mb_lib.t6g(sch_1):page73_i109@pure_quanta.q_cap(chips)',
 PATH='I109',
 DRAWING='@T6G_MB_LIB.T6G(SCH_1):PAGE72',
 TOLERANCE='20%',
 MATERIAL='X6S',
 PHYS_PAGE='73',
 XY='(-825,4500)',
 ROT='0',
 VER='1',
 PACK_TYPE='C0402',
 LOCATION='C2402',
 CDS_LIB='pure_quanta',
 CDS_PART_NAME='Q_CAP_C0402-22UF,4V,20%,X6S,CH622KMEB02',
 VOLTAGE='4V',
 PART_NUMBER='CH622KMEB02',
 VALUE='22UF',
 PRIM_FILE='./archive_libs/logical/q_cap/chips/chips.prt';

PART_NAME
 C2403 'Q_CAP_C0402-22UF,4V,20%,X6S,CH622KMEB02':;

SECTION_NUMBER 1
 '@T6G_MB_LIB.T6G(SCH_1):PAGE72_I100@PURE_QUANTA.Q_CAP(CHIPS)':
 C_PATH='@t6g_mb_lib.t6g(sch_1):page72_i100@pure_quanta.q_cap(chips)',
 P_PATH='@t6g_mb_lib.t6g(sch_1):page73_i100@pure_quanta.q_cap(chips)',
 PATH='I100',
 DRAWING='@T6G_MB_LIB.T6G(SCH_1):PAGE72',
 TOLERANCE='20%',
 MATERIAL='X6S',
 PHYS_PAGE='73',
 XY='(-825,3725)',
 ROT='0',
 VER='1',
 PACK_TYPE='C0402',
 LOCATION='C2403',
 CDS_LIB='pure_quanta',
 CDS_PART_NAME='Q_CAP_C0402-22UF,4V,20%,X6S,CH622KMEB02',
 VOLTAGE='4V',
 PART_NUMBER='CH622KMEB02',
 VALUE='22UF',
 PRIM_FILE='./archive_libs/logical/q_cap/chips/chips.prt';

PART_NAME
 C2404 'Q_CAP_C0402-22UF,4V,20%,X6S,CH622KMEB02':;

SECTION_NUMBER 1
 '@T6G_MB_LIB.T6G(SCH_1):PAGE72_I98@PURE_QUANTA.Q_CAP(CHIPS)':
 C_PATH='@t6g_mb_lib.t6g(sch_1):page72_i98@pure_quanta.q_cap(chips)',
 P_PATH='@t6g_mb_lib.t6g(sch_1):page73_i98@pure_quanta.q_cap(chips)',
 PATH='I98',
 DRAWING='@T6G_MB_LIB.T6G(SCH_1):PAGE72',
 TOLERANCE='20%',
 MATERIAL='X6S',
 PHYS_PAGE='73',
 XY='(-825,2925)',
 ROT='0',
 VER='1',
 PACK_TYPE='C0402',
 LOCATION='C2404',
 CDS_LIB='pure_quanta',
 CDS_PART_NAME='Q_CAP_C0402-22UF,4V,20%,X6S,CH622KMEB02',
 VOLTAGE='4V',
 PART_NUMBER='CH622KMEB02',
 VALUE='22UF',
 PRIM_FILE='./archive_libs/logical/q_cap/chips/chips.prt';

PART_NAME
 C2405 'Q_CAP_C0402-22UF,4V,20%,X6S,CH622KMEB02':;

SECTION_NUMBER 1
 '@T6G_MB_LIB.T6G(SCH_1):PAGE72_I96@PURE_QUANTA.Q_CAP(CHIPS)':
 C_PATH='@t6g_mb_lib.t6g(sch_1):page72_i96@pure_quanta.q_cap(chips)',
 P_PATH='@t6g_mb_lib.t6g(sch_1):page73_i96@pure_quanta.q_cap(chips)',
 PATH='I96',
 DRAWING='@T6G_MB_LIB.T6G(SCH_1):PAGE72',
 TOLERANCE='20%',
 MATERIAL='X6S',
 PHYS_PAGE='73',
 XY='(-825,2125)',
 ROT='0',
 VER='1',
 PACK_TYPE='C0402',
 LOCATION='C2405',
 CDS_LIB='pure_quanta',
 CDS_PART_NAME='Q_CAP_C0402-22UF,4V,20%,X6S,CH622KMEB02',
 VOLTAGE='4V',
 PART_NUMBER='CH622KMEB02',
 VALUE='22UF',
 PRIM_FILE='./archive_libs/logical/q_cap/chips/chips.prt';

PART_NAME
 C2407 'Q_CAP_C0402-22UF,4V,20%,X6S,CH622KMEB02':;

SECTION_NUMBER 1
 '@T6G_MB_LIB.T6G(SCH_1):PAGE73_I55@PURE_QUANTA.Q_CAP(CHIPS)':
 C_PATH='@t6g_mb_lib.t6g(sch_1):page73_i55@pure_quanta.q_cap(chips)',
 P_PATH='@t6g_mb_lib.t6g(sch_1):page74_i55@pure_quanta.q_cap(chips)',
 PATH='I55',
 DRAWING='@T6G_MB_LIB.T6G(SCH_1):PAGE73',
 TOLERANCE='20%',
 MATERIAL='X6S',
 PHYS_PAGE='74',
 XY='(400,5875)',
 ROT='0',
 VER='1',
 PACK_TYPE='C0402',
 LOCATION='C2407',
 CDS_LIB='pure_quanta',
 CDS_PART_NAME='Q_CAP_C0402-22UF,4V,20%,X6S,CH622KMEB02',
 VOLTAGE='4V',
 PART_NUMBER='CH622KMEB02',
 VALUE='22UF',
 PRIM_FILE='./archive_libs/logical/q_cap/chips/chips.prt';

PART_NAME
 C2408 'Q_CAP_C0402-22UF,4V,20%,X6S,CH622KMEB02':;

SECTION_NUMBER 1
 '@T6G_MB_LIB.T6G(SCH_1):PAGE73_I53@PURE_QUANTA.Q_CAP(CHIPS)':
 C_PATH='@t6g_mb_lib.t6g(sch_1):page73_i53@pure_quanta.q_cap(chips)',
 P_PATH='@t6g_mb_lib.t6g(sch_1):page74_i53@pure_quanta.q_cap(chips)',
 PATH='I53',
 DRAWING='@T6G_MB_LIB.T6G(SCH_1):PAGE73',
 TOLERANCE='20%',
 MATERIAL='X6S',
 PHYS_PAGE='74',
 XY='(400,5225)',
 ROT='0',
 VER='1',
 PACK_TYPE='C0402',
 LOCATION='C2408',
 CDS_LIB='pure_quanta',
 CDS_PART_NAME='Q_CAP_C0402-22UF,4V,20%,X6S,CH622KMEB02',
 VOLTAGE='4V',
 PART_NUMBER='CH622KMEB02',
 VALUE='22UF',
 PRIM_FILE='./archive_libs/logical/q_cap/chips/chips.prt';

PART_NAME
 C2409 'Q_CAP_C0402-22UF,4V,20%,X6S,CH622KMEB02':;

SECTION_NUMBER 1
 '@T6G_MB_LIB.T6G(SCH_1):PAGE73_I50@PURE_QUANTA.Q_CAP(CHIPS)':
 C_PATH='@t6g_mb_lib.t6g(sch_1):page73_i50@pure_quanta.q_cap(chips)',
 P_PATH='@t6g_mb_lib.t6g(sch_1):page74_i50@pure_quanta.q_cap(chips)',
 PATH='I50',
 DRAWING='@T6G_MB_LIB.T6G(SCH_1):PAGE73',
 TOLERANCE='20%',
 MATERIAL='X6S',
 PHYS_PAGE='74',
 XY='(400,4550)',
 ROT='0',
 VER='1',
 PACK_TYPE='C0402',
 LOCATION='C2409',
 CDS_LIB='pure_quanta',
 CDS_PART_NAME='Q_CAP_C0402-22UF,4V,20%,X6S,CH622KMEB02',
 VOLTAGE='4V',
 PART_NUMBER='CH622KMEB02',
 VALUE='22UF',
 PRIM_FILE='./archive_libs/logical/q_cap/chips/chips.prt';

PART_NAME
 C2410 'Q_CAP_C0402-22UF,4V,20%,X6S,CH622KMEB02':;

SECTION_NUMBER 1
 '@T6G_MB_LIB.T6G(SCH_1):PAGE73_I16@PURE_QUANTA.Q_CAP(CHIPS)':
 C_PATH='@t6g_mb_lib.t6g(sch_1):page73_i16@pure_quanta.q_cap(chips)',
 P_PATH='@t6g_mb_lib.t6g(sch_1):page74_i16@pure_quanta.q_cap(chips)',
 PATH='I16',
 DRAWING='@T6G_MB_LIB.T6G(SCH_1):PAGE73',
 TOLERANCE='20%',
 MATERIAL='X6S',
 PHYS_PAGE='74',
 XY='(400,3850)',
 ROT='0',
 VER='1',
 PACK_TYPE='C0402',
 LOCATION='C2410',
 CDS_LIB='pure_quanta',
 CDS_PART_NAME='Q_CAP_C0402-22UF,4V,20%,X6S,CH622KMEB02',
 VOLTAGE='4V',
 PART_NUMBER='CH622KMEB02',
 VALUE='22UF',
 PRIM_FILE='./archive_libs/logical/q_cap/chips/chips.prt';

PART_NAME
 C2411 'Q_CAP_C0402-22UF,4V,20%,X6S,CH622KMEB02':;

SECTION_NUMBER 1
 '@T6G_MB_LIB.T6G(SCH_1):PAGE73_I14@PURE_QUANTA.Q_CAP(CHIPS)':
 C_PATH='@t6g_mb_lib.t6g(sch_1):page73_i14@pure_quanta.q_cap(chips)',
 P_PATH='@t6g_mb_lib.t6g(sch_1):page74_i14@pure_quanta.q_cap(chips)',
 PATH='I14',
 DRAWING='@T6G_MB_LIB.T6G(SCH_1):PAGE73',
 TOLERANCE='20%',
 MATERIAL='X6S',
 PHYS_PAGE='74',
 XY='(400,3150)',
 ROT='0',
 VER='1',
 PACK_TYPE='C0402',
 LOCATION='C2411',
 CDS_LIB='pure_quanta',
 CDS_PART_NAME='Q_CAP_C0402-22UF,4V,20%,X6S,CH622KMEB02',
 VOLTAGE='4V',
 PART_NUMBER='CH622KMEB02',
 VALUE='22UF',
 PRIM_FILE='./archive_libs/logical/q_cap/chips/chips.prt';

PART_NAME
 C2412 'Q_CAP_C0402-22UF,4V,20%,X6S,CH622KMEB02':;

SECTION_NUMBER 1
 '@T6G_MB_LIB.T6G(SCH_1):PAGE73_I11@PURE_QUANTA.Q_CAP(CHIPS)':
 C_PATH='@t6g_mb_lib.t6g(sch_1):page73_i11@pure_quanta.q_cap(chips)',
 P_PATH='@t6g_mb_lib.t6g(sch_1):page74_i11@pure_quanta.q_cap(chips)',
 PATH='I11',
 DRAWING='@T6G_MB_LIB.T6G(SCH_1):PAGE73',
 TOLERANCE='20%',
 MATERIAL='X6S',
 PHYS_PAGE='74',
 XY='(400,2475)',
 ROT='0',
 VER='1',
 PACK_TYPE='C0402',
 LOCATION='C2412',
 CDS_LIB='pure_quanta',
 CDS_PART_NAME='Q_CAP_C0402-22UF,4V,20%,X6S,CH622KMEB02',
 VOLTAGE='4V',
 PART_NUMBER='CH622KMEB02',
 VALUE='22UF',
 PRIM_FILE='./archive_libs/logical/q_cap/chips/chips.prt';

PART_NAME
 C2413 'Q_CAP_C0402-22UF,4V,20%,X6S,CH622KMEB02':;

SECTION_NUMBER 1
 '@T6G_MB_LIB.T6G(SCH_1):PAGE73_I3@PURE_QUANTA.Q_CAP(CHIPS)':
 C_PATH='@t6g_mb_lib.t6g(sch_1):page73_i3@pure_quanta.q_cap(chips)',
 P_PATH='@t6g_mb_lib.t6g(sch_1):page74_i3@pure_quanta.q_cap(chips)',
 PATH='I3',
 DRAWING='@T6G_MB_LIB.T6G(SCH_1):PAGE73',
 TOLERANCE='20%',
 MATERIAL='X6S',
 PHYS_PAGE='74',
 XY='(400,1800)',
 ROT='0',
 VER='1',
 PACK_TYPE='C0402',
 LOCATION='C2413',
 CDS_LIB='pure_quanta',
 CDS_PART_NAME='Q_CAP_C0402-22UF,4V,20%,X6S,CH622KMEB02',
 VOLTAGE='4V',
 PART_NUMBER='CH622KMEB02',
 VALUE='22UF',
 PRIM_FILE='./archive_libs/logical/q_cap/chips/chips.prt';

PART_NAME
 C2414 'Q_CAP_C0402-22UF,4V,20%,X6S,CH622KMEB02':;

SECTION_NUMBER 1
 '@T6G_MB_LIB.T6G(SCH_1):PAGE73_I57@PURE_QUANTA.Q_CAP(CHIPS)':
 C_PATH='@t6g_mb_lib.t6g(sch_1):page73_i57@pure_quanta.q_cap(chips)',
 P_PATH='@t6g_mb_lib.t6g(sch_1):page74_i57@pure_quanta.q_cap(chips)',
 PATH='I57',
 DRAWING='@T6G_MB_LIB.T6G(SCH_1):PAGE73',
 TOLERANCE='20%',
 MATERIAL='X6S',
 PHYS_PAGE='74',
 XY='(850,5875)',
 ROT='0',
 VER='1',
 PACK_TYPE='C0402',
 LOCATION='C2414',
 CDS_LIB='pure_quanta',
 CDS_PART_NAME='Q_CAP_C0402-22UF,4V,20%,X6S,CH622KMEB02',
 VOLTAGE='4V',
 PART_NUMBER='CH622KMEB02',
 VALUE='22UF',
 PRIM_FILE='./archive_libs/logical/q_cap/chips/chips.prt';

PART_NAME
 C2415 'Q_CAP_C0402-22UF,4V,20%,X6S,CH622KMEB02':;

SECTION_NUMBER 1
 '@T6G_MB_LIB.T6G(SCH_1):PAGE73_I56@PURE_QUANTA.Q_CAP(CHIPS)':
 C_PATH='@t6g_mb_lib.t6g(sch_1):page73_i56@pure_quanta.q_cap(chips)',
 P_PATH='@t6g_mb_lib.t6g(sch_1):page74_i56@pure_quanta.q_cap(chips)',
 PATH='I56',
 DRAWING='@T6G_MB_LIB.T6G(SCH_1):PAGE73',
 TOLERANCE='20%',
 MATERIAL='X6S',
 PHYS_PAGE='74',
 XY='(850,5225)',
 ROT='0',
 VER='1',
 PACK_TYPE='C0402',
 LOCATION='C2415',
 CDS_LIB='pure_quanta',
 CDS_PART_NAME='Q_CAP_C0402-22UF,4V,20%,X6S,CH622KMEB02',
 VOLTAGE='4V',
 PART_NUMBER='CH622KMEB02',
 VALUE='22UF',
 PRIM_FILE='./archive_libs/logical/q_cap/chips/chips.prt';

PART_NAME
 C2416 'Q_CAP_C0402-22UF,4V,20%,X6S,CH622KMEB02':;

SECTION_NUMBER 1
 '@T6G_MB_LIB.T6G(SCH_1):PAGE73_I52@PURE_QUANTA.Q_CAP(CHIPS)':
 C_PATH='@t6g_mb_lib.t6g(sch_1):page73_i52@pure_quanta.q_cap(chips)',
 P_PATH='@t6g_mb_lib.t6g(sch_1):page74_i52@pure_quanta.q_cap(chips)',
 PATH='I52',
 DRAWING='@T6G_MB_LIB.T6G(SCH_1):PAGE73',
 TOLERANCE='20%',
 MATERIAL='X6S',
 PHYS_PAGE='74',
 XY='(850,4550)',
 ROT='0',
 VER='1',
 PACK_TYPE='C0402',
 LOCATION='C2416',
 CDS_LIB='pure_quanta',
 CDS_PART_NAME='Q_CAP_C0402-22UF,4V,20%,X6S,CH622KMEB02',
 VOLTAGE='4V',
 PART_NUMBER='CH622KMEB02',
 VALUE='22UF',
 PRIM_FILE='./archive_libs/logical/q_cap/chips/chips.prt';

PART_NAME
 C2417 'Q_CAP_C0402-22UF,4V,20%,X6S,CH622KMEB02':;

SECTION_NUMBER 1
 '@T6G_MB_LIB.T6G(SCH_1):PAGE73_I18@PURE_QUANTA.Q_CAP(CHIPS)':
 C_PATH='@t6g_mb_lib.t6g(sch_1):page73_i18@pure_quanta.q_cap(chips)',
 P_PATH='@t6g_mb_lib.t6g(sch_1):page74_i18@pure_quanta.q_cap(chips)',
 PATH='I18',
 DRAWING='@T6G_MB_LIB.T6G(SCH_1):PAGE73',
 TOLERANCE='20%',
 MATERIAL='X6S',
 PHYS_PAGE='74',
 XY='(850,3850)',
 ROT='0',
 VER='1',
 PACK_TYPE='C0402',
 LOCATION='C2417',
 CDS_LIB='pure_quanta',
 CDS_PART_NAME='Q_CAP_C0402-22UF,4V,20%,X6S,CH622KMEB02',
 VOLTAGE='4V',
 PART_NUMBER='CH622KMEB02',
 VALUE='22UF',
 PRIM_FILE='./archive_libs/logical/q_cap/chips/chips.prt';

PART_NAME
 C2418 'Q_CAP_C0402-22UF,4V,20%,X6S,CH622KMEB02':;

SECTION_NUMBER 1
 '@T6G_MB_LIB.T6G(SCH_1):PAGE73_I17@PURE_QUANTA.Q_CAP(CHIPS)':
 C_PATH='@t6g_mb_lib.t6g(sch_1):page73_i17@pure_quanta.q_cap(chips)',
 P_PATH='@t6g_mb_lib.t6g(sch_1):page74_i17@pure_quanta.q_cap(chips)',
 PATH='I17',
 DRAWING='@T6G_MB_LIB.T6G(SCH_1):PAGE73',
 TOLERANCE='20%',
 MATERIAL='X6S',
 PHYS_PAGE='74',
 XY='(850,3150)',
 ROT='0',
 VER='1',
 PACK_TYPE='C0402',
 LOCATION='C2418',
 CDS_LIB='pure_quanta',
 CDS_PART_NAME='Q_CAP_C0402-22UF,4V,20%,X6S,CH622KMEB02',
 VOLTAGE='4V',
 PART_NUMBER='CH622KMEB02',
 VALUE='22UF',
 PRIM_FILE='./archive_libs/logical/q_cap/chips/chips.prt';

PART_NAME
 C2419 'Q_CAP_C0402-22UF,4V,20%,X6S,CH622KMEB02':;

SECTION_NUMBER 1
 '@T6G_MB_LIB.T6G(SCH_1):PAGE73_I13@PURE_QUANTA.Q_CAP(CHIPS)':
 C_PATH='@t6g_mb_lib.t6g(sch_1):page73_i13@pure_quanta.q_cap(chips)',
 P_PATH='@t6g_mb_lib.t6g(sch_1):page74_i13@pure_quanta.q_cap(chips)',
 PATH='I13',
 DRAWING='@T6G_MB_LIB.T6G(SCH_1):PAGE73',
 TOLERANCE='20%',
 MATERIAL='X6S',
 PHYS_PAGE='74',
 XY='(850,2475)',
 ROT='0',
 VER='1',
 PACK_TYPE='C0402',
 LOCATION='C2419',
 CDS_LIB='pure_quanta',
 CDS_PART_NAME='Q_CAP_C0402-22UF,4V,20%,X6S,CH622KMEB02',
 VOLTAGE='4V',
 PART_NUMBER='CH622KMEB02',
 VALUE='22UF',
 PRIM_FILE='./archive_libs/logical/q_cap/chips/chips.prt';

PART_NAME
 C2420 'Q_CAP_C0402-22UF,4V,20%,X6S,CH622KMEB02':;

SECTION_NUMBER 1
 '@T6G_MB_LIB.T6G(SCH_1):PAGE73_I5@PURE_QUANTA.Q_CAP(CHIPS)':
 C_PATH='@t6g_mb_lib.t6g(sch_1):page73_i5@pure_quanta.q_cap(chips)',
 P_PATH='@t6g_mb_lib.t6g(sch_1):page74_i5@pure_quanta.q_cap(chips)',
 PATH='I5',
 DRAWING='@T6G_MB_LIB.T6G(SCH_1):PAGE73',
 TOLERANCE='20%',
 MATERIAL='X6S',
 PHYS_PAGE='74',
 XY='(850,1800)',
 ROT='0',
 VER='1',
 PACK_TYPE='C0402',
 LOCATION='C2420',
 CDS_LIB='pure_quanta',
 CDS_PART_NAME='Q_CAP_C0402-22UF,4V,20%,X6S,CH622KMEB02',
 VOLTAGE='4V',
 PART_NUMBER='CH622KMEB02',
 VALUE='22UF',
 PRIM_FILE='./archive_libs/logical/q_cap/chips/chips.prt';

PART_NAME
 C2421 'Q_CAP_C0402-22UF,4V,20%,X6S,CH622KMEB02':;

SECTION_NUMBER 1
 '@T6G_MB_LIB.T6G(SCH_1):PAGE73_I61@PURE_QUANTA.Q_CAP(CHIPS)':
 C_PATH='@t6g_mb_lib.t6g(sch_1):page73_i61@pure_quanta.q_cap(chips)',
 P_PATH='@t6g_mb_lib.t6g(sch_1):page74_i61@pure_quanta.q_cap(chips)',
 PATH='I61',
 DRAWING='@T6G_MB_LIB.T6G(SCH_1):PAGE73',
 TOLERANCE='20%',
 MATERIAL='X6S',
 PHYS_PAGE='74',
 XY='(1300,5875)',
 ROT='0',
 VER='1',
 PACK_TYPE='C0402',
 LOCATION='C2421',
 CDS_LIB='pure_quanta',
 CDS_PART_NAME='Q_CAP_C0402-22UF,4V,20%,X6S,CH622KMEB02',
 VOLTAGE='4V',
 PART_NUMBER='CH622KMEB02',
 VALUE='22UF',
 PRIM_FILE='./archive_libs/logical/q_cap/chips/chips.prt';

PART_NAME
 C2422 'Q_CAP_C0402-22UF,4V,20%,X6S,CH622KMEB02':;

SECTION_NUMBER 1
 '@T6G_MB_LIB.T6G(SCH_1):PAGE73_I60@PURE_QUANTA.Q_CAP(CHIPS)':
 C_PATH='@t6g_mb_lib.t6g(sch_1):page73_i60@pure_quanta.q_cap(chips)',
 P_PATH='@t6g_mb_lib.t6g(sch_1):page74_i60@pure_quanta.q_cap(chips)',
 PATH='I60',
 DRAWING='@T6G_MB_LIB.T6G(SCH_1):PAGE73',
 TOLERANCE='20%',
 MATERIAL='X6S',
 PHYS_PAGE='74',
 XY='(1300,5225)',
 ROT='0',
 VER='1',
 PACK_TYPE='C0402',
 LOCATION='C2422',
 CDS_LIB='pure_quanta',
 CDS_PART_NAME='Q_CAP_C0402-22UF,4V,20%,X6S,CH622KMEB02',
 VOLTAGE='4V',
 PART_NUMBER='CH622KMEB02',
 VALUE='22UF',
 PRIM_FILE='./archive_libs/logical/q_cap/chips/chips.prt';

PART_NAME
 C2423 'Q_CAP_C0402-22UF,4V,20%,X6S,CH622KMEB02':;

SECTION_NUMBER 1
 '@T6G_MB_LIB.T6G(SCH_1):PAGE73_I58@PURE_QUANTA.Q_CAP(CHIPS)':
 C_PATH='@t6g_mb_lib.t6g(sch_1):page73_i58@pure_quanta.q_cap(chips)',
 P_PATH='@t6g_mb_lib.t6g(sch_1):page74_i58@pure_quanta.q_cap(chips)',
 PATH='I58',
 DRAWING='@T6G_MB_LIB.T6G(SCH_1):PAGE73',
 TOLERANCE='20%',
 MATERIAL='X6S',
 PHYS_PAGE='74',
 XY='(1300,4550)',
 ROT='0',
 VER='1',
 PACK_TYPE='C0402',
 LOCATION='C2423',
 CDS_LIB='pure_quanta',
 CDS_PART_NAME='Q_CAP_C0402-22UF,4V,20%,X6S,CH622KMEB02',
 VOLTAGE='4V',
 PART_NUMBER='CH622KMEB02',
 VALUE='22UF',
 PRIM_FILE='./archive_libs/logical/q_cap/chips/chips.prt';

PART_NAME
 C2424 'Q_CAP_C0402-22UF,4V,20%,X6S,CH622KMEB02':;

SECTION_NUMBER 1
 '@T6G_MB_LIB.T6G(SCH_1):PAGE73_I22@PURE_QUANTA.Q_CAP(CHIPS)':
 C_PATH='@t6g_mb_lib.t6g(sch_1):page73_i22@pure_quanta.q_cap(chips)',
 P_PATH='@t6g_mb_lib.t6g(sch_1):page74_i22@pure_quanta.q_cap(chips)',
 PATH='I22',
 DRAWING='@T6G_MB_LIB.T6G(SCH_1):PAGE73',
 TOLERANCE='20%',
 MATERIAL='X6S',
 PHYS_PAGE='74',
 XY='(1300,3850)',
 ROT='0',
 VER='1',
 PACK_TYPE='C0402',
 LOCATION='C2424',
 CDS_LIB='pure_quanta',
 CDS_PART_NAME='Q_CAP_C0402-22UF,4V,20%,X6S,CH622KMEB02',
 VOLTAGE='4V',
 PART_NUMBER='CH622KMEB02',
 VALUE='22UF',
 PRIM_FILE='./archive_libs/logical/q_cap/chips/chips.prt';

PART_NAME
 C2425 'Q_CAP_C0402-22UF,4V,20%,X6S,CH622KMEB02':;

SECTION_NUMBER 1
 '@T6G_MB_LIB.T6G(SCH_1):PAGE73_I21@PURE_QUANTA.Q_CAP(CHIPS)':
 C_PATH='@t6g_mb_lib.t6g(sch_1):page73_i21@pure_quanta.q_cap(chips)',
 P_PATH='@t6g_mb_lib.t6g(sch_1):page74_i21@pure_quanta.q_cap(chips)',
 PATH='I21',
 DRAWING='@T6G_MB_LIB.T6G(SCH_1):PAGE73',
 TOLERANCE='20%',
 MATERIAL='X6S',
 PHYS_PAGE='74',
 XY='(1300,3150)',
 ROT='0',
 VER='1',
 PACK_TYPE='C0402',
 LOCATION='C2425',
 CDS_LIB='pure_quanta',
 CDS_PART_NAME='Q_CAP_C0402-22UF,4V,20%,X6S,CH622KMEB02',
 VOLTAGE='4V',
 PART_NUMBER='CH622KMEB02',
 VALUE='22UF',
 PRIM_FILE='./archive_libs/logical/q_cap/chips/chips.prt';

PART_NAME
 C2426 'Q_CAP_C0402-22UF,4V,20%,X6S,CH622KMEB02':;

SECTION_NUMBER 1
 '@T6G_MB_LIB.T6G(SCH_1):PAGE73_I19@PURE_QUANTA.Q_CAP(CHIPS)':
 C_PATH='@t6g_mb_lib.t6g(sch_1):page73_i19@pure_quanta.q_cap(chips)',
 P_PATH='@t6g_mb_lib.t6g(sch_1):page74_i19@pure_quanta.q_cap(chips)',
 PATH='I19',
 DRAWING='@T6G_MB_LIB.T6G(SCH_1):PAGE73',
 TOLERANCE='20%',
 MATERIAL='X6S',
 PHYS_PAGE='74',
 XY='(1300,2475)',
 ROT='0',
 VER='1',
 PACK_TYPE='C0402',
 LOCATION='C2426',
 CDS_LIB='pure_quanta',
 CDS_PART_NAME='Q_CAP_C0402-22UF,4V,20%,X6S,CH622KMEB02',
 VOLTAGE='4V',
 PART_NUMBER='CH622KMEB02',
 VALUE='22UF',
 PRIM_FILE='./archive_libs/logical/q_cap/chips/chips.prt';

PART_NAME
 C2427 'Q_CAP_C0402-22UF,4V,20%,X6S,CH622KMEB02':;

SECTION_NUMBER 1
 '@T6G_MB_LIB.T6G(SCH_1):PAGE73_I7@PURE_QUANTA.Q_CAP(CHIPS)':
 C_PATH='@t6g_mb_lib.t6g(sch_1):page73_i7@pure_quanta.q_cap(chips)',
 P_PATH='@t6g_mb_lib.t6g(sch_1):page74_i7@pure_quanta.q_cap(chips)',
 PATH='I7',
 DRAWING='@T6G_MB_LIB.T6G(SCH_1):PAGE73',
 TOLERANCE='20%',
 MATERIAL='X6S',
 PHYS_PAGE='74',
 XY='(1300,1800)',
 ROT='0',
 VER='1',
 PACK_TYPE='C0402',
 LOCATION='C2427',
 CDS_LIB='pure_quanta',
 CDS_PART_NAME='Q_CAP_C0402-22UF,4V,20%,X6S,CH622KMEB02',
 VOLTAGE='4V',
 PART_NUMBER='CH622KMEB02',
 VALUE='22UF',
 PRIM_FILE='./archive_libs/logical/q_cap/chips/chips.prt';

PART_NAME
 C2428 'Q_CAP_C0402-22UF,4V,20%,X6S,CH622KMEB02':;

SECTION_NUMBER 1
 '@T6G_MB_LIB.T6G(SCH_1):PAGE73_I175@PURE_QUANTA.Q_CAP(CHIPS)':
 C_PATH='@t6g_mb_lib.t6g(sch_1):page73_i175@pure_quanta.q_cap(chips)',
 P_PATH='@t6g_mb_lib.t6g(sch_1):page74_i175@pure_quanta.q_cap(chips)',
 PATH='I175',
 DRAWING='@T6G_MB_LIB.T6G(SCH_1):PAGE73',
 TOLERANCE='20%',
 MATERIAL='X6S',
 PHYS_PAGE='74',
 XY='(1750,5875)',
 ROT='0',
 VER='1',
 PACK_TYPE='C0402',
 LOCATION='C2428',
 CDS_LIB='pure_quanta',
 CDS_PART_NAME='Q_CAP_C0402-22UF,4V,20%,X6S,CH622KMEB02',
 VOLTAGE='4V',
 PART_NUMBER='CH622KMEB02',
 VALUE='22UF',
 PRIM_FILE='./archive_libs/logical/q_cap/chips/chips.prt';

PART_NAME
 C2429 'Q_CAP_C0402-22UF,4V,20%,X6S,CH622KMEB02':;

SECTION_NUMBER 1
 '@T6G_MB_LIB.T6G(SCH_1):PAGE73_I62@PURE_QUANTA.Q_CAP(CHIPS)':
 C_PATH='@t6g_mb_lib.t6g(sch_1):page73_i62@pure_quanta.q_cap(chips)',
 P_PATH='@t6g_mb_lib.t6g(sch_1):page74_i62@pure_quanta.q_cap(chips)',
 PATH='I62',
 DRAWING='@T6G_MB_LIB.T6G(SCH_1):PAGE73',
 TOLERANCE='20%',
 MATERIAL='X6S',
 PHYS_PAGE='74',
 XY='(1750,5225)',
 ROT='0',
 VER='1',
 PACK_TYPE='C0402',
 LOCATION='C2429',
 CDS_LIB='pure_quanta',
 CDS_PART_NAME='Q_CAP_C0402-22UF,4V,20%,X6S,CH622KMEB02',
 VOLTAGE='4V',
 PART_NUMBER='CH622KMEB02',
 VALUE='22UF',
 PRIM_FILE='./archive_libs/logical/q_cap/chips/chips.prt';

PART_NAME
 C2430 'Q_CAP_C0402-22UF,4V,20%,X6S,CH622KMEB02':;

SECTION_NUMBER 1
 '@T6G_MB_LIB.T6G(SCH_1):PAGE73_I59@PURE_QUANTA.Q_CAP(CHIPS)':
 C_PATH='@t6g_mb_lib.t6g(sch_1):page73_i59@pure_quanta.q_cap(chips)',
 P_PATH='@t6g_mb_lib.t6g(sch_1):page74_i59@pure_quanta.q_cap(chips)',
 PATH='I59',
 DRAWING='@T6G_MB_LIB.T6G(SCH_1):PAGE73',
 TOLERANCE='20%',
 MATERIAL='X6S',
 PHYS_PAGE='74',
 XY='(1750,4550)',
 ROT='0',
 VER='1',
 PACK_TYPE='C0402',
 LOCATION='C2430',
 CDS_LIB='pure_quanta',
 CDS_PART_NAME='Q_CAP_C0402-22UF,4V,20%,X6S,CH622KMEB02',
 VOLTAGE='4V',
 PART_NUMBER='CH622KMEB02',
 VALUE='22UF',
 PRIM_FILE='./archive_libs/logical/q_cap/chips/chips.prt';

PART_NAME
 C2431 'Q_CAP_C0402-22UF,4V,20%,X6S,CH622KMEB02':;

SECTION_NUMBER 1
 '@T6G_MB_LIB.T6G(SCH_1):PAGE73_I24@PURE_QUANTA.Q_CAP(CHIPS)':
 C_PATH='@t6g_mb_lib.t6g(sch_1):page73_i24@pure_quanta.q_cap(chips)',
 P_PATH='@t6g_mb_lib.t6g(sch_1):page74_i24@pure_quanta.q_cap(chips)',
 PATH='I24',
 DRAWING='@T6G_MB_LIB.T6G(SCH_1):PAGE73',
 TOLERANCE='20%',
 MATERIAL='X6S',
 PHYS_PAGE='74',
 XY='(1750,3850)',
 ROT='0',
 VER='1',
 PACK_TYPE='C0402',
 LOCATION='C2431',
 CDS_LIB='pure_quanta',
 CDS_PART_NAME='Q_CAP_C0402-22UF,4V,20%,X6S,CH622KMEB02',
 VOLTAGE='4V',
 PART_NUMBER='CH622KMEB02',
 VALUE='22UF',
 PRIM_FILE='./archive_libs/logical/q_cap/chips/chips.prt';

PART_NAME
 C2432 'Q_CAP_C0402-22UF,4V,20%,X6S,CH622KMEB02':;

SECTION_NUMBER 1
 '@T6G_MB_LIB.T6G(SCH_1):PAGE73_I23@PURE_QUANTA.Q_CAP(CHIPS)':
 C_PATH='@t6g_mb_lib.t6g(sch_1):page73_i23@pure_quanta.q_cap(chips)',
 P_PATH='@t6g_mb_lib.t6g(sch_1):page74_i23@pure_quanta.q_cap(chips)',
 PATH='I23',
 DRAWING='@T6G_MB_LIB.T6G(SCH_1):PAGE73',
 TOLERANCE='20%',
 MATERIAL='X6S',
 PHYS_PAGE='74',
 XY='(1750,3150)',
 ROT='0',
 VER='1',
 PACK_TYPE='C0402',
 LOCATION='C2432',
 CDS_LIB='pure_quanta',
 CDS_PART_NAME='Q_CAP_C0402-22UF,4V,20%,X6S,CH622KMEB02',
 VOLTAGE='4V',
 PART_NUMBER='CH622KMEB02',
 VALUE='22UF',
 PRIM_FILE='./archive_libs/logical/q_cap/chips/chips.prt';

PART_NAME
 C2433 'Q_CAP_C0402-22UF,4V,20%,X6S,CH622KMEB02':;

SECTION_NUMBER 1
 '@T6G_MB_LIB.T6G(SCH_1):PAGE73_I20@PURE_QUANTA.Q_CAP(CHIPS)':
 C_PATH='@t6g_mb_lib.t6g(sch_1):page73_i20@pure_quanta.q_cap(chips)',
 P_PATH='@t6g_mb_lib.t6g(sch_1):page74_i20@pure_quanta.q_cap(chips)',
 PATH='I20',
 DRAWING='@T6G_MB_LIB.T6G(SCH_1):PAGE73',
 TOLERANCE='20%',
 MATERIAL='X6S',
 PHYS_PAGE='74',
 XY='(1750,2475)',
 ROT='0',
 VER='1',
 PACK_TYPE='C0402',
 LOCATION='C2433',
 CDS_LIB='pure_quanta',
 CDS_PART_NAME='Q_CAP_C0402-22UF,4V,20%,X6S,CH622KMEB02',
 VOLTAGE='4V',
 PART_NUMBER='CH622KMEB02',
 VALUE='22UF',
 PRIM_FILE='./archive_libs/logical/q_cap/chips/chips.prt';

PART_NAME
 C2434 'Q_CAP_C0402-22UF,4V,20%,X6S,CH622KMEB02':;

SECTION_NUMBER 1
 '@T6G_MB_LIB.T6G(SCH_1):PAGE73_I9@PURE_QUANTA.Q_CAP(CHIPS)':
 C_PATH='@t6g_mb_lib.t6g(sch_1):page73_i9@pure_quanta.q_cap(chips)',
 P_PATH='@t6g_mb_lib.t6g(sch_1):page74_i9@pure_quanta.q_cap(chips)',
 PATH='I9',
 DRAWING='@T6G_MB_LIB.T6G(SCH_1):PAGE73',
 TOLERANCE='20%',
 MATERIAL='X6S',
 PHYS_PAGE='74',
 XY='(1750,1800)',
 ROT='0',
 VER='1',
 PACK_TYPE='C0402',
 LOCATION='C2434',
 CDS_LIB='pure_quanta',
 CDS_PART_NAME='Q_CAP_C0402-22UF,4V,20%,X6S,CH622KMEB02',
 VOLTAGE='4V',
 PART_NUMBER='CH622KMEB02',
 VALUE='22UF',
 PRIM_FILE='./archive_libs/logical/q_cap/chips/chips.prt';

PART_NAME
 C2435 'Q_CAP_C0402-22UF,4V,20%,X6S,CH622KMEB02':;

SECTION_NUMBER 1
 '@T6G_MB_LIB.T6G(SCH_1):PAGE73_I174@PURE_QUANTA.Q_CAP(CHIPS)':
 C_PATH='@t6g_mb_lib.t6g(sch_1):page73_i174@pure_quanta.q_cap(chips)',
 P_PATH='@t6g_mb_lib.t6g(sch_1):page74_i174@pure_quanta.q_cap(chips)',
 PATH='I174',
 DRAWING='@T6G_MB_LIB.T6G(SCH_1):PAGE73',
 TOLERANCE='20%',
 MATERIAL='X6S',
 PHYS_PAGE='74',
 XY='(2200,5875)',
 ROT='0',
 VER='1',
 PACK_TYPE='C0402',
 LOCATION='C2435',
 CDS_LIB='pure_quanta',
 CDS_PART_NAME='Q_CAP_C0402-22UF,4V,20%,X6S,CH622KMEB02',
 VOLTAGE='4V',
 PART_NUMBER='CH622KMEB02',
 VALUE='22UF',
 PRIM_FILE='./archive_libs/logical/q_cap/chips/chips.prt';

PART_NAME
 C2436 'Q_CAP_C0402-22UF,4V,20%,X6S,CH622KMEB02':;

SECTION_NUMBER 1
 '@T6G_MB_LIB.T6G(SCH_1):PAGE73_I66@PURE_QUANTA.Q_CAP(CHIPS)':
 C_PATH='@t6g_mb_lib.t6g(sch_1):page73_i66@pure_quanta.q_cap(chips)',
 P_PATH='@t6g_mb_lib.t6g(sch_1):page74_i66@pure_quanta.q_cap(chips)',
 PATH='I66',
 DRAWING='@T6G_MB_LIB.T6G(SCH_1):PAGE73',
 TOLERANCE='20%',
 MATERIAL='X6S',
 PHYS_PAGE='74',
 XY='(2200,5225)',
 ROT='0',
 VER='1',
 PACK_TYPE='C0402',
 LOCATION='C2436',
 CDS_LIB='pure_quanta',
 CDS_PART_NAME='Q_CAP_C0402-22UF,4V,20%,X6S,CH622KMEB02',
 VOLTAGE='4V',
 PART_NUMBER='CH622KMEB02',
 VALUE='22UF',
 PRIM_FILE='./archive_libs/logical/q_cap/chips/chips.prt';

PART_NAME
 C2437 'Q_CAP_C0402-22UF,4V,20%,X6S,CH622KMEB02':;

SECTION_NUMBER 1
 '@T6G_MB_LIB.T6G(SCH_1):PAGE73_I64@PURE_QUANTA.Q_CAP(CHIPS)':
 C_PATH='@t6g_mb_lib.t6g(sch_1):page73_i64@pure_quanta.q_cap(chips)',
 P_PATH='@t6g_mb_lib.t6g(sch_1):page74_i64@pure_quanta.q_cap(chips)',
 PATH='I64',
 DRAWING='@T6G_MB_LIB.T6G(SCH_1):PAGE73',
 TOLERANCE='20%',
 MATERIAL='X6S',
 PHYS_PAGE='74',
 XY='(2200,4550)',
 ROT='0',
 VER='1',
 PACK_TYPE='C0402',
 LOCATION='C2437',
 CDS_LIB='pure_quanta',
 CDS_PART_NAME='Q_CAP_C0402-22UF,4V,20%,X6S,CH622KMEB02',
 VOLTAGE='4V',
 PART_NUMBER='CH622KMEB02',
 VALUE='22UF',
 PRIM_FILE='./archive_libs/logical/q_cap/chips/chips.prt';

PART_NAME
 C2438 'Q_CAP_C0402-22UF,4V,20%,X6S,CH622KMEB02':;

SECTION_NUMBER 1
 '@T6G_MB_LIB.T6G(SCH_1):PAGE73_I37@PURE_QUANTA.Q_CAP(CHIPS)':
 C_PATH='@t6g_mb_lib.t6g(sch_1):page73_i37@pure_quanta.q_cap(chips)',
 P_PATH='@t6g_mb_lib.t6g(sch_1):page74_i37@pure_quanta.q_cap(chips)',
 PATH='I37',
 DRAWING='@T6G_MB_LIB.T6G(SCH_1):PAGE73',
 TOLERANCE='20%',
 MATERIAL='X6S',
 PHYS_PAGE='74',
 XY='(2200,3850)',
 ROT='0',
 VER='1',
 PACK_TYPE='C0402',
 LOCATION='C2438',
 CDS_LIB='pure_quanta',
 CDS_PART_NAME='Q_CAP_C0402-22UF,4V,20%,X6S,CH622KMEB02',
 VOLTAGE='4V',
 PART_NUMBER='CH622KMEB02',
 VALUE='22UF',
 PRIM_FILE='./archive_libs/logical/q_cap/chips/chips.prt';

PART_NAME
 C2439 'Q_CAP_C0402-22UF,4V,20%,X6S,CH622KMEB02':;

SECTION_NUMBER 1
 '@T6G_MB_LIB.T6G(SCH_1):PAGE73_I36@PURE_QUANTA.Q_CAP(CHIPS)':
 C_PATH='@t6g_mb_lib.t6g(sch_1):page73_i36@pure_quanta.q_cap(chips)',
 P_PATH='@t6g_mb_lib.t6g(sch_1):page74_i36@pure_quanta.q_cap(chips)',
 PATH='I36',
 DRAWING='@T6G_MB_LIB.T6G(SCH_1):PAGE73',
 TOLERANCE='20%',
 MATERIAL='X6S',
 PHYS_PAGE='74',
 XY='(2200,3150)',
 ROT='0',
 VER='1',
 PACK_TYPE='C0402',
 LOCATION='C2439',
 CDS_LIB='pure_quanta',
 CDS_PART_NAME='Q_CAP_C0402-22UF,4V,20%,X6S,CH622KMEB02',
 VOLTAGE='4V',
 PART_NUMBER='CH622KMEB02',
 VALUE='22UF',
 PRIM_FILE='./archive_libs/logical/q_cap/chips/chips.prt';

PART_NAME
 C2440 'Q_CAP_C0402-22UF,4V,20%,X6S,CH622KMEB02':;

SECTION_NUMBER 1
 '@T6G_MB_LIB.T6G(SCH_1):PAGE73_I34@PURE_QUANTA.Q_CAP(CHIPS)':
 C_PATH='@t6g_mb_lib.t6g(sch_1):page73_i34@pure_quanta.q_cap(chips)',
 P_PATH='@t6g_mb_lib.t6g(sch_1):page74_i34@pure_quanta.q_cap(chips)',
 PATH='I34',
 DRAWING='@T6G_MB_LIB.T6G(SCH_1):PAGE73',
 TOLERANCE='20%',
 MATERIAL='X6S',
 PHYS_PAGE='74',
 XY='(2200,2475)',
 ROT='0',
 VER='1',
 PACK_TYPE='C0402',
 LOCATION='C2440',
 CDS_LIB='pure_quanta',
 CDS_PART_NAME='Q_CAP_C0402-22UF,4V,20%,X6S,CH622KMEB02',
 VOLTAGE='4V',
 PART_NUMBER='CH622KMEB02',
 VALUE='22UF',
 PRIM_FILE='./archive_libs/logical/q_cap/chips/chips.prt';

PART_NAME
 C2441 'Q_CAP_C0402-22UF,4V,20%,X6S,CH622KMEB02':;

SECTION_NUMBER 1
 '@T6G_MB_LIB.T6G(SCH_1):PAGE73_I26@PURE_QUANTA.Q_CAP(CHIPS)':
 C_PATH='@t6g_mb_lib.t6g(sch_1):page73_i26@pure_quanta.q_cap(chips)',
 P_PATH='@t6g_mb_lib.t6g(sch_1):page74_i26@pure_quanta.q_cap(chips)',
 PATH='I26',
 DRAWING='@T6G_MB_LIB.T6G(SCH_1):PAGE73',
 TOLERANCE='20%',
 MATERIAL='X6S',
 PHYS_PAGE='74',
 XY='(2200,1800)',
 ROT='0',
 VER='1',
 PACK_TYPE='C0402',
 LOCATION='C2441',
 CDS_LIB='pure_quanta',
 CDS_PART_NAME='Q_CAP_C0402-22UF,4V,20%,X6S,CH622KMEB02',
 VOLTAGE='4V',
 PART_NUMBER='CH622KMEB02',
 VALUE='22UF',
 PRIM_FILE='./archive_libs/logical/q_cap/chips/chips.prt';

PART_NAME
 C2442 'Q_CAP_C0402-22UF,4V,20%,X6S,CH622KMEB02':;

SECTION_NUMBER 1
 '@T6G_MB_LIB.T6G(SCH_1):PAGE73_I173@PURE_QUANTA.Q_CAP(CHIPS)':
 C_PATH='@t6g_mb_lib.t6g(sch_1):page73_i173@pure_quanta.q_cap(chips)',
 P_PATH='@t6g_mb_lib.t6g(sch_1):page74_i173@pure_quanta.q_cap(chips)',
 PATH='I173',
 DRAWING='@T6G_MB_LIB.T6G(SCH_1):PAGE73',
 TOLERANCE='20%',
 MATERIAL='X6S',
 PHYS_PAGE='74',
 XY='(2650,5875)',
 ROT='0',
 VER='1',
 PACK_TYPE='C0402',
 LOCATION='C2442',
 CDS_LIB='pure_quanta',
 CDS_PART_NAME='Q_CAP_C0402-22UF,4V,20%,X6S,CH622KMEB02',
 VOLTAGE='4V',
 PART_NUMBER='CH622KMEB02',
 VALUE='22UF',
 PRIM_FILE='./archive_libs/logical/q_cap/chips/chips.prt';

PART_NAME
 C2443 'Q_CAP_C0402-22UF,4V,20%,X6S,CH622KMEB02':;

SECTION_NUMBER 1
 '@T6G_MB_LIB.T6G(SCH_1):PAGE73_I67@PURE_QUANTA.Q_CAP(CHIPS)':
 C_PATH='@t6g_mb_lib.t6g(sch_1):page73_i67@pure_quanta.q_cap(chips)',
 P_PATH='@t6g_mb_lib.t6g(sch_1):page74_i67@pure_quanta.q_cap(chips)',
 PATH='I67',
 DRAWING='@T6G_MB_LIB.T6G(SCH_1):PAGE73',
 TOLERANCE='20%',
 MATERIAL='X6S',
 PHYS_PAGE='74',
 XY='(2650,5225)',
 ROT='0',
 VER='1',
 PACK_TYPE='C0402',
 LOCATION='C2443',
 CDS_LIB='pure_quanta',
 CDS_PART_NAME='Q_CAP_C0402-22UF,4V,20%,X6S,CH622KMEB02',
 VOLTAGE='4V',
 PART_NUMBER='CH622KMEB02',
 VALUE='22UF',
 PRIM_FILE='./archive_libs/logical/q_cap/chips/chips.prt';

PART_NAME
 C2444 'Q_CAP_C0402-22UF,4V,20%,X6S,CH622KMEB02':;

SECTION_NUMBER 1
 '@T6G_MB_LIB.T6G(SCH_1):PAGE73_I65@PURE_QUANTA.Q_CAP(CHIPS)':
 C_PATH='@t6g_mb_lib.t6g(sch_1):page73_i65@pure_quanta.q_cap(chips)',
 P_PATH='@t6g_mb_lib.t6g(sch_1):page74_i65@pure_quanta.q_cap(chips)',
 PATH='I65',
 DRAWING='@T6G_MB_LIB.T6G(SCH_1):PAGE73',
 TOLERANCE='20%',
 MATERIAL='X6S',
 PHYS_PAGE='74',
 XY='(2650,4550)',
 ROT='0',
 VER='1',
 PACK_TYPE='C0402',
 LOCATION='C2444',
 CDS_LIB='pure_quanta',
 CDS_PART_NAME='Q_CAP_C0402-22UF,4V,20%,X6S,CH622KMEB02',
 VOLTAGE='4V',
 PART_NUMBER='CH622KMEB02',
 VALUE='22UF',
 PRIM_FILE='./archive_libs/logical/q_cap/chips/chips.prt';

PART_NAME
 C2445 'Q_CAP_C0402-22UF,4V,20%,X6S,CH622KMEB02':;

SECTION_NUMBER 1
 '@T6G_MB_LIB.T6G(SCH_1):PAGE73_I39@PURE_QUANTA.Q_CAP(CHIPS)':
 C_PATH='@t6g_mb_lib.t6g(sch_1):page73_i39@pure_quanta.q_cap(chips)',
 P_PATH='@t6g_mb_lib.t6g(sch_1):page74_i39@pure_quanta.q_cap(chips)',
 PATH='I39',
 DRAWING='@T6G_MB_LIB.T6G(SCH_1):PAGE73',
 TOLERANCE='20%',
 MATERIAL='X6S',
 PHYS_PAGE='74',
 XY='(2650,3850)',
 ROT='0',
 VER='1',
 PACK_TYPE='C0402',
 LOCATION='C2445',
 CDS_LIB='pure_quanta',
 CDS_PART_NAME='Q_CAP_C0402-22UF,4V,20%,X6S,CH622KMEB02',
 VOLTAGE='4V',
 PART_NUMBER='CH622KMEB02',
 VALUE='22UF',
 PRIM_FILE='./archive_libs/logical/q_cap/chips/chips.prt';

PART_NAME
 C2446 'Q_CAP_C0402-22UF,4V,20%,X6S,CH622KMEB02':;

SECTION_NUMBER 1
 '@T6G_MB_LIB.T6G(SCH_1):PAGE73_I38@PURE_QUANTA.Q_CAP(CHIPS)':
 C_PATH='@t6g_mb_lib.t6g(sch_1):page73_i38@pure_quanta.q_cap(chips)',
 P_PATH='@t6g_mb_lib.t6g(sch_1):page74_i38@pure_quanta.q_cap(chips)',
 PATH='I38',
 DRAWING='@T6G_MB_LIB.T6G(SCH_1):PAGE73',
 TOLERANCE='20%',
 MATERIAL='X6S',
 PHYS_PAGE='74',
 XY='(2650,3150)',
 ROT='0',
 VER='1',
 PACK_TYPE='C0402',
 LOCATION='C2446',
 CDS_LIB='pure_quanta',
 CDS_PART_NAME='Q_CAP_C0402-22UF,4V,20%,X6S,CH622KMEB02',
 VOLTAGE='4V',
 PART_NUMBER='CH622KMEB02',
 VALUE='22UF',
 PRIM_FILE='./archive_libs/logical/q_cap/chips/chips.prt';

PART_NAME
 C2447 'Q_CAP_C0402-22UF,4V,20%,X6S,CH622KMEB02':;

SECTION_NUMBER 1
 '@T6G_MB_LIB.T6G(SCH_1):PAGE73_I35@PURE_QUANTA.Q_CAP(CHIPS)':
 C_PATH='@t6g_mb_lib.t6g(sch_1):page73_i35@pure_quanta.q_cap(chips)',
 P_PATH='@t6g_mb_lib.t6g(sch_1):page74_i35@pure_quanta.q_cap(chips)',
 PATH='I35',
 DRAWING='@T6G_MB_LIB.T6G(SCH_1):PAGE73',
 TOLERANCE='20%',
 MATERIAL='X6S',
 PHYS_PAGE='74',
 XY='(2650,2475)',
 ROT='0',
 VER='1',
 PACK_TYPE='C0402',
 LOCATION='C2447',
 CDS_LIB='pure_quanta',
 CDS_PART_NAME='Q_CAP_C0402-22UF,4V,20%,X6S,CH622KMEB02',
 VOLTAGE='4V',
 PART_NUMBER='CH622KMEB02',
 VALUE='22UF',
 PRIM_FILE='./archive_libs/logical/q_cap/chips/chips.prt';

PART_NAME
 C2448 'Q_CAP_C0402-22UF,4V,20%,X6S,CH622KMEB02':;

SECTION_NUMBER 1
 '@T6G_MB_LIB.T6G(SCH_1):PAGE73_I28@PURE_QUANTA.Q_CAP(CHIPS)':
 C_PATH='@t6g_mb_lib.t6g(sch_1):page73_i28@pure_quanta.q_cap(chips)',
 P_PATH='@t6g_mb_lib.t6g(sch_1):page74_i28@pure_quanta.q_cap(chips)',
 PATH='I28',
 DRAWING='@T6G_MB_LIB.T6G(SCH_1):PAGE73',
 TOLERANCE='20%',
 MATERIAL='X6S',
 PHYS_PAGE='74',
 XY='(2650,1800)',
 ROT='0',
 VER='1',
 PACK_TYPE='C0402',
 LOCATION='C2448',
 CDS_LIB='pure_quanta',
 CDS_PART_NAME='Q_CAP_C0402-22UF,4V,20%,X6S,CH622KMEB02',
 VOLTAGE='4V',
 PART_NUMBER='CH622KMEB02',
 VALUE='22UF',
 PRIM_FILE='./archive_libs/logical/q_cap/chips/chips.prt';

PART_NAME
 C2449 'Q_CAP_C0402-22UF,4V,20%,X6S,CH622KMEB02':;

SECTION_NUMBER 1
 '@T6G_MB_LIB.T6G(SCH_1):PAGE73_I68@PURE_QUANTA.Q_CAP(CHIPS)':
 C_PATH='@t6g_mb_lib.t6g(sch_1):page73_i68@pure_quanta.q_cap(chips)',
 P_PATH='@t6g_mb_lib.t6g(sch_1):page74_i68@pure_quanta.q_cap(chips)',
 PATH='I68',
 DRAWING='@T6G_MB_LIB.T6G(SCH_1):PAGE73',
 TOLERANCE='20%',
 MATERIAL='X6S',
 PHYS_PAGE='74',
 XY='(3100,5875)',
 ROT='0',
 VER='1',
 PACK_TYPE='C0402',
 LOCATION='C2449',
 CDS_LIB='pure_quanta',
 CDS_PART_NAME='Q_CAP_C0402-22UF,4V,20%,X6S,CH622KMEB02',
 VOLTAGE='4V',
 PART_NUMBER='CH622KMEB02',
 VALUE='22UF',
 PRIM_FILE='./archive_libs/logical/q_cap/chips/chips.prt';

PART_NAME
 C2450 'Q_CAP_C0402-22UF,4V,20%,X6S,CH622KMEB02':;

SECTION_NUMBER 1
 '@T6G_MB_LIB.T6G(SCH_1):PAGE73_I69@PURE_QUANTA.Q_CAP(CHIPS)':
 C_PATH='@t6g_mb_lib.t6g(sch_1):page73_i69@pure_quanta.q_cap(chips)',
 P_PATH='@t6g_mb_lib.t6g(sch_1):page74_i69@pure_quanta.q_cap(chips)',
 PATH='I69',
 DRAWING='@T6G_MB_LIB.T6G(SCH_1):PAGE73',
 TOLERANCE='20%',
 MATERIAL='X6S',
 PHYS_PAGE='74',
 XY='(3100,5225)',
 ROT='0',
 VER='1',
 PACK_TYPE='C0402',
 LOCATION='C2450',
 CDS_LIB='pure_quanta',
 CDS_PART_NAME='Q_CAP_C0402-22UF,4V,20%,X6S,CH622KMEB02',
 VOLTAGE='4V',
 PART_NUMBER='CH622KMEB02',
 VALUE='22UF',
 PRIM_FILE='./archive_libs/logical/q_cap/chips/chips.prt';

PART_NAME
 C2451 'Q_CAP_C0402-22UF,4V,20%,X6S,CH622KMEB02':;

SECTION_NUMBER 1
 '@T6G_MB_LIB.T6G(SCH_1):PAGE73_I70@PURE_QUANTA.Q_CAP(CHIPS)':
 C_PATH='@t6g_mb_lib.t6g(sch_1):page73_i70@pure_quanta.q_cap(chips)',
 P_PATH='@t6g_mb_lib.t6g(sch_1):page74_i70@pure_quanta.q_cap(chips)',
 PATH='I70',
 DRAWING='@T6G_MB_LIB.T6G(SCH_1):PAGE73',
 TOLERANCE='20%',
 MATERIAL='X6S',
 PHYS_PAGE='74',
 XY='(3100,4550)',
 ROT='0',
 VER='1',
 PACK_TYPE='C0402',
 LOCATION='C2451',
 CDS_LIB='pure_quanta',
 CDS_PART_NAME='Q_CAP_C0402-22UF,4V,20%,X6S,CH622KMEB02',
 VOLTAGE='4V',
 PART_NUMBER='CH622KMEB02',
 VALUE='22UF',
 PRIM_FILE='./archive_libs/logical/q_cap/chips/chips.prt';

PART_NAME
 C2452 'Q_CAP_C0402-22UF,4V,20%,X6S,CH622KMEB02':;

SECTION_NUMBER 1
 '@T6G_MB_LIB.T6G(SCH_1):PAGE73_I40@PURE_QUANTA.Q_CAP(CHIPS)':
 C_PATH='@t6g_mb_lib.t6g(sch_1):page73_i40@pure_quanta.q_cap(chips)',
 P_PATH='@t6g_mb_lib.t6g(sch_1):page74_i40@pure_quanta.q_cap(chips)',
 PATH='I40',
 DRAWING='@T6G_MB_LIB.T6G(SCH_1):PAGE73',
 TOLERANCE='20%',
 MATERIAL='X6S',
 PHYS_PAGE='74',
 XY='(3100,3850)',
 ROT='0',
 VER='1',
 PACK_TYPE='C0402',
 LOCATION='C2452',
 CDS_LIB='pure_quanta',
 CDS_PART_NAME='Q_CAP_C0402-22UF,4V,20%,X6S,CH622KMEB02',
 VOLTAGE='4V',
 PART_NUMBER='CH622KMEB02',
 VALUE='22UF',
 PRIM_FILE='./archive_libs/logical/q_cap/chips/chips.prt';

PART_NAME
 C2453 'Q_CAP_C0402-22UF,4V,20%,X6S,CH622KMEB02':;

SECTION_NUMBER 1
 '@T6G_MB_LIB.T6G(SCH_1):PAGE73_I41@PURE_QUANTA.Q_CAP(CHIPS)':
 C_PATH='@t6g_mb_lib.t6g(sch_1):page73_i41@pure_quanta.q_cap(chips)',
 P_PATH='@t6g_mb_lib.t6g(sch_1):page74_i41@pure_quanta.q_cap(chips)',
 PATH='I41',
 DRAWING='@T6G_MB_LIB.T6G(SCH_1):PAGE73',
 TOLERANCE='20%',
 MATERIAL='X6S',
 PHYS_PAGE='74',
 XY='(3100,3150)',
 ROT='0',
 VER='1',
 PACK_TYPE='C0402',
 LOCATION='C2453',
 CDS_LIB='pure_quanta',
 CDS_PART_NAME='Q_CAP_C0402-22UF,4V,20%,X6S,CH622KMEB02',
 VOLTAGE='4V',
 PART_NUMBER='CH622KMEB02',
 VALUE='22UF',
 PRIM_FILE='./archive_libs/logical/q_cap/chips/chips.prt';

PART_NAME
 C2454 'Q_CAP_C0402-22UF,4V,20%,X6S,CH622KMEB02':;

SECTION_NUMBER 1
 '@T6G_MB_LIB.T6G(SCH_1):PAGE73_I42@PURE_QUANTA.Q_CAP(CHIPS)':
 C_PATH='@t6g_mb_lib.t6g(sch_1):page73_i42@pure_quanta.q_cap(chips)',
 P_PATH='@t6g_mb_lib.t6g(sch_1):page74_i42@pure_quanta.q_cap(chips)',
 PATH='I42',
 DRAWING='@T6G_MB_LIB.T6G(SCH_1):PAGE73',
 TOLERANCE='20%',
 MATERIAL='X6S',
 PHYS_PAGE='74',
 XY='(3100,2475)',
 ROT='0',
 VER='1',
 PACK_TYPE='C0402',
 LOCATION='C2454',
 CDS_LIB='pure_quanta',
 CDS_PART_NAME='Q_CAP_C0402-22UF,4V,20%,X6S,CH622KMEB02',
 VOLTAGE='4V',
 PART_NUMBER='CH622KMEB02',
 VALUE='22UF',
 PRIM_FILE='./archive_libs/logical/q_cap/chips/chips.prt';

PART_NAME
 C2455 'Q_CAP_C0402-22UF,4V,20%,X6S,CH622KMEB02':;

SECTION_NUMBER 1
 '@T6G_MB_LIB.T6G(SCH_1):PAGE73_I29@PURE_QUANTA.Q_CAP(CHIPS)':
 C_PATH='@t6g_mb_lib.t6g(sch_1):page73_i29@pure_quanta.q_cap(chips)',
 P_PATH='@t6g_mb_lib.t6g(sch_1):page74_i29@pure_quanta.q_cap(chips)',
 PATH='I29',
 DRAWING='@T6G_MB_LIB.T6G(SCH_1):PAGE73',
 TOLERANCE='20%',
 MATERIAL='X6S',
 PHYS_PAGE='74',
 XY='(3100,1800)',
 ROT='0',
 VER='1',
 PACK_TYPE='C0402',
 LOCATION='C2455',
 CDS_LIB='pure_quanta',
 CDS_PART_NAME='Q_CAP_C0402-22UF,4V,20%,X6S,CH622KMEB02',
 VOLTAGE='4V',
 PART_NUMBER='CH622KMEB02',
 VALUE='22UF',
 PRIM_FILE='./archive_libs/logical/q_cap/chips/chips.prt';

PART_NAME
 C2456 'Q_CAP_C0402-22UF,4V,20%,X6S,CH622KMEB02':;

SECTION_NUMBER 1
 '@T6G_MB_LIB.T6G(SCH_1):PAGE73_I74@PURE_QUANTA.Q_CAP(CHIPS)':
 C_PATH='@t6g_mb_lib.t6g(sch_1):page73_i74@pure_quanta.q_cap(chips)',
 P_PATH='@t6g_mb_lib.t6g(sch_1):page74_i74@pure_quanta.q_cap(chips)',
 PATH='I74',
 DRAWING='@T6G_MB_LIB.T6G(SCH_1):PAGE73',
 TOLERANCE='20%',
 MATERIAL='X6S',
 PHYS_PAGE='74',
 XY='(3550,5875)',
 ROT='0',
 VER='1',
 PACK_TYPE='C0402',
 LOCATION='C2456',
 CDS_LIB='pure_quanta',
 CDS_PART_NAME='Q_CAP_C0402-22UF,4V,20%,X6S,CH622KMEB02',
 VOLTAGE='4V',
 PART_NUMBER='CH622KMEB02',
 VALUE='22UF',
 PRIM_FILE='./archive_libs/logical/q_cap/chips/chips.prt';

PART_NAME
 C2457 'Q_CAP_C0402-22UF,4V,20%,X6S,CH622KMEB02':;

SECTION_NUMBER 1
 '@T6G_MB_LIB.T6G(SCH_1):PAGE73_I73@PURE_QUANTA.Q_CAP(CHIPS)':
 C_PATH='@t6g_mb_lib.t6g(sch_1):page73_i73@pure_quanta.q_cap(chips)',
 P_PATH='@t6g_mb_lib.t6g(sch_1):page74_i73@pure_quanta.q_cap(chips)',
 PATH='I73',
 DRAWING='@T6G_MB_LIB.T6G(SCH_1):PAGE73',
 TOLERANCE='20%',
 MATERIAL='X6S',
 PHYS_PAGE='74',
 XY='(3550,5225)',
 ROT='0',
 VER='1',
 PACK_TYPE='C0402',
 LOCATION='C2457',
 CDS_LIB='pure_quanta',
 CDS_PART_NAME='Q_CAP_C0402-22UF,4V,20%,X6S,CH622KMEB02',
 VOLTAGE='4V',
 PART_NUMBER='CH622KMEB02',
 VALUE='22UF',
 PRIM_FILE='./archive_libs/logical/q_cap/chips/chips.prt';

PART_NAME
 C2458 'Q_CAP_C0402-22UF,4V,20%,X6S,CH622KMEB02':;

SECTION_NUMBER 1
 '@T6G_MB_LIB.T6G(SCH_1):PAGE73_I71@PURE_QUANTA.Q_CAP(CHIPS)':
 C_PATH='@t6g_mb_lib.t6g(sch_1):page73_i71@pure_quanta.q_cap(chips)',
 P_PATH='@t6g_mb_lib.t6g(sch_1):page74_i71@pure_quanta.q_cap(chips)',
 PATH='I71',
 DRAWING='@T6G_MB_LIB.T6G(SCH_1):PAGE73',
 TOLERANCE='20%',
 MATERIAL='X6S',
 PHYS_PAGE='74',
 XY='(3550,4550)',
 ROT='0',
 VER='1',
 PACK_TYPE='C0402',
 LOCATION='C2458',
 CDS_LIB='pure_quanta',
 CDS_PART_NAME='Q_CAP_C0402-22UF,4V,20%,X6S,CH622KMEB02',
 VOLTAGE='4V',
 PART_NUMBER='CH622KMEB02',
 VALUE='22UF',
 PRIM_FILE='./archive_libs/logical/q_cap/chips/chips.prt';

PART_NAME
 C2459 'Q_CAP_C0402-22UF,4V,20%,X6S,CH622KMEB02':;

SECTION_NUMBER 1
 '@T6G_MB_LIB.T6G(SCH_1):PAGE73_I46@PURE_QUANTA.Q_CAP(CHIPS)':
 C_PATH='@t6g_mb_lib.t6g(sch_1):page73_i46@pure_quanta.q_cap(chips)',
 P_PATH='@t6g_mb_lib.t6g(sch_1):page74_i46@pure_quanta.q_cap(chips)',
 PATH='I46',
 DRAWING='@T6G_MB_LIB.T6G(SCH_1):PAGE73',
 TOLERANCE='20%',
 MATERIAL='X6S',
 PHYS_PAGE='74',
 XY='(3550,3850)',
 ROT='0',
 VER='1',
 PACK_TYPE='C0402',
 LOCATION='C2459',
 CDS_LIB='pure_quanta',
 CDS_PART_NAME='Q_CAP_C0402-22UF,4V,20%,X6S,CH622KMEB02',
 VOLTAGE='4V',
 PART_NUMBER='CH622KMEB02',
 VALUE='22UF',
 PRIM_FILE='./archive_libs/logical/q_cap/chips/chips.prt';

PART_NAME
 C2460 'Q_CAP_C0402-22UF,4V,20%,X6S,CH622KMEB02':;

SECTION_NUMBER 1
 '@T6G_MB_LIB.T6G(SCH_1):PAGE73_I45@PURE_QUANTA.Q_CAP(CHIPS)':
 C_PATH='@t6g_mb_lib.t6g(sch_1):page73_i45@pure_quanta.q_cap(chips)',
 P_PATH='@t6g_mb_lib.t6g(sch_1):page74_i45@pure_quanta.q_cap(chips)',
 PATH='I45',
 DRAWING='@T6G_MB_LIB.T6G(SCH_1):PAGE73',
 TOLERANCE='20%',
 MATERIAL='X6S',
 PHYS_PAGE='74',
 XY='(3550,3150)',
 ROT='0',
 VER='1',
 PACK_TYPE='C0402',
 LOCATION='C2460',
 CDS_LIB='pure_quanta',
 CDS_PART_NAME='Q_CAP_C0402-22UF,4V,20%,X6S,CH622KMEB02',
 VOLTAGE='4V',
 PART_NUMBER='CH622KMEB02',
 VALUE='22UF',
 PRIM_FILE='./archive_libs/logical/q_cap/chips/chips.prt';

PART_NAME
 C2461 'Q_CAP_C0402-22UF,4V,20%,X6S,CH622KMEB02':;

SECTION_NUMBER 1
 '@T6G_MB_LIB.T6G(SCH_1):PAGE73_I43@PURE_QUANTA.Q_CAP(CHIPS)':
 C_PATH='@t6g_mb_lib.t6g(sch_1):page73_i43@pure_quanta.q_cap(chips)',
 P_PATH='@t6g_mb_lib.t6g(sch_1):page74_i43@pure_quanta.q_cap(chips)',
 PATH='I43',
 DRAWING='@T6G_MB_LIB.T6G(SCH_1):PAGE73',
 TOLERANCE='20%',
 MATERIAL='X6S',
 PHYS_PAGE='74',
 XY='(3550,2475)',
 ROT='0',
 VER='1',
 PACK_TYPE='C0402',
 LOCATION='C2461',
 CDS_LIB='pure_quanta',
 CDS_PART_NAME='Q_CAP_C0402-22UF,4V,20%,X6S,CH622KMEB02',
 VOLTAGE='4V',
 PART_NUMBER='CH622KMEB02',
 VALUE='22UF',
 PRIM_FILE='./archive_libs/logical/q_cap/chips/chips.prt';

PART_NAME
 C2462 'Q_CAP_C0402-22UF,4V,20%,X6S,CH622KMEB02':;

SECTION_NUMBER 1
 '@T6G_MB_LIB.T6G(SCH_1):PAGE73_I32@PURE_QUANTA.Q_CAP(CHIPS)':
 C_PATH='@t6g_mb_lib.t6g(sch_1):page73_i32@pure_quanta.q_cap(chips)',
 P_PATH='@t6g_mb_lib.t6g(sch_1):page74_i32@pure_quanta.q_cap(chips)',
 PATH='I32',
 DRAWING='@T6G_MB_LIB.T6G(SCH_1):PAGE73',
 TOLERANCE='20%',
 MATERIAL='X6S',
 PHYS_PAGE='74',
 XY='(3550,1800)',
 ROT='0',
 VER='1',
 PACK_TYPE='C0402',
 LOCATION='C2462',
 CDS_LIB='pure_quanta',
 CDS_PART_NAME='Q_CAP_C0402-22UF,4V,20%,X6S,CH622KMEB02',
 VOLTAGE='4V',
 PART_NUMBER='CH622KMEB02',
 VALUE='22UF',
 PRIM_FILE='./archive_libs/logical/q_cap/chips/chips.prt';

PART_NAME
 C2463 'Q_CAP_C0402-22UF,4V,20%,X6S,CH622KMEB02':;

SECTION_NUMBER 1
 '@T6G_MB_LIB.T6G(SCH_1):PAGE73_I76@PURE_QUANTA.Q_CAP(CHIPS)':
 C_PATH='@t6g_mb_lib.t6g(sch_1):page73_i76@pure_quanta.q_cap(chips)',
 P_PATH='@t6g_mb_lib.t6g(sch_1):page74_i76@pure_quanta.q_cap(chips)',
 PATH='I76',
 DRAWING='@T6G_MB_LIB.T6G(SCH_1):PAGE73',
 TOLERANCE='20%',
 MATERIAL='X6S',
 PHYS_PAGE='74',
 XY='(4000,5875)',
 ROT='0',
 VER='1',
 PACK_TYPE='C0402',
 LOCATION='C2463',
 CDS_LIB='pure_quanta',
 CDS_PART_NAME='Q_CAP_C0402-22UF,4V,20%,X6S,CH622KMEB02',
 VOLTAGE='4V',
 PART_NUMBER='CH622KMEB02',
 VALUE='22UF',
 PRIM_FILE='./archive_libs/logical/q_cap/chips/chips.prt';

PART_NAME
 C2464 'Q_CAP_C0402-22UF,4V,20%,X6S,CH622KMEB02':;

SECTION_NUMBER 1
 '@T6G_MB_LIB.T6G(SCH_1):PAGE73_I75@PURE_QUANTA.Q_CAP(CHIPS)':
 C_PATH='@t6g_mb_lib.t6g(sch_1):page73_i75@pure_quanta.q_cap(chips)',
 P_PATH='@t6g_mb_lib.t6g(sch_1):page74_i75@pure_quanta.q_cap(chips)',
 PATH='I75',
 DRAWING='@T6G_MB_LIB.T6G(SCH_1):PAGE73',
 TOLERANCE='20%',
 MATERIAL='X6S',
 PHYS_PAGE='74',
 XY='(4000,5225)',
 ROT='0',
 VER='1',
 PACK_TYPE='C0402',
 LOCATION='C2464',
 CDS_LIB='pure_quanta',
 CDS_PART_NAME='Q_CAP_C0402-22UF,4V,20%,X6S,CH622KMEB02',
 VOLTAGE='4V',
 PART_NUMBER='CH622KMEB02',
 VALUE='22UF',
 PRIM_FILE='./archive_libs/logical/q_cap/chips/chips.prt';

PART_NAME
 C2465 'Q_CAP_C0402-22UF,4V,20%,X6S,CH622KMEB02':;

SECTION_NUMBER 1
 '@T6G_MB_LIB.T6G(SCH_1):PAGE73_I72@PURE_QUANTA.Q_CAP(CHIPS)':
 C_PATH='@t6g_mb_lib.t6g(sch_1):page73_i72@pure_quanta.q_cap(chips)',
 P_PATH='@t6g_mb_lib.t6g(sch_1):page74_i72@pure_quanta.q_cap(chips)',
 PATH='I72',
 DRAWING='@T6G_MB_LIB.T6G(SCH_1):PAGE73',
 TOLERANCE='20%',
 MATERIAL='X6S',
 PHYS_PAGE='74',
 XY='(4000,4550)',
 ROT='0',
 VER='1',
 PACK_TYPE='C0402',
 LOCATION='C2465',
 CDS_LIB='pure_quanta',
 CDS_PART_NAME='Q_CAP_C0402-22UF,4V,20%,X6S,CH622KMEB02',
 VOLTAGE='4V',
 PART_NUMBER='CH622KMEB02',
 VALUE='22UF',
 PRIM_FILE='./archive_libs/logical/q_cap/chips/chips.prt';

PART_NAME
 C2466 'Q_CAP_C0402-22UF,4V,20%,X6S,CH622KMEB02':;

SECTION_NUMBER 1
 '@T6G_MB_LIB.T6G(SCH_1):PAGE73_I48@PURE_QUANTA.Q_CAP(CHIPS)':
 C_PATH='@t6g_mb_lib.t6g(sch_1):page73_i48@pure_quanta.q_cap(chips)',
 P_PATH='@t6g_mb_lib.t6g(sch_1):page74_i48@pure_quanta.q_cap(chips)',
 PATH='I48',
 DRAWING='@T6G_MB_LIB.T6G(SCH_1):PAGE73',
 TOLERANCE='20%',
 MATERIAL='X6S',
 PHYS_PAGE='74',
 XY='(4000,3850)',
 ROT='0',
 VER='1',
 PACK_TYPE='C0402',
 LOCATION='C2466',
 CDS_LIB='pure_quanta',
 CDS_PART_NAME='Q_CAP_C0402-22UF,4V,20%,X6S,CH622KMEB02',
 VOLTAGE='4V',
 PART_NUMBER='CH622KMEB02',
 VALUE='22UF',
 PRIM_FILE='./archive_libs/logical/q_cap/chips/chips.prt';

PART_NAME
 C2467 'Q_CAP_C0402-22UF,4V,20%,X6S,CH622KMEB02':;

SECTION_NUMBER 1
 '@T6G_MB_LIB.T6G(SCH_1):PAGE73_I47@PURE_QUANTA.Q_CAP(CHIPS)':
 C_PATH='@t6g_mb_lib.t6g(sch_1):page73_i47@pure_quanta.q_cap(chips)',
 P_PATH='@t6g_mb_lib.t6g(sch_1):page74_i47@pure_quanta.q_cap(chips)',
 PATH='I47',
 DRAWING='@T6G_MB_LIB.T6G(SCH_1):PAGE73',
 TOLERANCE='20%',
 MATERIAL='X6S',
 PHYS_PAGE='74',
 XY='(4000,3150)',
 ROT='0',
 VER='1',
 PACK_TYPE='C0402',
 LOCATION='C2467',
 CDS_LIB='pure_quanta',
 CDS_PART_NAME='Q_CAP_C0402-22UF,4V,20%,X6S,CH622KMEB02',
 VOLTAGE='4V',
 PART_NUMBER='CH622KMEB02',
 VALUE='22UF',
 PRIM_FILE='./archive_libs/logical/q_cap/chips/chips.prt';

PART_NAME
 C2468 'Q_CAP_C0402-22UF,4V,20%,X6S,CH622KMEB02':;

SECTION_NUMBER 1
 '@T6G_MB_LIB.T6G(SCH_1):PAGE73_I44@PURE_QUANTA.Q_CAP(CHIPS)':
 C_PATH='@t6g_mb_lib.t6g(sch_1):page73_i44@pure_quanta.q_cap(chips)',
 P_PATH='@t6g_mb_lib.t6g(sch_1):page74_i44@pure_quanta.q_cap(chips)',
 PATH='I44',
 DRAWING='@T6G_MB_LIB.T6G(SCH_1):PAGE73',
 TOLERANCE='20%',
 MATERIAL='X6S',
 PHYS_PAGE='74',
 XY='(4000,2475)',
 ROT='0',
 VER='1',
 PACK_TYPE='C0402',
 LOCATION='C2468',
 CDS_LIB='pure_quanta',
 CDS_PART_NAME='Q_CAP_C0402-22UF,4V,20%,X6S,CH622KMEB02',
 VOLTAGE='4V',
 PART_NUMBER='CH622KMEB02',
 VALUE='22UF',
 PRIM_FILE='./archive_libs/logical/q_cap/chips/chips.prt';

PART_NAME
 C2469 'Q_CAP_C0402-22UF,4V,20%,X6S,CH622KMEB02':;

SECTION_NUMBER 1
 '@T6G_MB_LIB.T6G(SCH_1):PAGE73_I33@PURE_QUANTA.Q_CAP(CHIPS)':
 C_PATH='@t6g_mb_lib.t6g(sch_1):page73_i33@pure_quanta.q_cap(chips)',
 P_PATH='@t6g_mb_lib.t6g(sch_1):page74_i33@pure_quanta.q_cap(chips)',
 PATH='I33',
 DRAWING='@T6G_MB_LIB.T6G(SCH_1):PAGE73',
 TOLERANCE='20%',
 MATERIAL='X6S',
 PHYS_PAGE='74',
 XY='(4000,1800)',
 ROT='0',
 VER='1',
 PACK_TYPE='C0402',
 LOCATION='C2469',
 CDS_LIB='pure_quanta',
 CDS_PART_NAME='Q_CAP_C0402-22UF,4V,20%,X6S,CH622KMEB02',
 VOLTAGE='4V',
 PART_NUMBER='CH622KMEB02',
 VALUE='22UF',
 PRIM_FILE='./archive_libs/logical/q_cap/chips/chips.prt';

PART_NAME
 C2470 'Q_CAP_C0402-22UF,4V,20%,X6S,CH622KMEB02':;

SECTION_NUMBER 1
 '@T6G_MB_LIB.T6G(SCH_1):PAGE73_I133@PURE_QUANTA.Q_CAP(CHIPS)':
 C_PATH='@t6g_mb_lib.t6g(sch_1):page73_i133@pure_quanta.q_cap(chips)',
 P_PATH='@t6g_mb_lib.t6g(sch_1):page74_i133@pure_quanta.q_cap(chips)',
 PATH='I133',
 DRAWING='@T6G_MB_LIB.T6G(SCH_1):PAGE73',
 TOLERANCE='20%',
 MATERIAL='X6S',
 PHYS_PAGE='74',
 XY='(4400,5875)',
 ROT='0',
 VER='1',
 PACK_TYPE='C0402',
 LOCATION='C2470',
 CDS_LIB='pure_quanta',
 CDS_PART_NAME='Q_CAP_C0402-22UF,4V,20%,X6S,CH622KMEB02',
 VOLTAGE='4V',
 PART_NUMBER='CH622KMEB02',
 VALUE='22UF',
 PRIM_FILE='./archive_libs/logical/q_cap/chips/chips.prt';

PART_NAME
 C2471 'Q_CAP_C0402-22UF,4V,20%,X6S,CH622KMEB02':;

SECTION_NUMBER 1
 '@T6G_MB_LIB.T6G(SCH_1):PAGE73_I131@PURE_QUANTA.Q_CAP(CHIPS)':
 C_PATH='@t6g_mb_lib.t6g(sch_1):page73_i131@pure_quanta.q_cap(chips)',
 P_PATH='@t6g_mb_lib.t6g(sch_1):page74_i131@pure_quanta.q_cap(chips)',
 PATH='I131',
 DRAWING='@T6G_MB_LIB.T6G(SCH_1):PAGE73',
 TOLERANCE='20%',
 MATERIAL='X6S',
 PHYS_PAGE='74',
 XY='(4400,5225)',
 ROT='0',
 VER='1',
 PACK_TYPE='C0402',
 LOCATION='C2471',
 CDS_LIB='pure_quanta',
 CDS_PART_NAME='Q_CAP_C0402-22UF,4V,20%,X6S,CH622KMEB02',
 VOLTAGE='4V',
 PART_NUMBER='CH622KMEB02',
 VALUE='22UF',
 PRIM_FILE='./archive_libs/logical/q_cap/chips/chips.prt';

PART_NAME
 C2472 'Q_CAP_C0402-22UF,4V,20%,X6S,CH622KMEB02':;

SECTION_NUMBER 1
 '@T6G_MB_LIB.T6G(SCH_1):PAGE73_I127@PURE_QUANTA.Q_CAP(CHIPS)':
 C_PATH='@t6g_mb_lib.t6g(sch_1):page73_i127@pure_quanta.q_cap(chips)',
 P_PATH='@t6g_mb_lib.t6g(sch_1):page74_i127@pure_quanta.q_cap(chips)',
 PATH='I127',
 DRAWING='@T6G_MB_LIB.T6G(SCH_1):PAGE73',
 TOLERANCE='20%',
 MATERIAL='X6S',
 PHYS_PAGE='74',
 XY='(4400,4550)',
 ROT='0',
 VER='1',
 PACK_TYPE='C0402',
 LOCATION='C2472',
 CDS_LIB='pure_quanta',
 CDS_PART_NAME='Q_CAP_C0402-22UF,4V,20%,X6S,CH622KMEB02',
 VOLTAGE='4V',
 PART_NUMBER='CH622KMEB02',
 VALUE='22UF',
 PRIM_FILE='./archive_libs/logical/q_cap/chips/chips.prt';

PART_NAME
 C2473 'Q_CAP_C0402-22UF,4V,20%,X6S,CH622KMEB02':;

SECTION_NUMBER 1
 '@T6G_MB_LIB.T6G(SCH_1):PAGE73_I96@PURE_QUANTA.Q_CAP(CHIPS)':
 C_PATH='@t6g_mb_lib.t6g(sch_1):page73_i96@pure_quanta.q_cap(chips)',
 P_PATH='@t6g_mb_lib.t6g(sch_1):page74_i96@pure_quanta.q_cap(chips)',
 PATH='I96',
 DRAWING='@T6G_MB_LIB.T6G(SCH_1):PAGE73',
 TOLERANCE='20%',
 MATERIAL='X6S',
 PHYS_PAGE='74',
 XY='(4400,3850)',
 ROT='0',
 VER='1',
 PACK_TYPE='C0402',
 LOCATION='C2473',
 CDS_LIB='pure_quanta',
 CDS_PART_NAME='Q_CAP_C0402-22UF,4V,20%,X6S,CH622KMEB02',
 VOLTAGE='4V',
 PART_NUMBER='CH622KMEB02',
 VALUE='22UF',
 PRIM_FILE='./archive_libs/logical/q_cap/chips/chips.prt';

PART_NAME
 C2474 'Q_CAP_C0402-22UF,4V,20%,X6S,CH622KMEB02':;

SECTION_NUMBER 1
 '@T6G_MB_LIB.T6G(SCH_1):PAGE73_I94@PURE_QUANTA.Q_CAP(CHIPS)':
 C_PATH='@t6g_mb_lib.t6g(sch_1):page73_i94@pure_quanta.q_cap(chips)',
 P_PATH='@t6g_mb_lib.t6g(sch_1):page74_i94@pure_quanta.q_cap(chips)',
 PATH='I94',
 DRAWING='@T6G_MB_LIB.T6G(SCH_1):PAGE73',
 TOLERANCE='20%',
 MATERIAL='X6S',
 PHYS_PAGE='74',
 XY='(4400,3150)',
 ROT='0',
 VER='1',
 PACK_TYPE='C0402',
 LOCATION='C2474',
 CDS_LIB='pure_quanta',
 CDS_PART_NAME='Q_CAP_C0402-22UF,4V,20%,X6S,CH622KMEB02',
 VOLTAGE='4V',
 PART_NUMBER='CH622KMEB02',
 VALUE='22UF',
 PRIM_FILE='./archive_libs/logical/q_cap/chips/chips.prt';

PART_NAME
 C2475 'Q_CAP_C0402-22UF,4V,20%,X6S,CH622KMEB02':;

SECTION_NUMBER 1
 '@T6G_MB_LIB.T6G(SCH_1):PAGE73_I88@PURE_QUANTA.Q_CAP(CHIPS)':
 C_PATH='@t6g_mb_lib.t6g(sch_1):page73_i88@pure_quanta.q_cap(chips)',
 P_PATH='@t6g_mb_lib.t6g(sch_1):page74_i88@pure_quanta.q_cap(chips)',
 PATH='I88',
 DRAWING='@T6G_MB_LIB.T6G(SCH_1):PAGE73',
 TOLERANCE='20%',
 MATERIAL='X6S',
 PHYS_PAGE='74',
 XY='(4400,2475)',
 ROT='0',
 VER='1',
 PACK_TYPE='C0402',
 LOCATION='C2475',
 CDS_LIB='pure_quanta',
 CDS_PART_NAME='Q_CAP_C0402-22UF,4V,20%,X6S,CH622KMEB02',
 VOLTAGE='4V',
 PART_NUMBER='CH622KMEB02',
 VALUE='22UF',
 PRIM_FILE='./archive_libs/logical/q_cap/chips/chips.prt';

PART_NAME
 C2476 'Q_CAP_C0402-22UF,4V,20%,X6S,CH622KMEB02':;

SECTION_NUMBER 1
 '@T6G_MB_LIB.T6G(SCH_1):PAGE73_I79@PURE_QUANTA.Q_CAP(CHIPS)':
 C_PATH='@t6g_mb_lib.t6g(sch_1):page73_i79@pure_quanta.q_cap(chips)',
 P_PATH='@t6g_mb_lib.t6g(sch_1):page74_i79@pure_quanta.q_cap(chips)',
 PATH='I79',
 DRAWING='@T6G_MB_LIB.T6G(SCH_1):PAGE73',
 TOLERANCE='20%',
 MATERIAL='X6S',
 PHYS_PAGE='74',
 XY='(4400,1800)',
 ROT='0',
 VER='1',
 PACK_TYPE='C0402',
 LOCATION='C2476',
 CDS_LIB='pure_quanta',
 CDS_PART_NAME='Q_CAP_C0402-22UF,4V,20%,X6S,CH622KMEB02',
 VOLTAGE='4V',
 PART_NUMBER='CH622KMEB02',
 VALUE='22UF',
 PRIM_FILE='./archive_libs/logical/q_cap/chips/chips.prt';

PART_NAME
 C2477 'Q_CAP_C0402-22UF,4V,20%,X6S,CH622KMEB02':;

SECTION_NUMBER 1
 '@T6G_MB_LIB.T6G(SCH_1):PAGE73_I136@PURE_QUANTA.Q_CAP(CHIPS)':
 C_PATH='@t6g_mb_lib.t6g(sch_1):page73_i136@pure_quanta.q_cap(chips)',
 P_PATH='@t6g_mb_lib.t6g(sch_1):page74_i136@pure_quanta.q_cap(chips)',
 PATH='I136',
 DRAWING='@T6G_MB_LIB.T6G(SCH_1):PAGE73',
 TOLERANCE='20%',
 MATERIAL='X6S',
 PHYS_PAGE='74',
 XY='(4975,5875)',
 ROT='0',
 VER='1',
 PACK_TYPE='C0402',
 LOCATION='C2477',
 CDS_LIB='pure_quanta',
 CDS_PART_NAME='Q_CAP_C0402-22UF,4V,20%,X6S,CH622KMEB02',
 VOLTAGE='4V',
 PART_NUMBER='CH622KMEB02',
 VALUE='22UF',
 PRIM_FILE='./archive_libs/logical/q_cap/chips/chips.prt';

PART_NAME
 C2478 'Q_CAP_C0402-22UF,4V,20%,X6S,CH622KMEB02':;

SECTION_NUMBER 1
 '@T6G_MB_LIB.T6G(SCH_1):PAGE73_I134@PURE_QUANTA.Q_CAP(CHIPS)':
 C_PATH='@t6g_mb_lib.t6g(sch_1):page73_i134@pure_quanta.q_cap(chips)',
 P_PATH='@t6g_mb_lib.t6g(sch_1):page74_i134@pure_quanta.q_cap(chips)',
 PATH='I134',
 DRAWING='@T6G_MB_LIB.T6G(SCH_1):PAGE73',
 TOLERANCE='20%',
 MATERIAL='X6S',
 PHYS_PAGE='74',
 XY='(4975,5075)',
 ROT='0',
 VER='1',
 PACK_TYPE='C0402',
 LOCATION='C2478',
 CDS_LIB='pure_quanta',
 CDS_PART_NAME='Q_CAP_C0402-22UF,4V,20%,X6S,CH622KMEB02',
 VOLTAGE='4V',
 PART_NUMBER='CH622KMEB02',
 VALUE='22UF',
 PRIM_FILE='./archive_libs/logical/q_cap/chips/chips.prt';

PART_NAME
 C2479 'Q_CAP_C0402-22UF,4V,20%,X6S,CH622KMEB02':;

SECTION_NUMBER 1
 '@T6G_MB_LIB.T6G(SCH_1):PAGE73_I129@PURE_QUANTA.Q_CAP(CHIPS)':
 C_PATH='@t6g_mb_lib.t6g(sch_1):page73_i129@pure_quanta.q_cap(chips)',
 P_PATH='@t6g_mb_lib.t6g(sch_1):page74_i129@pure_quanta.q_cap(chips)',
 PATH='I129',
 DRAWING='@T6G_MB_LIB.T6G(SCH_1):PAGE73',
 TOLERANCE='20%',
 MATERIAL='X6S',
 PHYS_PAGE='74',
 XY='(5000,4300)',
 ROT='0',
 VER='1',
 PACK_TYPE='C0402',
 LOCATION='C2479',
 CDS_LIB='pure_quanta',
 CDS_PART_NAME='Q_CAP_C0402-22UF,4V,20%,X6S,CH622KMEB02',
 VOLTAGE='4V',
 PART_NUMBER='CH622KMEB02',
 VALUE='22UF',
 PRIM_FILE='./archive_libs/logical/q_cap/chips/chips.prt';

PART_NAME
 C2480 'Q_CAP_C0402-22UF,4V,20%,X6S,CH622KMEB02':;

SECTION_NUMBER 1
 '@T6G_MB_LIB.T6G(SCH_1):PAGE73_I97@PURE_QUANTA.Q_CAP(CHIPS)':
 C_PATH='@t6g_mb_lib.t6g(sch_1):page73_i97@pure_quanta.q_cap(chips)',
 P_PATH='@t6g_mb_lib.t6g(sch_1):page74_i97@pure_quanta.q_cap(chips)',
 PATH='I97',
 DRAWING='@T6G_MB_LIB.T6G(SCH_1):PAGE73',
 TOLERANCE='20%',
 MATERIAL='X6S',
 PHYS_PAGE='74',
 XY='(5000,3325)',
 ROT='0',
 VER='1',
 PACK_TYPE='C0402',
 LOCATION='C2480',
 CDS_LIB='pure_quanta',
 CDS_PART_NAME='Q_CAP_C0402-22UF,4V,20%,X6S,CH622KMEB02',
 VOLTAGE='4V',
 PART_NUMBER='CH622KMEB02',
 VALUE='22UF',
 PRIM_FILE='./archive_libs/logical/q_cap/chips/chips.prt';

PART_NAME
 C2481 'Q_CAP_C0402-22UF,4V,20%,X6S,CH622KMEB02':;

SECTION_NUMBER 1
 '@T6G_MB_LIB.T6G(SCH_1):PAGE73_I92@PURE_QUANTA.Q_CAP(CHIPS)':
 C_PATH='@t6g_mb_lib.t6g(sch_1):page73_i92@pure_quanta.q_cap(chips)',
 P_PATH='@t6g_mb_lib.t6g(sch_1):page74_i92@pure_quanta.q_cap(chips)',
 PATH='I92',
 DRAWING='@T6G_MB_LIB.T6G(SCH_1):PAGE73',
 TOLERANCE='20%',
 MATERIAL='X6S',
 PHYS_PAGE='74',
 XY='(5000,2650)',
 ROT='0',
 VER='1',
 PACK_TYPE='C0402',
 LOCATION='C2481',
 CDS_LIB='pure_quanta',
 CDS_PART_NAME='Q_CAP_C0402-22UF,4V,20%,X6S,CH622KMEB02',
 VOLTAGE='4V',
 PART_NUMBER='CH622KMEB02',
 VALUE='22UF',
 PRIM_FILE='./archive_libs/logical/q_cap/chips/chips.prt';

PART_NAME
 C2482 'Q_CAP_C0402-22UF,4V,20%,X6S,CH622KMEB02':;

SECTION_NUMBER 1
 '@T6G_MB_LIB.T6G(SCH_1):PAGE73_I90@PURE_QUANTA.Q_CAP(CHIPS)':
 C_PATH='@t6g_mb_lib.t6g(sch_1):page73_i90@pure_quanta.q_cap(chips)',
 P_PATH='@t6g_mb_lib.t6g(sch_1):page74_i90@pure_quanta.q_cap(chips)',
 PATH='I90',
 DRAWING='@T6G_MB_LIB.T6G(SCH_1):PAGE73',
 TOLERANCE='20%',
 MATERIAL='X6S',
 PHYS_PAGE='74',
 XY='(5000,2025)',
 ROT='0',
 VER='1',
 PACK_TYPE='C0402',
 LOCATION='C2482',
 CDS_LIB='pure_quanta',
 CDS_PART_NAME='Q_CAP_C0402-22UF,4V,20%,X6S,CH622KMEB02',
 VOLTAGE='4V',
 PART_NUMBER='CH622KMEB02',
 VALUE='22UF',
 PRIM_FILE='./archive_libs/logical/q_cap/chips/chips.prt';

PART_NAME
 C2483 'Q_CAP_C0402-22UF,4V,20%,X6S,CH622KMEB02':;

SECTION_NUMBER 1
 '@T6G_MB_LIB.T6G(SCH_1):PAGE73_I81@PURE_QUANTA.Q_CAP(CHIPS)':
 C_PATH='@t6g_mb_lib.t6g(sch_1):page73_i81@pure_quanta.q_cap(chips)',
 P_PATH='@t6g_mb_lib.t6g(sch_1):page74_i81@pure_quanta.q_cap(chips)',
 PATH='I81',
 DRAWING='@T6G_MB_LIB.T6G(SCH_1):PAGE73',
 TOLERANCE='20%',
 MATERIAL='X6S',
 PHYS_PAGE='74',
 XY='(5000,1375)',
 ROT='0',
 VER='1',
 PACK_TYPE='C0402',
 LOCATION='C2483',
 CDS_LIB='pure_quanta',
 CDS_PART_NAME='Q_CAP_C0402-22UF,4V,20%,X6S,CH622KMEB02',
 VOLTAGE='4V',
 PART_NUMBER='CH622KMEB02',
 VALUE='22UF',
 PRIM_FILE='./archive_libs/logical/q_cap/chips/chips.prt';

PART_NAME
 C2484 'Q_CAP_C0402-22UF,4V,20%,X6S,CH622KMEB02':;

SECTION_NUMBER 1
 '@T6G_MB_LIB.T6G(SCH_1):PAGE73_I139@PURE_QUANTA.Q_CAP(CHIPS)':
 C_PATH='@t6g_mb_lib.t6g(sch_1):page73_i139@pure_quanta.q_cap(chips)',
 P_PATH='@t6g_mb_lib.t6g(sch_1):page74_i139@pure_quanta.q_cap(chips)',
 PATH='I139',
 DRAWING='@T6G_MB_LIB.T6G(SCH_1):PAGE73',
 TOLERANCE='20%',
 MATERIAL='X6S',
 PHYS_PAGE='74',
 XY='(5425,5075)',
 ROT='0',
 VER='1',
 PACK_TYPE='C0402',
 LOCATION='C2484',
 CDS_LIB='pure_quanta',
 CDS_PART_NAME='Q_CAP_C0402-22UF,4V,20%,X6S,CH622KMEB02',
 VOLTAGE='4V',
 PART_NUMBER='CH622KMEB02',
 VALUE='22UF',
 PRIM_FILE='./archive_libs/logical/q_cap/chips/chips.prt';

PART_NAME
 C2485 'Q_CAP_C0402-22UF,4V,20%,X6S,CH622KMEB02':;

SECTION_NUMBER 1
 '@T6G_MB_LIB.T6G(SCH_1):PAGE73_I103@PURE_QUANTA.Q_CAP(CHIPS)':
 C_PATH='@t6g_mb_lib.t6g(sch_1):page73_i103@pure_quanta.q_cap(chips)',
 P_PATH='@t6g_mb_lib.t6g(sch_1):page74_i103@pure_quanta.q_cap(chips)',
 PATH='I103',
 DRAWING='@T6G_MB_LIB.T6G(SCH_1):PAGE73',
 TOLERANCE='20%',
 MATERIAL='X6S',
 PHYS_PAGE='74',
 XY='(5450,3325)',
 ROT='0',
 VER='1',
 PACK_TYPE='C0402',
 LOCATION='C2485',
 CDS_LIB='pure_quanta',
 CDS_PART_NAME='Q_CAP_C0402-22UF,4V,20%,X6S,CH622KMEB02',
 VOLTAGE='4V',
 PART_NUMBER='CH622KMEB02',
 VALUE='22UF',
 PRIM_FILE='./archive_libs/logical/q_cap/chips/chips.prt';

PART_NAME
 C2486 'Q_CAP_C0402-22UF,4V,20%,X6S,CH622KMEB02':;

SECTION_NUMBER 1
 '@T6G_MB_LIB.T6G(SCH_1):PAGE73_I100@PURE_QUANTA.Q_CAP(CHIPS)':
 C_PATH='@t6g_mb_lib.t6g(sch_1):page73_i100@pure_quanta.q_cap(chips)',
 P_PATH='@t6g_mb_lib.t6g(sch_1):page74_i100@pure_quanta.q_cap(chips)',
 PATH='I100',
 DRAWING='@T6G_MB_LIB.T6G(SCH_1):PAGE73',
 TOLERANCE='20%',
 MATERIAL='X6S',
 PHYS_PAGE='74',
 XY='(5450,2650)',
 ROT='0',
 VER='1',
 PACK_TYPE='C0402',
 LOCATION='C2486',
 CDS_LIB='pure_quanta',
 CDS_PART_NAME='Q_CAP_C0402-22UF,4V,20%,X6S,CH622KMEB02',
 VOLTAGE='4V',
 PART_NUMBER='CH622KMEB02',
 VALUE='22UF',
 PRIM_FILE='./archive_libs/logical/q_cap/chips/chips.prt';

PART_NAME
 C2487 'Q_CAP_C0402-22UF,4V,20%,X6S,CH622KMEB02':;

SECTION_NUMBER 1
 '@T6G_MB_LIB.T6G(SCH_1):PAGE73_I99@PURE_QUANTA.Q_CAP(CHIPS)':
 C_PATH='@t6g_mb_lib.t6g(sch_1):page73_i99@pure_quanta.q_cap(chips)',
 P_PATH='@t6g_mb_lib.t6g(sch_1):page74_i99@pure_quanta.q_cap(chips)',
 PATH='I99',
 DRAWING='@T6G_MB_LIB.T6G(SCH_1):PAGE73',
 TOLERANCE='20%',
 MATERIAL='X6S',
 PHYS_PAGE='74',
 XY='(5450,2025)',
 ROT='0',
 VER='1',
 PACK_TYPE='C0402',
 LOCATION='C2487',
 CDS_LIB='pure_quanta',
 CDS_PART_NAME='Q_CAP_C0402-22UF,4V,20%,X6S,CH622KMEB02',
 VOLTAGE='4V',
 PART_NUMBER='CH622KMEB02',
 VALUE='22UF',
 PRIM_FILE='./archive_libs/logical/q_cap/chips/chips.prt';

PART_NAME
 C2488 'Q_CAP_C0402-22UF,4V,20%,X6S,CH622KMEB02':;

SECTION_NUMBER 1
 '@T6G_MB_LIB.T6G(SCH_1):PAGE73_I85@PURE_QUANTA.Q_CAP(CHIPS)':
 C_PATH='@t6g_mb_lib.t6g(sch_1):page73_i85@pure_quanta.q_cap(chips)',
 P_PATH='@t6g_mb_lib.t6g(sch_1):page74_i85@pure_quanta.q_cap(chips)',
 PATH='I85',
 DRAWING='@T6G_MB_LIB.T6G(SCH_1):PAGE73',
 TOLERANCE='20%',
 MATERIAL='X6S',
 PHYS_PAGE='74',
 XY='(5450,1375)',
 ROT='0',
 VER='1',
 PACK_TYPE='C0402',
 LOCATION='C2488',
 CDS_LIB='pure_quanta',
 CDS_PART_NAME='Q_CAP_C0402-22UF,4V,20%,X6S,CH622KMEB02',
 VOLTAGE='4V',
 PART_NUMBER='CH622KMEB02',
 VALUE='22UF',
 PRIM_FILE='./archive_libs/logical/q_cap/chips/chips.prt';

PART_NAME
 C2489 'Q_CAP_C0402-22UF,4V,20%,X6S,CH622KMEB02':;

SECTION_NUMBER 1
 '@T6G_MB_LIB.T6G(SCH_1):PAGE73_I104@PURE_QUANTA.Q_CAP(CHIPS)':
 C_PATH='@t6g_mb_lib.t6g(sch_1):page73_i104@pure_quanta.q_cap(chips)',
 P_PATH='@t6g_mb_lib.t6g(sch_1):page74_i104@pure_quanta.q_cap(chips)',
 PATH='I104',
 DRAWING='@T6G_MB_LIB.T6G(SCH_1):PAGE73',
 TOLERANCE='20%',
 MATERIAL='X6S',
 PHYS_PAGE='74',
 XY='(5900,3325)',
 ROT='0',
 VER='1',
 PACK_TYPE='C0402',
 LOCATION='C2489',
 CDS_LIB='pure_quanta',
 CDS_PART_NAME='Q_CAP_C0402-22UF,4V,20%,X6S,CH622KMEB02',
 VOLTAGE='4V',
 PART_NUMBER='CH622KMEB02',
 VALUE='22UF',
 PRIM_FILE='./archive_libs/logical/q_cap/chips/chips.prt';

PART_NAME
 C2490 'Q_CAP_C0402-22UF,4V,20%,X6S,CH622KMEB02':;

SECTION_NUMBER 1
 '@T6G_MB_LIB.T6G(SCH_1):PAGE73_I102@PURE_QUANTA.Q_CAP(CHIPS)':
 C_PATH='@t6g_mb_lib.t6g(sch_1):page73_i102@pure_quanta.q_cap(chips)',
 P_PATH='@t6g_mb_lib.t6g(sch_1):page74_i102@pure_quanta.q_cap(chips)',
 PATH='I102',
 DRAWING='@T6G_MB_LIB.T6G(SCH_1):PAGE73',
 TOLERANCE='20%',
 MATERIAL='X6S',
 PHYS_PAGE='74',
 XY='(5900,2650)',
 ROT='0',
 VER='1',
 PACK_TYPE='C0402',
 LOCATION='C2490',
 CDS_LIB='pure_quanta',
 CDS_PART_NAME='Q_CAP_C0402-22UF,4V,20%,X6S,CH622KMEB02',
 VOLTAGE='4V',
 PART_NUMBER='CH622KMEB02',
 VALUE='22UF',
 PRIM_FILE='./archive_libs/logical/q_cap/chips/chips.prt';

PART_NAME
 C2491 'Q_CAP_C0402-22UF,4V,20%,X6S,CH622KMEB02':;

SECTION_NUMBER 1
 '@T6G_MB_LIB.T6G(SCH_1):PAGE73_I101@PURE_QUANTA.Q_CAP(CHIPS)':
 C_PATH='@t6g_mb_lib.t6g(sch_1):page73_i101@pure_quanta.q_cap(chips)',
 P_PATH='@t6g_mb_lib.t6g(sch_1):page74_i101@pure_quanta.q_cap(chips)',
 PATH='I101',
 DRAWING='@T6G_MB_LIB.T6G(SCH_1):PAGE73',
 TOLERANCE='20%',
 MATERIAL='X6S',
 PHYS_PAGE='74',
 XY='(5900,2025)',
 ROT='0',
 VER='1',
 PACK_TYPE='C0402',
 LOCATION='C2491',
 CDS_LIB='pure_quanta',
 CDS_PART_NAME='Q_CAP_C0402-22UF,4V,20%,X6S,CH622KMEB02',
 VOLTAGE='4V',
 PART_NUMBER='CH622KMEB02',
 VALUE='22UF',
 PRIM_FILE='./archive_libs/logical/q_cap/chips/chips.prt';

PART_NAME
 C2492 'Q_CAP_C0402-22UF,4V,20%,X6S,CH622KMEB02':;

SECTION_NUMBER 1
 '@T6G_MB_LIB.T6G(SCH_1):PAGE73_I86@PURE_QUANTA.Q_CAP(CHIPS)':
 C_PATH='@t6g_mb_lib.t6g(sch_1):page73_i86@pure_quanta.q_cap(chips)',
 P_PATH='@t6g_mb_lib.t6g(sch_1):page74_i86@pure_quanta.q_cap(chips)',
 PATH='I86',
 DRAWING='@T6G_MB_LIB.T6G(SCH_1):PAGE73',
 TOLERANCE='20%',
 MATERIAL='X6S',
 PHYS_PAGE='74',
 XY='(5900,1375)',
 ROT='0',
 VER='1',
 PACK_TYPE='C0402',
 LOCATION='C2492',
 CDS_LIB='pure_quanta',
 CDS_PART_NAME='Q_CAP_C0402-22UF,4V,20%,X6S,CH622KMEB02',
 VOLTAGE='4V',
 PART_NUMBER='CH622KMEB02',
 VALUE='22UF',
 PRIM_FILE='./archive_libs/logical/q_cap/chips/chips.prt';

PART_NAME
 C2493 'Q_CAP_C0402-22UF,4V,20%,X6S,CH622KMEB02':;

SECTION_NUMBER 1
 '@T6G_MB_LIB.T6G(SCH_1):PAGE73_I146@PURE_QUANTA.Q_CAP(CHIPS)':
 C_PATH='@t6g_mb_lib.t6g(sch_1):page73_i146@pure_quanta.q_cap(chips)',
 P_PATH='@t6g_mb_lib.t6g(sch_1):page74_i146@pure_quanta.q_cap(chips)',
 PATH='I146',
 DRAWING='@T6G_MB_LIB.T6G(SCH_1):PAGE73',
 TOLERANCE='20%',
 MATERIAL='X6S',
 PHYS_PAGE='74',
 XY='(6325,5875)',
 ROT='0',
 VER='1',
 PACK_TYPE='C0402',
 LOCATION='C2493',
 CDS_LIB='pure_quanta',
 CDS_PART_NAME='Q_CAP_C0402-22UF,4V,20%,X6S,CH622KMEB02',
 VOLTAGE='4V',
 PART_NUMBER='CH622KMEB02',
 VALUE='22UF',
 PRIM_FILE='./archive_libs/logical/q_cap/chips/chips.prt';

PART_NAME
 C2494 'Q_CAP_C0402-22UF,4V,20%,X6S,CH622KMEB02':;

SECTION_NUMBER 1
 '@T6G_MB_LIB.T6G(SCH_1):PAGE73_I114@PURE_QUANTA.Q_CAP(CHIPS)':
 C_PATH='@t6g_mb_lib.t6g(sch_1):page73_i114@pure_quanta.q_cap(chips)',
 P_PATH='@t6g_mb_lib.t6g(sch_1):page74_i114@pure_quanta.q_cap(chips)',
 PATH='I114',
 DRAWING='@T6G_MB_LIB.T6G(SCH_1):PAGE73',
 TOLERANCE='20%',
 MATERIAL='X6S',
 PHYS_PAGE='74',
 XY='(6350,3325)',
 ROT='0',
 VER='1',
 PACK_TYPE='C0402',
 LOCATION='C2494',
 CDS_LIB='pure_quanta',
 CDS_PART_NAME='Q_CAP_C0402-22UF,4V,20%,X6S,CH622KMEB02',
 VOLTAGE='4V',
 PART_NUMBER='CH622KMEB02',
 VALUE='22UF',
 PRIM_FILE='./archive_libs/logical/q_cap/chips/chips.prt';

PART_NAME
 C2495 'Q_CAP_C0402-22UF,4V,20%,X6S,CH622KMEB02':;

SECTION_NUMBER 1
 '@T6G_MB_LIB.T6G(SCH_1):PAGE73_I111@PURE_QUANTA.Q_CAP(CHIPS)':
 C_PATH='@t6g_mb_lib.t6g(sch_1):page73_i111@pure_quanta.q_cap(chips)',
 P_PATH='@t6g_mb_lib.t6g(sch_1):page74_i111@pure_quanta.q_cap(chips)',
 PATH='I111',
 DRAWING='@T6G_MB_LIB.T6G(SCH_1):PAGE73',
 TOLERANCE='20%',
 MATERIAL='X6S',
 PHYS_PAGE='74',
 XY='(6350,2650)',
 ROT='0',
 VER='1',
 PACK_TYPE='C0402',
 LOCATION='C2495',
 CDS_LIB='pure_quanta',
 CDS_PART_NAME='Q_CAP_C0402-22UF,4V,20%,X6S,CH622KMEB02',
 VOLTAGE='4V',
 PART_NUMBER='CH622KMEB02',
 VALUE='22UF',
 PRIM_FILE='./archive_libs/logical/q_cap/chips/chips.prt';

PART_NAME
 C2496 'Q_CAP_C0402-22UF,4V,20%,X6S,CH622KMEB02':;

SECTION_NUMBER 1
 '@T6G_MB_LIB.T6G(SCH_1):PAGE73_I110@PURE_QUANTA.Q_CAP(CHIPS)':
 C_PATH='@t6g_mb_lib.t6g(sch_1):page73_i110@pure_quanta.q_cap(chips)',
 P_PATH='@t6g_mb_lib.t6g(sch_1):page74_i110@pure_quanta.q_cap(chips)',
 PATH='I110',
 DRAWING='@T6G_MB_LIB.T6G(SCH_1):PAGE73',
 TOLERANCE='20%',
 MATERIAL='X6S',
 PHYS_PAGE='74',
 XY='(6350,2025)',
 ROT='0',
 VER='1',
 PACK_TYPE='C0402',
 LOCATION='C2496',
 CDS_LIB='pure_quanta',
 CDS_PART_NAME='Q_CAP_C0402-22UF,4V,20%,X6S,CH622KMEB02',
 VOLTAGE='4V',
 PART_NUMBER='CH622KMEB02',
 VALUE='22UF',
 PRIM_FILE='./archive_libs/logical/q_cap/chips/chips.prt';

PART_NAME
 C2497 'Q_CAP_C0402-22UF,4V,20%,X6S,CH622KMEB02':;

SECTION_NUMBER 1
 '@T6G_MB_LIB.T6G(SCH_1):PAGE73_I105@PURE_QUANTA.Q_CAP(CHIPS)':
 C_PATH='@t6g_mb_lib.t6g(sch_1):page73_i105@pure_quanta.q_cap(chips)',
 P_PATH='@t6g_mb_lib.t6g(sch_1):page74_i105@pure_quanta.q_cap(chips)',
 PATH='I105',
 DRAWING='@T6G_MB_LIB.T6G(SCH_1):PAGE73',
 TOLERANCE='20%',
 MATERIAL='X6S',
 PHYS_PAGE='74',
 XY='(6350,1375)',
 ROT='0',
 VER='1',
 PACK_TYPE='C0402',
 LOCATION='C2497',
 CDS_LIB='pure_quanta',
 CDS_PART_NAME='Q_CAP_C0402-22UF,4V,20%,X6S,CH622KMEB02',
 VOLTAGE='4V',
 PART_NUMBER='CH622KMEB02',
 VALUE='22UF',
 PRIM_FILE='./archive_libs/logical/q_cap/chips/chips.prt';

PART_NAME
 C2498 'Q_CAP_C0402-22UF,4V,20%,X6S,CH622KMEB02':;

SECTION_NUMBER 1
 '@T6G_MB_LIB.T6G(SCH_1):PAGE73_I147@PURE_QUANTA.Q_CAP(CHIPS)':
 C_PATH='@t6g_mb_lib.t6g(sch_1):page73_i147@pure_quanta.q_cap(chips)',
 P_PATH='@t6g_mb_lib.t6g(sch_1):page74_i147@pure_quanta.q_cap(chips)',
 PATH='I147',
 DRAWING='@T6G_MB_LIB.T6G(SCH_1):PAGE73',
 TOLERANCE='20%',
 MATERIAL='X6S',
 PHYS_PAGE='74',
 XY='(6775,5075)',
 ROT='0',
 VER='1',
 PACK_TYPE='C0402',
 LOCATION='C2498',
 CDS_LIB='pure_quanta',
 CDS_PART_NAME='Q_CAP_C0402-22UF,4V,20%,X6S,CH622KMEB02',
 VOLTAGE='4V',
 PART_NUMBER='CH622KMEB02',
 VALUE='22UF',
 PRIM_FILE='./archive_libs/logical/q_cap/chips/chips.prt';

PART_NAME
 C2499 'Q_CAP_C0402-22UF,4V,20%,X6S,CH622KMEB02':;

SECTION_NUMBER 1
 '@T6G_MB_LIB.T6G(SCH_1):PAGE73_I116@PURE_QUANTA.Q_CAP(CHIPS)':
 C_PATH='@t6g_mb_lib.t6g(sch_1):page73_i116@pure_quanta.q_cap(chips)',
 P_PATH='@t6g_mb_lib.t6g(sch_1):page74_i116@pure_quanta.q_cap(chips)',
 PATH='I116',
 DRAWING='@T6G_MB_LIB.T6G(SCH_1):PAGE73',
 TOLERANCE='20%',
 MATERIAL='X6S',
 PHYS_PAGE='74',
 XY='(6800,3325)',
 ROT='0',
 VER='1',
 PACK_TYPE='C0402',
 LOCATION='C2499',
 CDS_LIB='pure_quanta',
 CDS_PART_NAME='Q_CAP_C0402-22UF,4V,20%,X6S,CH622KMEB02',
 VOLTAGE='4V',
 PART_NUMBER='CH622KMEB02',
 VALUE='22UF',
 PRIM_FILE='./archive_libs/logical/q_cap/chips/chips.prt';

PART_NAME
 C2500 'Q_CAP_C0402-22UF,4V,20%,X6S,CH622KMEB02':;

SECTION_NUMBER 1
 '@T6G_MB_LIB.T6G(SCH_1):PAGE73_I113@PURE_QUANTA.Q_CAP(CHIPS)':
 C_PATH='@t6g_mb_lib.t6g(sch_1):page73_i113@pure_quanta.q_cap(chips)',
 P_PATH='@t6g_mb_lib.t6g(sch_1):page74_i113@pure_quanta.q_cap(chips)',
 PATH='I113',
 DRAWING='@T6G_MB_LIB.T6G(SCH_1):PAGE73',
 TOLERANCE='20%',
 MATERIAL='X6S',
 PHYS_PAGE='74',
 XY='(6800,2650)',
 ROT='0',
 VER='1',
 PACK_TYPE='C0402',
 LOCATION='C2500',
 CDS_LIB='pure_quanta',
 CDS_PART_NAME='Q_CAP_C0402-22UF,4V,20%,X6S,CH622KMEB02',
 VOLTAGE='4V',
 PART_NUMBER='CH622KMEB02',
 VALUE='22UF',
 PRIM_FILE='./archive_libs/logical/q_cap/chips/chips.prt';

PART_NAME
 C2501 'Q_CAP_C0402-22UF,4V,20%,X6S,CH622KMEB02':;

SECTION_NUMBER 1
 '@T6G_MB_LIB.T6G(SCH_1):PAGE73_I112@PURE_QUANTA.Q_CAP(CHIPS)':
 C_PATH='@t6g_mb_lib.t6g(sch_1):page73_i112@pure_quanta.q_cap(chips)',
 P_PATH='@t6g_mb_lib.t6g(sch_1):page74_i112@pure_quanta.q_cap(chips)',
 PATH='I112',
 DRAWING='@T6G_MB_LIB.T6G(SCH_1):PAGE73',
 TOLERANCE='20%',
 MATERIAL='X6S',
 PHYS_PAGE='74',
 XY='(6800,2025)',
 ROT='0',
 VER='1',
 PACK_TYPE='C0402',
 LOCATION='C2501',
 CDS_LIB='pure_quanta',
 CDS_PART_NAME='Q_CAP_C0402-22UF,4V,20%,X6S,CH622KMEB02',
 VOLTAGE='4V',
 PART_NUMBER='CH622KMEB02',
 VALUE='22UF',
 PRIM_FILE='./archive_libs/logical/q_cap/chips/chips.prt';

PART_NAME
 C2502 'Q_CAP_C0402-22UF,4V,20%,X6S,CH622KMEB02':;

SECTION_NUMBER 1
 '@T6G_MB_LIB.T6G(SCH_1):PAGE73_I106@PURE_QUANTA.Q_CAP(CHIPS)':
 C_PATH='@t6g_mb_lib.t6g(sch_1):page73_i106@pure_quanta.q_cap(chips)',
 P_PATH='@t6g_mb_lib.t6g(sch_1):page74_i106@pure_quanta.q_cap(chips)',
 PATH='I106',
 DRAWING='@T6G_MB_LIB.T6G(SCH_1):PAGE73',
 TOLERANCE='20%',
 MATERIAL='X6S',
 PHYS_PAGE='74',
 XY='(6800,1375)',
 ROT='0',
 VER='1',
 PACK_TYPE='C0402',
 LOCATION='C2502',
 CDS_LIB='pure_quanta',
 CDS_PART_NAME='Q_CAP_C0402-22UF,4V,20%,X6S,CH622KMEB02',
 VOLTAGE='4V',
 PART_NUMBER='CH622KMEB02',
 VALUE='22UF',
 PRIM_FILE='./archive_libs/logical/q_cap/chips/chips.prt';

PART_NAME
 C2503 'Q_CAP_C0402-22UF,4V,20%,X6S,CH622KMEB02':;

SECTION_NUMBER 1
 '@T6G_MB_LIB.T6G(SCH_1):PAGE73_I123@PURE_QUANTA.Q_CAP(CHIPS)':
 C_PATH='@t6g_mb_lib.t6g(sch_1):page73_i123@pure_quanta.q_cap(chips)',
 P_PATH='@t6g_mb_lib.t6g(sch_1):page74_i123@pure_quanta.q_cap(chips)',
 PATH='I123',
 DRAWING='@T6G_MB_LIB.T6G(SCH_1):PAGE73',
 TOLERANCE='20%',
 MATERIAL='X6S',
 PHYS_PAGE='74',
 XY='(7250,3325)',
 ROT='0',
 VER='1',
 PACK_TYPE='C0402',
 LOCATION='C2503',
 CDS_LIB='pure_quanta',
 CDS_PART_NAME='Q_CAP_C0402-22UF,4V,20%,X6S,CH622KMEB02',
 VOLTAGE='4V',
 PART_NUMBER='CH622KMEB02',
 VALUE='22UF',
 PRIM_FILE='./archive_libs/logical/q_cap/chips/chips.prt';

PART_NAME
 C2504 'Q_CAP_C0402-22UF,4V,20%,X6S,CH622KMEB02':;

SECTION_NUMBER 1
 '@T6G_MB_LIB.T6G(SCH_1):PAGE73_I118@PURE_QUANTA.Q_CAP(CHIPS)':
 C_PATH='@t6g_mb_lib.t6g(sch_1):page73_i118@pure_quanta.q_cap(chips)',
 P_PATH='@t6g_mb_lib.t6g(sch_1):page74_i118@pure_quanta.q_cap(chips)',
 PATH='I118',
 DRAWING='@T6G_MB_LIB.T6G(SCH_1):PAGE73',
 TOLERANCE='20%',
 MATERIAL='X6S',
 PHYS_PAGE='74',
 XY='(7250,2650)',
 ROT='0',
 VER='1',
 PACK_TYPE='C0402',
 LOCATION='C2504',
 CDS_LIB='pure_quanta',
 CDS_PART_NAME='Q_CAP_C0402-22UF,4V,20%,X6S,CH622KMEB02',
 VOLTAGE='4V',
 PART_NUMBER='CH622KMEB02',
 VALUE='22UF',
 PRIM_FILE='./archive_libs/logical/q_cap/chips/chips.prt';

PART_NAME
 C2505 'Q_CAP_C0402-22UF,4V,20%,X6S,CH622KMEB02':;

SECTION_NUMBER 1
 '@T6G_MB_LIB.T6G(SCH_1):PAGE73_I117@PURE_QUANTA.Q_CAP(CHIPS)':
 C_PATH='@t6g_mb_lib.t6g(sch_1):page73_i117@pure_quanta.q_cap(chips)',
 P_PATH='@t6g_mb_lib.t6g(sch_1):page74_i117@pure_quanta.q_cap(chips)',
 PATH='I117',
 DRAWING='@T6G_MB_LIB.T6G(SCH_1):PAGE73',
 TOLERANCE='20%',
 MATERIAL='X6S',
 PHYS_PAGE='74',
 XY='(7250,2025)',
 ROT='0',
 VER='1',
 PACK_TYPE='C0402',
 LOCATION='C2505',
 CDS_LIB='pure_quanta',
 CDS_PART_NAME='Q_CAP_C0402-22UF,4V,20%,X6S,CH622KMEB02',
 VOLTAGE='4V',
 PART_NUMBER='CH622KMEB02',
 VALUE='22UF',
 PRIM_FILE='./archive_libs/logical/q_cap/chips/chips.prt';

PART_NAME
 C2506 'Q_CAP_C0402-22UF,4V,20%,X6S,CH622KMEB02':;

SECTION_NUMBER 1
 '@T6G_MB_LIB.T6G(SCH_1):PAGE73_I107@PURE_QUANTA.Q_CAP(CHIPS)':
 C_PATH='@t6g_mb_lib.t6g(sch_1):page73_i107@pure_quanta.q_cap(chips)',
 P_PATH='@t6g_mb_lib.t6g(sch_1):page74_i107@pure_quanta.q_cap(chips)',
 PATH='I107',
 DRAWING='@T6G_MB_LIB.T6G(SCH_1):PAGE73',
 TOLERANCE='20%',
 MATERIAL='X6S',
 PHYS_PAGE='74',
 XY='(7250,1375)',
 ROT='0',
 VER='1',
 PACK_TYPE='C0402',
 LOCATION='C2506',
 CDS_LIB='pure_quanta',
 CDS_PART_NAME='Q_CAP_C0402-22UF,4V,20%,X6S,CH622KMEB02',
 VOLTAGE='4V',
 PART_NUMBER='CH622KMEB02',
 VALUE='22UF',
 PRIM_FILE='./archive_libs/logical/q_cap/chips/chips.prt';

PART_NAME
 C2507 'Q_CAP_C0402-22UF,4V,20%,X6S,CH622KMEB02':;

SECTION_NUMBER 1
 '@T6G_MB_LIB.T6G(SCH_1):PAGE73_I152@PURE_QUANTA.Q_CAP(CHIPS)':
 C_PATH='@t6g_mb_lib.t6g(sch_1):page73_i152@pure_quanta.q_cap(chips)',
 P_PATH='@t6g_mb_lib.t6g(sch_1):page74_i152@pure_quanta.q_cap(chips)',
 PATH='I152',
 DRAWING='@T6G_MB_LIB.T6G(SCH_1):PAGE73',
 TOLERANCE='20%',
 MATERIAL='X6S',
 PHYS_PAGE='74',
 XY='(7675,5875)',
 ROT='0',
 VER='1',
 PACK_TYPE='C0402',
 LOCATION='C2507',
 CDS_LIB='pure_quanta',
 CDS_PART_NAME='Q_CAP_C0402-22UF,4V,20%,X6S,CH622KMEB02',
 VOLTAGE='4V',
 PART_NUMBER='CH622KMEB02',
 VALUE='22UF',
 PRIM_FILE='./archive_libs/logical/q_cap/chips/chips.prt';

PART_NAME
 C2508 'Q_CAP_C0402-22UF,4V,20%,X6S,CH622KMEB02':;

SECTION_NUMBER 1
 '@T6G_MB_LIB.T6G(SCH_1):PAGE73_I124@PURE_QUANTA.Q_CAP(CHIPS)':
 C_PATH='@t6g_mb_lib.t6g(sch_1):page73_i124@pure_quanta.q_cap(chips)',
 P_PATH='@t6g_mb_lib.t6g(sch_1):page74_i124@pure_quanta.q_cap(chips)',
 PATH='I124',
 DRAWING='@T6G_MB_LIB.T6G(SCH_1):PAGE73',
 TOLERANCE='20%',
 MATERIAL='X6S',
 PHYS_PAGE='74',
 XY='(7700,3325)',
 ROT='0',
 VER='1',
 PACK_TYPE='C0402',
 LOCATION='C2508',
 CDS_LIB='pure_quanta',
 CDS_PART_NAME='Q_CAP_C0402-22UF,4V,20%,X6S,CH622KMEB02',
 VOLTAGE='4V',
 PART_NUMBER='CH622KMEB02',
 VALUE='22UF',
 PRIM_FILE='./archive_libs/logical/q_cap/chips/chips.prt';

PART_NAME
 C2509 'Q_CAP_C0402-22UF,4V,20%,X6S,CH622KMEB02':;

SECTION_NUMBER 1
 '@T6G_MB_LIB.T6G(SCH_1):PAGE73_I170@PURE_QUANTA.Q_CAP(CHIPS)':
 C_PATH='@t6g_mb_lib.t6g(sch_1):page73_i170@pure_quanta.q_cap(chips)',
 P_PATH='@t6g_mb_lib.t6g(sch_1):page74_i170@pure_quanta.q_cap(chips)',
 PATH='I170',
 DRAWING='@T6G_MB_LIB.T6G(SCH_1):PAGE73',
 TOLERANCE='20%',
 MATERIAL='X6S',
 PHYS_PAGE='74',
 XY='(8975,5075)',
 ROT='0',
 VER='1',
 PACK_TYPE='C0402',
 LOCATION='C2509',
 CDS_LIB='pure_quanta',
 CDS_PART_NAME='Q_CAP_C0402-22UF,4V,20%,X6S,CH622KMEB02',
 VOLTAGE='4V',
 PART_NUMBER='CH622KMEB02',
 VALUE='22UF',
 PRIM_FILE='./archive_libs/logical/q_cap/chips/chips.prt';

PART_NAME
 C2510 'Q_CAP_C0402-22UF,4V,20%,X6S,CH622KMEB02':;

SECTION_NUMBER 1
 '@T6G_MB_LIB.T6G(SCH_1):PAGE73_I163@PURE_QUANTA.Q_CAP(CHIPS)':
 C_PATH='@t6g_mb_lib.t6g(sch_1):page73_i163@pure_quanta.q_cap(chips)',
 P_PATH='@t6g_mb_lib.t6g(sch_1):page74_i163@pure_quanta.q_cap(chips)',
 PATH='I163',
 DRAWING='@T6G_MB_LIB.T6G(SCH_1):PAGE73',
 TOLERANCE='20%',
 MATERIAL='X6S',
 PHYS_PAGE='74',
 XY='(9000,2650)',
 ROT='0',
 VER='1',
 PACK_TYPE='C0402',
 LOCATION='C2510',
 CDS_LIB='pure_quanta',
 CDS_PART_NAME='Q_CAP_C0402-22UF,4V,20%,X6S,CH622KMEB02',
 VOLTAGE='4V',
 PART_NUMBER='CH622KMEB02',
 VALUE='22UF',
 PRIM_FILE='./archive_libs/logical/q_cap/chips/chips.prt';

PART_NAME
 C2511 'Q_CAP_C0402-22UF,4V,20%,X6S,CH622KMEB02':;

SECTION_NUMBER 1
 '@T6G_MB_LIB.T6G(SCH_1):PAGE73_I161@PURE_QUANTA.Q_CAP(CHIPS)':
 C_PATH='@t6g_mb_lib.t6g(sch_1):page73_i161@pure_quanta.q_cap(chips)',
 P_PATH='@t6g_mb_lib.t6g(sch_1):page74_i161@pure_quanta.q_cap(chips)',
 PATH='I161',
 DRAWING='@T6G_MB_LIB.T6G(SCH_1):PAGE73',
 TOLERANCE='20%',
 MATERIAL='X6S',
 PHYS_PAGE='74',
 XY='(9000,2025)',
 ROT='0',
 VER='1',
 PACK_TYPE='C0402',
 LOCATION='C2511',
 CDS_LIB='pure_quanta',
 CDS_PART_NAME='Q_CAP_C0402-22UF,4V,20%,X6S,CH622KMEB02',
 VOLTAGE='4V',
 PART_NUMBER='CH622KMEB02',
 VALUE='22UF',
 PRIM_FILE='./archive_libs/logical/q_cap/chips/chips.prt';

PART_NAME
 C2512 'Q_CAP_C0402-10UF,6.3V,20%,X6S,CH6101MEB01':;

SECTION_NUMBER 1
 '@T6G_MB_LIB.T6G(SCH_1):PAGE70_I26@PURE_QUANTA.Q_CAP(CHIPS)':
 C_PATH='@t6g_mb_lib.t6g(sch_1):page70_i26@pure_quanta.q_cap(chips)',
 P_PATH='@t6g_mb_lib.t6g(sch_1):page71_i26@pure_quanta.q_cap(chips)',
 PATH='I26',
 DRAWING='@T6G_MB_LIB.T6G(SCH_1):PAGE70',
 TOLERANCE='20%',
 MATERIAL='X6S',
 PHYS_PAGE='71',
 XY='(-8525,5525)',
 ROT='0',
 VER='1',
 PACK_TYPE='C0402',
 LOCATION='C2512',
 CDS_LIB='pure_quanta',
 CDS_PART_NAME='Q_CAP_C0402-10UF,6.3V,20%,X6S,CH6101MEB01',
 VOLTAGE='6.3V',
 PART_NUMBER='CH6101MEB01',
 VALUE='10UF',
 PRIM_FILE='./archive_libs/logical/q_cap/chips/chips.prt';

PART_NAME
 C2513 'Q_CAP_C0402-22UF,4V,20%,X6S,CH622KMEB02':;

SECTION_NUMBER 1
 '@T6G_MB_LIB.T6G(SCH_1):PAGE70_I3@PURE_QUANTA.Q_CAP(CHIPS)':
 C_PATH='@t6g_mb_lib.t6g(sch_1):page70_i3@pure_quanta.q_cap(chips)',
 P_PATH='@t6g_mb_lib.t6g(sch_1):page71_i3@pure_quanta.q_cap(chips)',
 PATH='I3',
 DRAWING='@T6G_MB_LIB.T6G(SCH_1):PAGE70',
 TOLERANCE='20%',
 MATERIAL='X6S',
 PHYS_PAGE='71',
 XY='(-8600,3875)',
 ROT='0',
 VER='1',
 PACK_TYPE='C0402',
 LOCATION='C2513',
 CDS_LIB='pure_quanta',
 CDS_PART_NAME='Q_CAP_C0402-22UF,4V,20%,X6S,CH622KMEB02',
 VOLTAGE='4V',
 PART_NUMBER='CH622KMEB02',
 VALUE='22UF',
 PRIM_FILE='./archive_libs/logical/q_cap/chips/chips.prt';

PART_NAME
 C2514 'Q_CAP_C0402-22UF,4V,20%,X6S,CH622KMEB02':;

SECTION_NUMBER 1
 '@T6G_MB_LIB.T6G(SCH_1):PAGE70_I1@PURE_QUANTA.Q_CAP(CHIPS)':
 C_PATH='@t6g_mb_lib.t6g(sch_1):page70_i1@pure_quanta.q_cap(chips)',
 P_PATH='@t6g_mb_lib.t6g(sch_1):page71_i1@pure_quanta.q_cap(chips)',
 PATH='I1',
 DRAWING='@T6G_MB_LIB.T6G(SCH_1):PAGE70',
 TOLERANCE='20%',
 MATERIAL='X6S',
 PHYS_PAGE='71',
 XY='(-8600,3100)',
 ROT='0',
 VER='1',
 PACK_TYPE='C0402',
 LOCATION='C2514',
 CDS_LIB='pure_quanta',
 CDS_PART_NAME='Q_CAP_C0402-22UF,4V,20%,X6S,CH622KMEB02',
 VOLTAGE='4V',
 PART_NUMBER='CH622KMEB02',
 VALUE='22UF',
 PRIM_FILE='./archive_libs/logical/q_cap/chips/chips.prt';

PART_NAME
 C2515 'Q_CAP_C0402-10UF,6.3V,20%,X6S,CH6101MEB01':;

SECTION_NUMBER 1
 '@T6G_MB_LIB.T6G(SCH_1):PAGE70_I25@PURE_QUANTA.Q_CAP(CHIPS)':
 C_PATH='@t6g_mb_lib.t6g(sch_1):page70_i25@pure_quanta.q_cap(chips)',
 P_PATH='@t6g_mb_lib.t6g(sch_1):page71_i25@pure_quanta.q_cap(chips)',
 PATH='I25',
 DRAWING='@T6G_MB_LIB.T6G(SCH_1):PAGE70',
 TOLERANCE='20%',
 MATERIAL='X6S',
 PHYS_PAGE='71',
 XY='(-8075,5525)',
 ROT='0',
 VER='1',
 PACK_TYPE='C0402',
 LOCATION='C2515',
 CDS_LIB='pure_quanta',
 CDS_PART_NAME='Q_CAP_C0402-10UF,6.3V,20%,X6S,CH6101MEB01',
 VOLTAGE='6.3V',
 PART_NUMBER='CH6101MEB01',
 VALUE='10UF',
 PRIM_FILE='./archive_libs/logical/q_cap/chips/chips.prt';

PART_NAME
 C2516 'Q_CAP_C0402-22UF,4V,20%,X6S,CH622KMEB02':;

SECTION_NUMBER 1
 '@T6G_MB_LIB.T6G(SCH_1):PAGE70_I9@PURE_QUANTA.Q_CAP(CHIPS)':
 C_PATH='@t6g_mb_lib.t6g(sch_1):page70_i9@pure_quanta.q_cap(chips)',
 P_PATH='@t6g_mb_lib.t6g(sch_1):page71_i9@pure_quanta.q_cap(chips)',
 PATH='I9',
 DRAWING='@T6G_MB_LIB.T6G(SCH_1):PAGE70',
 TOLERANCE='20%',
 MATERIAL='X6S',
 PHYS_PAGE='71',
 XY='(-8150,3875)',
 ROT='0',
 VER='1',
 PACK_TYPE='C0402',
 LOCATION='C2516',
 CDS_LIB='pure_quanta',
 CDS_PART_NAME='Q_CAP_C0402-22UF,4V,20%,X6S,CH622KMEB02',
 VOLTAGE='4V',
 PART_NUMBER='CH622KMEB02',
 VALUE='22UF',
 PRIM_FILE='./archive_libs/logical/q_cap/chips/chips.prt';

PART_NAME
 C2517 'Q_CAP_C0402-22UF,4V,20%,X6S,CH622KMEB02':;

SECTION_NUMBER 1
 '@T6G_MB_LIB.T6G(SCH_1):PAGE70_I8@PURE_QUANTA.Q_CAP(CHIPS)':
 C_PATH='@t6g_mb_lib.t6g(sch_1):page70_i8@pure_quanta.q_cap(chips)',
 P_PATH='@t6g_mb_lib.t6g(sch_1):page71_i8@pure_quanta.q_cap(chips)',
 PATH='I8',
 DRAWING='@T6G_MB_LIB.T6G(SCH_1):PAGE70',
 TOLERANCE='20%',
 MATERIAL='X6S',
 PHYS_PAGE='71',
 XY='(-8150,3100)',
 ROT='0',
 VER='1',
 PACK_TYPE='C0402',
 LOCATION='C2517',
 CDS_LIB='pure_quanta',
 CDS_PART_NAME='Q_CAP_C0402-22UF,4V,20%,X6S,CH622KMEB02',
 VOLTAGE='4V',
 PART_NUMBER='CH622KMEB02',
 VALUE='22UF',
 PRIM_FILE='./archive_libs/logical/q_cap/chips/chips.prt';

PART_NAME
 C2518 'Q_CAP_C0402-22UF,4V,20%,X6S,CH622KMEB02':;

SECTION_NUMBER 1
 '@T6G_MB_LIB.T6G(SCH_1):PAGE70_I10@PURE_QUANTA.Q_CAP(CHIPS)':
 C_PATH='@t6g_mb_lib.t6g(sch_1):page70_i10@pure_quanta.q_cap(chips)',
 P_PATH='@t6g_mb_lib.t6g(sch_1):page71_i10@pure_quanta.q_cap(chips)',
 PATH='I10',
 DRAWING='@T6G_MB_LIB.T6G(SCH_1):PAGE70',
 TOLERANCE='20%',
 MATERIAL='X6S',
 PHYS_PAGE='71',
 XY='(-7700,3875)',
 ROT='0',
 VER='1',
 PACK_TYPE='C0402',
 LOCATION='C2518',
 CDS_LIB='pure_quanta',
 CDS_PART_NAME='Q_CAP_C0402-22UF,4V,20%,X6S,CH622KMEB02',
 VOLTAGE='4V',
 PART_NUMBER='CH622KMEB02',
 VALUE='22UF',
 PRIM_FILE='./archive_libs/logical/q_cap/chips/chips.prt';

PART_NAME
 C2520 'Q_CAP_C0402-22UF,4V,20%,X6S,CH622KMEB02':;

SECTION_NUMBER 1
 '@T6G_MB_LIB.T6G(SCH_1):PAGE70_I11@PURE_QUANTA.Q_CAP(CHIPS)':
 C_PATH='@t6g_mb_lib.t6g(sch_1):page70_i11@pure_quanta.q_cap(chips)',
 P_PATH='@t6g_mb_lib.t6g(sch_1):page71_i11@pure_quanta.q_cap(chips)',
 PATH='I11',
 DRAWING='@T6G_MB_LIB.T6G(SCH_1):PAGE70',
 TOLERANCE='20%',
 MATERIAL='X6S',
 PHYS_PAGE='71',
 XY='(-7250,3875)',
 ROT='0',
 VER='1',
 PACK_TYPE='C0402',
 LOCATION='C2520',
 CDS_LIB='pure_quanta',
 CDS_PART_NAME='Q_CAP_C0402-22UF,4V,20%,X6S,CH622KMEB02',
 VOLTAGE='4V',
 PART_NUMBER='CH622KMEB02',
 VALUE='22UF',
 PRIM_FILE='./archive_libs/logical/q_cap/chips/chips.prt';

PART_NAME
 C2521 'Q_CAP_C0402-22UF,4V,20%,X6S,CH622KMEB02':;

SECTION_NUMBER 1
 '@T6G_MB_LIB.T6G(SCH_1):PAGE70_I12@PURE_QUANTA.Q_CAP(CHIPS)':
 C_PATH='@t6g_mb_lib.t6g(sch_1):page70_i12@pure_quanta.q_cap(chips)',
 P_PATH='@t6g_mb_lib.t6g(sch_1):page71_i12@pure_quanta.q_cap(chips)',
 PATH='I12',
 DRAWING='@T6G_MB_LIB.T6G(SCH_1):PAGE70',
 TOLERANCE='20%',
 MATERIAL='X6S',
 PHYS_PAGE='71',
 XY='(-6800,3875)',
 ROT='0',
 VER='1',
 PACK_TYPE='C0402',
 LOCATION='C2521',
 CDS_LIB='pure_quanta',
 CDS_PART_NAME='Q_CAP_C0402-22UF,4V,20%,X6S,CH622KMEB02',
 VOLTAGE='4V',
 PART_NUMBER='CH622KMEB02',
 VALUE='22UF',
 PRIM_FILE='./archive_libs/logical/q_cap/chips/chips.prt';

PART_NAME
 C2522 'Q_CAP_C0402-22UF,4V,20%,X6S,CH622KMEB02':;

SECTION_NUMBER 1
 '@T6G_MB_LIB.T6G(SCH_1):PAGE70_I13@PURE_QUANTA.Q_CAP(CHIPS)':
 C_PATH='@t6g_mb_lib.t6g(sch_1):page70_i13@pure_quanta.q_cap(chips)',
 P_PATH='@t6g_mb_lib.t6g(sch_1):page71_i13@pure_quanta.q_cap(chips)',
 PATH='I13',
 DRAWING='@T6G_MB_LIB.T6G(SCH_1):PAGE70',
 TOLERANCE='20%',
 MATERIAL='X6S',
 PHYS_PAGE='71',
 XY='(-6350,3875)',
 ROT='0',
 VER='1',
 PACK_TYPE='C0402',
 LOCATION='C2522',
 CDS_LIB='pure_quanta',
 CDS_PART_NAME='Q_CAP_C0402-22UF,4V,20%,X6S,CH622KMEB02',
 VOLTAGE='4V',
 PART_NUMBER='CH622KMEB02',
 VALUE='22UF',
 PRIM_FILE='./archive_libs/logical/q_cap/chips/chips.prt';

PART_NAME
 C2523 'Q_CAP_C0402-22UF,4V,20%,X6S,CH622KMEB02':;

SECTION_NUMBER 1
 '@T6G_MB_LIB.T6G(SCH_1):PAGE70_I14@PURE_QUANTA.Q_CAP(CHIPS)':
 C_PATH='@t6g_mb_lib.t6g(sch_1):page70_i14@pure_quanta.q_cap(chips)',
 P_PATH='@t6g_mb_lib.t6g(sch_1):page71_i14@pure_quanta.q_cap(chips)',
 PATH='I14',
 DRAWING='@T6G_MB_LIB.T6G(SCH_1):PAGE70',
 TOLERANCE='20%',
 MATERIAL='X6S',
 PHYS_PAGE='71',
 XY='(-5900,3875)',
 ROT='0',
 VER='1',
 PACK_TYPE='C0402',
 LOCATION='C2523',
 CDS_LIB='pure_quanta',
 CDS_PART_NAME='Q_CAP_C0402-22UF,4V,20%,X6S,CH622KMEB02',
 VOLTAGE='4V',
 PART_NUMBER='CH622KMEB02',
 VALUE='22UF',
 PRIM_FILE='./archive_libs/logical/q_cap/chips/chips.prt';

PART_NAME
 C2524 'Q_CAP_C0402-22UF,4V,20%,X6S,CH622KMEB02':;

SECTION_NUMBER 1
 '@T6G_MB_LIB.T6G(SCH_1):PAGE70_I15@PURE_QUANTA.Q_CAP(CHIPS)':
 C_PATH='@t6g_mb_lib.t6g(sch_1):page70_i15@pure_quanta.q_cap(chips)',
 P_PATH='@t6g_mb_lib.t6g(sch_1):page71_i15@pure_quanta.q_cap(chips)',
 PATH='I15',
 DRAWING='@T6G_MB_LIB.T6G(SCH_1):PAGE70',
 TOLERANCE='20%',
 MATERIAL='X6S',
 PHYS_PAGE='71',
 XY='(-5450,3875)',
 ROT='0',
 VER='1',
 PACK_TYPE='C0402',
 LOCATION='C2524',
 CDS_LIB='pure_quanta',
 CDS_PART_NAME='Q_CAP_C0402-22UF,4V,20%,X6S,CH622KMEB02',
 VOLTAGE='4V',
 PART_NUMBER='CH622KMEB02',
 VALUE='22UF',
 PRIM_FILE='./archive_libs/logical/q_cap/chips/chips.prt';

PART_NAME
 C2525 'Q_CAP_C0402-22UF,4V,20%,X6S,CH622KMEB02':;

SECTION_NUMBER 1
 '@T6G_MB_LIB.T6G(SCH_1):PAGE70_I16@PURE_QUANTA.Q_CAP(CHIPS)':
 C_PATH='@t6g_mb_lib.t6g(sch_1):page70_i16@pure_quanta.q_cap(chips)',
 P_PATH='@t6g_mb_lib.t6g(sch_1):page71_i16@pure_quanta.q_cap(chips)',
 PATH='I16',
 DRAWING='@T6G_MB_LIB.T6G(SCH_1):PAGE70',
 TOLERANCE='20%',
 MATERIAL='X6S',
 PHYS_PAGE='71',
 XY='(-5000,3875)',
 ROT='0',
 VER='1',
 PACK_TYPE='C0402',
 LOCATION='C2525',
 CDS_LIB='pure_quanta',
 CDS_PART_NAME='Q_CAP_C0402-22UF,4V,20%,X6S,CH622KMEB02',
 VOLTAGE='4V',
 PART_NUMBER='CH622KMEB02',
 VALUE='22UF',
 PRIM_FILE='./archive_libs/logical/q_cap/chips/chips.prt';

PART_NAME
 C2526 'Q_CAP_C0402-22UF,4V,20%,X6S,CH622KMEB02':;

SECTION_NUMBER 1
 '@T6G_MB_LIB.T6G(SCH_1):PAGE70_I18@PURE_QUANTA.Q_CAP(CHIPS)':
 C_PATH='@t6g_mb_lib.t6g(sch_1):page70_i18@pure_quanta.q_cap(chips)',
 P_PATH='@t6g_mb_lib.t6g(sch_1):page71_i18@pure_quanta.q_cap(chips)',
 PATH='I18',
 DRAWING='@T6G_MB_LIB.T6G(SCH_1):PAGE70',
 TOLERANCE='20%',
 MATERIAL='X6S',
 PHYS_PAGE='71',
 XY='(-4600,3875)',
 ROT='0',
 VER='1',
 PACK_TYPE='C0402',
 LOCATION='C2526',
 CDS_LIB='pure_quanta',
 CDS_PART_NAME='Q_CAP_C0402-22UF,4V,20%,X6S,CH622KMEB02',
 VOLTAGE='4V',
 PART_NUMBER='CH622KMEB02',
 VALUE='22UF',
 PRIM_FILE='./archive_libs/logical/q_cap/chips/chips.prt';

PART_NAME
 C2527 'Q_CAP_C0402-22UF,4V,20%,X6S,CH622KMEB02':;

SECTION_NUMBER 1
 '@T6G_MB_LIB.T6G(SCH_1):PAGE69_I22@PURE_QUANTA.Q_CAP(CHIPS)':
 C_PATH='@t6g_mb_lib.t6g(sch_1):page69_i22@pure_quanta.q_cap(chips)',
 P_PATH='@t6g_mb_lib.t6g(sch_1):page70_i22@pure_quanta.q_cap(chips)',
 PATH='I22',
 DRAWING='@T6G_MB_LIB.T6G(SCH_1):PAGE69',
 TOLERANCE='20%',
 MATERIAL='X6S',
 PHYS_PAGE='70',
 XY='(-9100,5900)',
 ROT='0',
 VER='1',
 PACK_TYPE='C0402',
 LOCATION='C2527',
 CDS_LIB='pure_quanta',
 CDS_PART_NAME='Q_CAP_C0402-22UF,4V,20%,X6S,CH622KMEB02',
 VOLTAGE='4V',
 PART_NUMBER='CH622KMEB02',
 VALUE='22UF',
 PRIM_FILE='./archive_libs/logical/q_cap/chips/chips.prt';

PART_NAME
 C2528 'Q_CAP_C0402-22UF,4V,20%,X6S,CH622KMEB02':;

SECTION_NUMBER 1
 '@T6G_MB_LIB.T6G(SCH_1):PAGE69_I18@PURE_QUANTA.Q_CAP(CHIPS)':
 C_PATH='@t6g_mb_lib.t6g(sch_1):page69_i18@pure_quanta.q_cap(chips)',
 P_PATH='@t6g_mb_lib.t6g(sch_1):page70_i18@pure_quanta.q_cap(chips)',
 PATH='I18',
 DRAWING='@T6G_MB_LIB.T6G(SCH_1):PAGE69',
 TOLERANCE='20%',
 MATERIAL='X6S',
 PHYS_PAGE='70',
 XY='(-9100,5150)',
 ROT='0',
 VER='1',
 PACK_TYPE='C0402',
 LOCATION='C2528',
 CDS_LIB='pure_quanta',
 CDS_PART_NAME='Q_CAP_C0402-22UF,4V,20%,X6S,CH622KMEB02',
 VOLTAGE='4V',
 PART_NUMBER='CH622KMEB02',
 VALUE='22UF',
 PRIM_FILE='./archive_libs/logical/q_cap/chips/chips.prt';

PART_NAME
 C2529 'Q_CAP_C0402-22UF,4V,20%,X6S,CH622KMEB02':;

SECTION_NUMBER 1
 '@T6G_MB_LIB.T6G(SCH_1):PAGE69_I16@PURE_QUANTA.Q_CAP(CHIPS)':
 C_PATH='@t6g_mb_lib.t6g(sch_1):page69_i16@pure_quanta.q_cap(chips)',
 P_PATH='@t6g_mb_lib.t6g(sch_1):page70_i16@pure_quanta.q_cap(chips)',
 PATH='I16',
 DRAWING='@T6G_MB_LIB.T6G(SCH_1):PAGE69',
 TOLERANCE='20%',
 MATERIAL='X6S',
 PHYS_PAGE='70',
 XY='(-9100,4425)',
 ROT='0',
 VER='1',
 PACK_TYPE='C0402',
 LOCATION='C2529',
 CDS_LIB='pure_quanta',
 CDS_PART_NAME='Q_CAP_C0402-22UF,4V,20%,X6S,CH622KMEB02',
 VOLTAGE='4V',
 PART_NUMBER='CH622KMEB02',
 VALUE='22UF',
 PRIM_FILE='./archive_libs/logical/q_cap/chips/chips.prt';

PART_NAME
 C2530 'Q_CAP_C0402-22UF,4V,20%,X6S,CH622KMEB02':;

SECTION_NUMBER 1
 '@T6G_MB_LIB.T6G(SCH_1):PAGE69_I13@PURE_QUANTA.Q_CAP(CHIPS)':
 C_PATH='@t6g_mb_lib.t6g(sch_1):page69_i13@pure_quanta.q_cap(chips)',
 P_PATH='@t6g_mb_lib.t6g(sch_1):page70_i13@pure_quanta.q_cap(chips)',
 PATH='I13',
 DRAWING='@T6G_MB_LIB.T6G(SCH_1):PAGE69',
 TOLERANCE='20%',
 MATERIAL='X6S',
 PHYS_PAGE='70',
 XY='(-9075,3725)',
 ROT='0',
 VER='1',
 PACK_TYPE='C0402',
 LOCATION='C2530',
 CDS_LIB='pure_quanta',
 CDS_PART_NAME='Q_CAP_C0402-22UF,4V,20%,X6S,CH622KMEB02',
 VOLTAGE='4V',
 PART_NUMBER='CH622KMEB02',
 VALUE='22UF',
 PRIM_FILE='./archive_libs/logical/q_cap/chips/chips.prt';

PART_NAME
 C2531 'Q_CAP_C0402-22UF,4V,20%,X6S,CH622KMEB02':;

SECTION_NUMBER 1
 '@T6G_MB_LIB.T6G(SCH_1):PAGE69_I9@PURE_QUANTA.Q_CAP(CHIPS)':
 C_PATH='@t6g_mb_lib.t6g(sch_1):page69_i9@pure_quanta.q_cap(chips)',
 P_PATH='@t6g_mb_lib.t6g(sch_1):page70_i9@pure_quanta.q_cap(chips)',
 PATH='I9',
 DRAWING='@T6G_MB_LIB.T6G(SCH_1):PAGE69',
 TOLERANCE='20%',
 MATERIAL='X6S',
 PHYS_PAGE='70',
 XY='(-9075,3000)',
 ROT='0',
 VER='1',
 PACK_TYPE='C0402',
 LOCATION='C2531',
 CDS_LIB='pure_quanta',
 CDS_PART_NAME='Q_CAP_C0402-22UF,4V,20%,X6S,CH622KMEB02',
 VOLTAGE='4V',
 PART_NUMBER='CH622KMEB02',
 VALUE='22UF',
 PRIM_FILE='./archive_libs/logical/q_cap/chips/chips.prt';

PART_NAME
 C2532 'Q_CAP_C0402-22UF,4V,20%,X6S,CH622KMEB02':;

SECTION_NUMBER 1
 '@T6G_MB_LIB.T6G(SCH_1):PAGE69_I7@PURE_QUANTA.Q_CAP(CHIPS)':
 C_PATH='@t6g_mb_lib.t6g(sch_1):page69_i7@pure_quanta.q_cap(chips)',
 P_PATH='@t6g_mb_lib.t6g(sch_1):page70_i7@pure_quanta.q_cap(chips)',
 PATH='I7',
 DRAWING='@T6G_MB_LIB.T6G(SCH_1):PAGE69',
 TOLERANCE='20%',
 MATERIAL='X6S',
 PHYS_PAGE='70',
 XY='(-9075,2300)',
 ROT='0',
 VER='1',
 PACK_TYPE='C0402',
 LOCATION='C2532',
 CDS_LIB='pure_quanta',
 CDS_PART_NAME='Q_CAP_C0402-22UF,4V,20%,X6S,CH622KMEB02',
 VOLTAGE='4V',
 PART_NUMBER='CH622KMEB02',
 VALUE='22UF',
 PRIM_FILE='./archive_libs/logical/q_cap/chips/chips.prt';

PART_NAME
 C2533 'Q_CAP_C0402-22UF,4V,20%,X6S,CH622KMEB02':;

SECTION_NUMBER 1
 '@T6G_MB_LIB.T6G(SCH_1):PAGE69_I4@PURE_QUANTA.Q_CAP(CHIPS)':
 C_PATH='@t6g_mb_lib.t6g(sch_1):page69_i4@pure_quanta.q_cap(chips)',
 P_PATH='@t6g_mb_lib.t6g(sch_1):page70_i4@pure_quanta.q_cap(chips)',
 PATH='I4',
 DRAWING='@T6G_MB_LIB.T6G(SCH_1):PAGE69',
 TOLERANCE='20%',
 MATERIAL='X6S',
 PHYS_PAGE='70',
 XY='(-9075,1575)',
 ROT='0',
 VER='1',
 PACK_TYPE='C0402',
 LOCATION='C2533',
 CDS_LIB='pure_quanta',
 CDS_PART_NAME='Q_CAP_C0402-22UF,4V,20%,X6S,CH622KMEB02',
 VOLTAGE='4V',
 PART_NUMBER='CH622KMEB02',
 VALUE='22UF',
 PRIM_FILE='./archive_libs/logical/q_cap/chips/chips.prt';

PART_NAME
 C2534 'Q_CAP_C0402-22UF,4V,20%,X6S,CH622KMEB02':;

SECTION_NUMBER 1
 '@T6G_MB_LIB.T6G(SCH_1):PAGE69_I24@PURE_QUANTA.Q_CAP(CHIPS)':
 C_PATH='@t6g_mb_lib.t6g(sch_1):page69_i24@pure_quanta.q_cap(chips)',
 P_PATH='@t6g_mb_lib.t6g(sch_1):page70_i24@pure_quanta.q_cap(chips)',
 PATH='I24',
 DRAWING='@T6G_MB_LIB.T6G(SCH_1):PAGE69',
 TOLERANCE='20%',
 MATERIAL='X6S',
 PHYS_PAGE='70',
 XY='(-8650,5900)',
 ROT='0',
 VER='1',
 PACK_TYPE='C0402',
 LOCATION='C2534',
 CDS_LIB='pure_quanta',
 CDS_PART_NAME='Q_CAP_C0402-22UF,4V,20%,X6S,CH622KMEB02',
 VOLTAGE='4V',
 PART_NUMBER='CH622KMEB02',
 VALUE='22UF',
 PRIM_FILE='./archive_libs/logical/q_cap/chips/chips.prt';

PART_NAME
 C2535 'Q_CAP_C0402-22UF,4V,20%,X6S,CH622KMEB02':;

SECTION_NUMBER 1
 '@T6G_MB_LIB.T6G(SCH_1):PAGE69_I20@PURE_QUANTA.Q_CAP(CHIPS)':
 C_PATH='@t6g_mb_lib.t6g(sch_1):page69_i20@pure_quanta.q_cap(chips)',
 P_PATH='@t6g_mb_lib.t6g(sch_1):page70_i20@pure_quanta.q_cap(chips)',
 PATH='I20',
 DRAWING='@T6G_MB_LIB.T6G(SCH_1):PAGE69',
 TOLERANCE='20%',
 MATERIAL='X6S',
 PHYS_PAGE='70',
 XY='(-8650,5150)',
 ROT='0',
 VER='1',
 PACK_TYPE='C0402',
 LOCATION='C2535',
 CDS_LIB='pure_quanta',
 CDS_PART_NAME='Q_CAP_C0402-22UF,4V,20%,X6S,CH622KMEB02',
 VOLTAGE='4V',
 PART_NUMBER='CH622KMEB02',
 VALUE='22UF',
 PRIM_FILE='./archive_libs/logical/q_cap/chips/chips.prt';

PART_NAME
 C2536 'Q_CAP_C0402-22UF,4V,20%,X6S,CH622KMEB02':;

SECTION_NUMBER 1
 '@T6G_MB_LIB.T6G(SCH_1):PAGE69_I19@PURE_QUANTA.Q_CAP(CHIPS)':
 C_PATH='@t6g_mb_lib.t6g(sch_1):page69_i19@pure_quanta.q_cap(chips)',
 P_PATH='@t6g_mb_lib.t6g(sch_1):page70_i19@pure_quanta.q_cap(chips)',
 PATH='I19',
 DRAWING='@T6G_MB_LIB.T6G(SCH_1):PAGE69',
 TOLERANCE='20%',
 MATERIAL='X6S',
 PHYS_PAGE='70',
 XY='(-8650,4425)',
 ROT='0',
 VER='1',
 PACK_TYPE='C0402',
 LOCATION='C2536',
 CDS_LIB='pure_quanta',
 CDS_PART_NAME='Q_CAP_C0402-22UF,4V,20%,X6S,CH622KMEB02',
 VOLTAGE='4V',
 PART_NUMBER='CH622KMEB02',
 VALUE='22UF',
 PRIM_FILE='./archive_libs/logical/q_cap/chips/chips.prt';

PART_NAME
 C2537 'Q_CAP_C0402-22UF,4V,20%,X6S,CH622KMEB02':;

SECTION_NUMBER 1
 '@T6G_MB_LIB.T6G(SCH_1):PAGE69_I15@PURE_QUANTA.Q_CAP(CHIPS)':
 C_PATH='@t6g_mb_lib.t6g(sch_1):page69_i15@pure_quanta.q_cap(chips)',
 P_PATH='@t6g_mb_lib.t6g(sch_1):page70_i15@pure_quanta.q_cap(chips)',
 PATH='I15',
 DRAWING='@T6G_MB_LIB.T6G(SCH_1):PAGE69',
 TOLERANCE='20%',
 MATERIAL='X6S',
 PHYS_PAGE='70',
 XY='(-8625,3725)',
 ROT='0',
 VER='1',
 PACK_TYPE='C0402',
 LOCATION='C2537',
 CDS_LIB='pure_quanta',
 CDS_PART_NAME='Q_CAP_C0402-22UF,4V,20%,X6S,CH622KMEB02',
 VOLTAGE='4V',
 PART_NUMBER='CH622KMEB02',
 VALUE='22UF',
 PRIM_FILE='./archive_libs/logical/q_cap/chips/chips.prt';

PART_NAME
 C2538 'Q_CAP_C0402-22UF,4V,20%,X6S,CH622KMEB02':;

SECTION_NUMBER 1
 '@T6G_MB_LIB.T6G(SCH_1):PAGE69_I11@PURE_QUANTA.Q_CAP(CHIPS)':
 C_PATH='@t6g_mb_lib.t6g(sch_1):page69_i11@pure_quanta.q_cap(chips)',
 P_PATH='@t6g_mb_lib.t6g(sch_1):page70_i11@pure_quanta.q_cap(chips)',
 PATH='I11',
 DRAWING='@T6G_MB_LIB.T6G(SCH_1):PAGE69',
 TOLERANCE='20%',
 MATERIAL='X6S',
 PHYS_PAGE='70',
 XY='(-8625,3000)',
 ROT='0',
 VER='1',
 PACK_TYPE='C0402',
 LOCATION='C2538',
 CDS_LIB='pure_quanta',
 CDS_PART_NAME='Q_CAP_C0402-22UF,4V,20%,X6S,CH622KMEB02',
 VOLTAGE='4V',
 PART_NUMBER='CH622KMEB02',
 VALUE='22UF',
 PRIM_FILE='./archive_libs/logical/q_cap/chips/chips.prt';

PART_NAME
 C2539 'Q_CAP_C0402-22UF,4V,20%,X6S,CH622KMEB02':;

SECTION_NUMBER 1
 '@T6G_MB_LIB.T6G(SCH_1):PAGE69_I10@PURE_QUANTA.Q_CAP(CHIPS)':
 C_PATH='@t6g_mb_lib.t6g(sch_1):page69_i10@pure_quanta.q_cap(chips)',
 P_PATH='@t6g_mb_lib.t6g(sch_1):page70_i10@pure_quanta.q_cap(chips)',
 PATH='I10',
 DRAWING='@T6G_MB_LIB.T6G(SCH_1):PAGE69',
 TOLERANCE='20%',
 MATERIAL='X6S',
 PHYS_PAGE='70',
 XY='(-8625,2300)',
 ROT='0',
 VER='1',
 PACK_TYPE='C0402',
 LOCATION='C2539',
 CDS_LIB='pure_quanta',
 CDS_PART_NAME='Q_CAP_C0402-22UF,4V,20%,X6S,CH622KMEB02',
 VOLTAGE='4V',
 PART_NUMBER='CH622KMEB02',
 VALUE='22UF',
 PRIM_FILE='./archive_libs/logical/q_cap/chips/chips.prt';

PART_NAME
 C2540 'Q_CAP_C0402-22UF,4V,20%,X6S,CH622KMEB02':;

SECTION_NUMBER 1
 '@T6G_MB_LIB.T6G(SCH_1):PAGE69_I6@PURE_QUANTA.Q_CAP(CHIPS)':
 C_PATH='@t6g_mb_lib.t6g(sch_1):page69_i6@pure_quanta.q_cap(chips)',
 P_PATH='@t6g_mb_lib.t6g(sch_1):page70_i6@pure_quanta.q_cap(chips)',
 PATH='I6',
 DRAWING='@T6G_MB_LIB.T6G(SCH_1):PAGE69',
 TOLERANCE='20%',
 MATERIAL='X6S',
 PHYS_PAGE='70',
 XY='(-8625,1575)',
 ROT='0',
 VER='1',
 PACK_TYPE='C0402',
 LOCATION='C2540',
 CDS_LIB='pure_quanta',
 CDS_PART_NAME='Q_CAP_C0402-22UF,4V,20%,X6S,CH622KMEB02',
 VOLTAGE='4V',
 PART_NUMBER='CH622KMEB02',
 VALUE='22UF',
 PRIM_FILE='./archive_libs/logical/q_cap/chips/chips.prt';

PART_NAME
 C2541 'Q_CAP_C0402-22UF,4V,20%,X6S,CH622KMEB02':;

SECTION_NUMBER 1
 '@T6G_MB_LIB.T6G(SCH_1):PAGE69_I84@PURE_QUANTA.Q_CAP(CHIPS)':
 C_PATH='@t6g_mb_lib.t6g(sch_1):page69_i84@pure_quanta.q_cap(chips)',
 P_PATH='@t6g_mb_lib.t6g(sch_1):page70_i84@pure_quanta.q_cap(chips)',
 PATH='I84',
 DRAWING='@T6G_MB_LIB.T6G(SCH_1):PAGE69',
 TOLERANCE='20%',
 MATERIAL='X6S',
 PHYS_PAGE='70',
 XY='(-8200,5900)',
 ROT='0',
 VER='1',
 PACK_TYPE='C0402',
 LOCATION='C2541',
 CDS_LIB='pure_quanta',
 CDS_PART_NAME='Q_CAP_C0402-22UF,4V,20%,X6S,CH622KMEB02',
 VOLTAGE='4V',
 PART_NUMBER='CH622KMEB02',
 VALUE='22UF',
 PRIM_FILE='./archive_libs/logical/q_cap/chips/chips.prt';

PART_NAME
 C2542 'Q_CAP_C0402-22UF,4V,20%,X6S,CH622KMEB02':;

SECTION_NUMBER 1
 '@T6G_MB_LIB.T6G(SCH_1):PAGE69_I79@PURE_QUANTA.Q_CAP(CHIPS)':
 C_PATH='@t6g_mb_lib.t6g(sch_1):page69_i79@pure_quanta.q_cap(chips)',
 P_PATH='@t6g_mb_lib.t6g(sch_1):page70_i79@pure_quanta.q_cap(chips)',
 PATH='I79',
 DRAWING='@T6G_MB_LIB.T6G(SCH_1):PAGE69',
 TOLERANCE='20%',
 MATERIAL='X6S',
 PHYS_PAGE='70',
 XY='(-8200,5150)',
 ROT='0',
 VER='1',
 PACK_TYPE='C0402',
 LOCATION='C2542',
 CDS_LIB='pure_quanta',
 CDS_PART_NAME='Q_CAP_C0402-22UF,4V,20%,X6S,CH622KMEB02',
 VOLTAGE='4V',
 PART_NUMBER='CH622KMEB02',
 VALUE='22UF',
 PRIM_FILE='./archive_libs/logical/q_cap/chips/chips.prt';

PART_NAME
 C2543 'Q_CAP_C0402-22UF,4V,20%,X6S,CH622KMEB02':;

SECTION_NUMBER 1
 '@T6G_MB_LIB.T6G(SCH_1):PAGE69_I78@PURE_QUANTA.Q_CAP(CHIPS)':
 C_PATH='@t6g_mb_lib.t6g(sch_1):page69_i78@pure_quanta.q_cap(chips)',
 P_PATH='@t6g_mb_lib.t6g(sch_1):page70_i78@pure_quanta.q_cap(chips)',
 PATH='I78',
 DRAWING='@T6G_MB_LIB.T6G(SCH_1):PAGE69',
 TOLERANCE='20%',
 MATERIAL='X6S',
 PHYS_PAGE='70',
 XY='(-8200,4425)',
 ROT='0',
 VER='1',
 PACK_TYPE='C0402',
 LOCATION='C2543',
 CDS_LIB='pure_quanta',
 CDS_PART_NAME='Q_CAP_C0402-22UF,4V,20%,X6S,CH622KMEB02',
 VOLTAGE='4V',
 PART_NUMBER='CH622KMEB02',
 VALUE='22UF',
 PRIM_FILE='./archive_libs/logical/q_cap/chips/chips.prt';

PART_NAME
 C2544 'Q_CAP_C0402-22UF,4V,20%,X6S,CH622KMEB02':;

SECTION_NUMBER 1
 '@T6G_MB_LIB.T6G(SCH_1):PAGE69_I42@PURE_QUANTA.Q_CAP(CHIPS)':
 C_PATH='@t6g_mb_lib.t6g(sch_1):page69_i42@pure_quanta.q_cap(chips)',
 P_PATH='@t6g_mb_lib.t6g(sch_1):page70_i42@pure_quanta.q_cap(chips)',
 PATH='I42',
 DRAWING='@T6G_MB_LIB.T6G(SCH_1):PAGE69',
 TOLERANCE='20%',
 MATERIAL='X6S',
 PHYS_PAGE='70',
 XY='(-8175,3725)',
 ROT='0',
 VER='1',
 PACK_TYPE='C0402',
 LOCATION='C2544',
 CDS_LIB='pure_quanta',
 CDS_PART_NAME='Q_CAP_C0402-22UF,4V,20%,X6S,CH622KMEB02',
 VOLTAGE='4V',
 PART_NUMBER='CH622KMEB02',
 VALUE='22UF',
 PRIM_FILE='./archive_libs/logical/q_cap/chips/chips.prt';

PART_NAME
 C2545 'Q_CAP_C0402-22UF,4V,20%,X6S,CH622KMEB02':;

SECTION_NUMBER 1
 '@T6G_MB_LIB.T6G(SCH_1):PAGE69_I37@PURE_QUANTA.Q_CAP(CHIPS)':
 C_PATH='@t6g_mb_lib.t6g(sch_1):page69_i37@pure_quanta.q_cap(chips)',
 P_PATH='@t6g_mb_lib.t6g(sch_1):page70_i37@pure_quanta.q_cap(chips)',
 PATH='I37',
 DRAWING='@T6G_MB_LIB.T6G(SCH_1):PAGE69',
 TOLERANCE='20%',
 MATERIAL='X6S',
 PHYS_PAGE='70',
 XY='(-8175,3000)',
 ROT='0',
 VER='1',
 PACK_TYPE='C0402',
 LOCATION='C2545',
 CDS_LIB='pure_quanta',
 CDS_PART_NAME='Q_CAP_C0402-22UF,4V,20%,X6S,CH622KMEB02',
 VOLTAGE='4V',
 PART_NUMBER='CH622KMEB02',
 VALUE='22UF',
 PRIM_FILE='./archive_libs/logical/q_cap/chips/chips.prt';

PART_NAME
 C2546 'Q_CAP_C0402-22UF,4V,20%,X6S,CH622KMEB02':;

SECTION_NUMBER 1
 '@T6G_MB_LIB.T6G(SCH_1):PAGE69_I36@PURE_QUANTA.Q_CAP(CHIPS)':
 C_PATH='@t6g_mb_lib.t6g(sch_1):page69_i36@pure_quanta.q_cap(chips)',
 P_PATH='@t6g_mb_lib.t6g(sch_1):page70_i36@pure_quanta.q_cap(chips)',
 PATH='I36',
 DRAWING='@T6G_MB_LIB.T6G(SCH_1):PAGE69',
 TOLERANCE='20%',
 MATERIAL='X6S',
 PHYS_PAGE='70',
 XY='(-8175,2300)',
 ROT='0',
 VER='1',
 PACK_TYPE='C0402',
 LOCATION='C2546',
 CDS_LIB='pure_quanta',
 CDS_PART_NAME='Q_CAP_C0402-22UF,4V,20%,X6S,CH622KMEB02',
 VOLTAGE='4V',
 PART_NUMBER='CH622KMEB02',
 VALUE='22UF',
 PRIM_FILE='./archive_libs/logical/q_cap/chips/chips.prt';

PART_NAME
 C2547 'Q_CAP_C0402-22UF,4V,20%,X6S,CH622KMEB02':;

SECTION_NUMBER 1
 '@T6G_MB_LIB.T6G(SCH_1):PAGE69_I28@PURE_QUANTA.Q_CAP(CHIPS)':
 C_PATH='@t6g_mb_lib.t6g(sch_1):page69_i28@pure_quanta.q_cap(chips)',
 P_PATH='@t6g_mb_lib.t6g(sch_1):page70_i28@pure_quanta.q_cap(chips)',
 PATH='I28',
 DRAWING='@T6G_MB_LIB.T6G(SCH_1):PAGE69',
 TOLERANCE='20%',
 MATERIAL='X6S',
 PHYS_PAGE='70',
 XY='(-8175,1575)',
 ROT='0',
 VER='1',
 PACK_TYPE='C0402',
 LOCATION='C2547',
 CDS_LIB='pure_quanta',
 CDS_PART_NAME='Q_CAP_C0402-22UF,4V,20%,X6S,CH622KMEB02',
 VOLTAGE='4V',
 PART_NUMBER='CH622KMEB02',
 VALUE='22UF',
 PRIM_FILE='./archive_libs/logical/q_cap/chips/chips.prt';

PART_NAME
 C2548 'Q_CAP_C0402-22UF,4V,20%,X6S,CH622KMEB02':;

SECTION_NUMBER 1
 '@T6G_MB_LIB.T6G(SCH_1):PAGE69_I85@PURE_QUANTA.Q_CAP(CHIPS)':
 C_PATH='@t6g_mb_lib.t6g(sch_1):page69_i85@pure_quanta.q_cap(chips)',
 P_PATH='@t6g_mb_lib.t6g(sch_1):page70_i85@pure_quanta.q_cap(chips)',
 PATH='I85',
 DRAWING='@T6G_MB_LIB.T6G(SCH_1):PAGE69',
 TOLERANCE='20%',
 MATERIAL='X6S',
 PHYS_PAGE='70',
 XY='(-7750,5900)',
 ROT='0',
 VER='1',
 PACK_TYPE='C0402',
 LOCATION='C2548',
 CDS_LIB='pure_quanta',
 CDS_PART_NAME='Q_CAP_C0402-22UF,4V,20%,X6S,CH622KMEB02',
 VOLTAGE='4V',
 PART_NUMBER='CH622KMEB02',
 VALUE='22UF',
 PRIM_FILE='./archive_libs/logical/q_cap/chips/chips.prt';

PART_NAME
 C2549 'Q_CAP_C0402-22UF,4V,20%,X6S,CH622KMEB02':;

SECTION_NUMBER 1
 '@T6G_MB_LIB.T6G(SCH_1):PAGE69_I81@PURE_QUANTA.Q_CAP(CHIPS)':
 C_PATH='@t6g_mb_lib.t6g(sch_1):page69_i81@pure_quanta.q_cap(chips)',
 P_PATH='@t6g_mb_lib.t6g(sch_1):page70_i81@pure_quanta.q_cap(chips)',
 PATH='I81',
 DRAWING='@T6G_MB_LIB.T6G(SCH_1):PAGE69',
 TOLERANCE='20%',
 MATERIAL='X6S',
 PHYS_PAGE='70',
 XY='(-7750,5150)',
 ROT='0',
 VER='1',
 PACK_TYPE='C0402',
 LOCATION='C2549',
 CDS_LIB='pure_quanta',
 CDS_PART_NAME='Q_CAP_C0402-22UF,4V,20%,X6S,CH622KMEB02',
 VOLTAGE='4V',
 PART_NUMBER='CH622KMEB02',
 VALUE='22UF',
 PRIM_FILE='./archive_libs/logical/q_cap/chips/chips.prt';

PART_NAME
 C2550 'Q_CAP_C0402-22UF,4V,20%,X6S,CH622KMEB02':;

SECTION_NUMBER 1
 '@T6G_MB_LIB.T6G(SCH_1):PAGE69_I80@PURE_QUANTA.Q_CAP(CHIPS)':
 C_PATH='@t6g_mb_lib.t6g(sch_1):page69_i80@pure_quanta.q_cap(chips)',
 P_PATH='@t6g_mb_lib.t6g(sch_1):page70_i80@pure_quanta.q_cap(chips)',
 PATH='I80',
 DRAWING='@T6G_MB_LIB.T6G(SCH_1):PAGE69',
 TOLERANCE='20%',
 MATERIAL='X6S',
 PHYS_PAGE='70',
 XY='(-7750,4425)',
 ROT='0',
 VER='1',
 PACK_TYPE='C0402',
 LOCATION='C2550',
 CDS_LIB='pure_quanta',
 CDS_PART_NAME='Q_CAP_C0402-22UF,4V,20%,X6S,CH622KMEB02',
 VOLTAGE='4V',
 PART_NUMBER='CH622KMEB02',
 VALUE='22UF',
 PRIM_FILE='./archive_libs/logical/q_cap/chips/chips.prt';

PART_NAME
 C2551 'Q_CAP_C0402-22UF,4V,20%,X6S,CH622KMEB02':;

SECTION_NUMBER 1
 '@T6G_MB_LIB.T6G(SCH_1):PAGE69_I43@PURE_QUANTA.Q_CAP(CHIPS)':
 C_PATH='@t6g_mb_lib.t6g(sch_1):page69_i43@pure_quanta.q_cap(chips)',
 P_PATH='@t6g_mb_lib.t6g(sch_1):page70_i43@pure_quanta.q_cap(chips)',
 PATH='I43',
 DRAWING='@T6G_MB_LIB.T6G(SCH_1):PAGE69',
 TOLERANCE='20%',
 MATERIAL='X6S',
 PHYS_PAGE='70',
 XY='(-7725,3725)',
 ROT='0',
 VER='1',
 PACK_TYPE='C0402',
 LOCATION='C2551',
 CDS_LIB='pure_quanta',
 CDS_PART_NAME='Q_CAP_C0402-22UF,4V,20%,X6S,CH622KMEB02',
 VOLTAGE='4V',
 PART_NUMBER='CH622KMEB02',
 VALUE='22UF',
 PRIM_FILE='./archive_libs/logical/q_cap/chips/chips.prt';

PART_NAME
 C2552 'Q_CAP_C0402-22UF,4V,20%,X6S,CH622KMEB02':;

SECTION_NUMBER 1
 '@T6G_MB_LIB.T6G(SCH_1):PAGE69_I40@PURE_QUANTA.Q_CAP(CHIPS)':
 C_PATH='@t6g_mb_lib.t6g(sch_1):page69_i40@pure_quanta.q_cap(chips)',
 P_PATH='@t6g_mb_lib.t6g(sch_1):page70_i40@pure_quanta.q_cap(chips)',
 PATH='I40',
 DRAWING='@T6G_MB_LIB.T6G(SCH_1):PAGE69',
 TOLERANCE='20%',
 MATERIAL='X6S',
 PHYS_PAGE='70',
 XY='(-7725,3000)',
 ROT='0',
 VER='1',
 PACK_TYPE='C0402',
 LOCATION='C2552',
 CDS_LIB='pure_quanta',
 CDS_PART_NAME='Q_CAP_C0402-22UF,4V,20%,X6S,CH622KMEB02',
 VOLTAGE='4V',
 PART_NUMBER='CH622KMEB02',
 VALUE='22UF',
 PRIM_FILE='./archive_libs/logical/q_cap/chips/chips.prt';

PART_NAME
 C2553 'Q_CAP_C0402-22UF,4V,20%,X6S,CH622KMEB02':;

SECTION_NUMBER 1
 '@T6G_MB_LIB.T6G(SCH_1):PAGE69_I38@PURE_QUANTA.Q_CAP(CHIPS)':
 C_PATH='@t6g_mb_lib.t6g(sch_1):page69_i38@pure_quanta.q_cap(chips)',
 P_PATH='@t6g_mb_lib.t6g(sch_1):page70_i38@pure_quanta.q_cap(chips)',
 PATH='I38',
 DRAWING='@T6G_MB_LIB.T6G(SCH_1):PAGE69',
 TOLERANCE='20%',
 MATERIAL='X6S',
 PHYS_PAGE='70',
 XY='(-7725,2300)',
 ROT='0',
 VER='1',
 PACK_TYPE='C0402',
 LOCATION='C2553',
 CDS_LIB='pure_quanta',
 CDS_PART_NAME='Q_CAP_C0402-22UF,4V,20%,X6S,CH622KMEB02',
 VOLTAGE='4V',
 PART_NUMBER='CH622KMEB02',
 VALUE='22UF',
 PRIM_FILE='./archive_libs/logical/q_cap/chips/chips.prt';

PART_NAME
 C2554 'Q_CAP_C0402-22UF,4V,20%,X6S,CH622KMEB02':;

SECTION_NUMBER 1
 '@T6G_MB_LIB.T6G(SCH_1):PAGE69_I29@PURE_QUANTA.Q_CAP(CHIPS)':
 C_PATH='@t6g_mb_lib.t6g(sch_1):page69_i29@pure_quanta.q_cap(chips)',
 P_PATH='@t6g_mb_lib.t6g(sch_1):page70_i29@pure_quanta.q_cap(chips)',
 PATH='I29',
 DRAWING='@T6G_MB_LIB.T6G(SCH_1):PAGE69',
 TOLERANCE='20%',
 MATERIAL='X6S',
 PHYS_PAGE='70',
 XY='(-7725,1575)',
 ROT='0',
 VER='1',
 PACK_TYPE='C0402',
 LOCATION='C2554',
 CDS_LIB='pure_quanta',
 CDS_PART_NAME='Q_CAP_C0402-22UF,4V,20%,X6S,CH622KMEB02',
 VOLTAGE='4V',
 PART_NUMBER='CH622KMEB02',
 VALUE='22UF',
 PRIM_FILE='./archive_libs/logical/q_cap/chips/chips.prt';

PART_NAME
 C2555 'Q_CAP_C0402-22UF,4V,20%,X6S,CH622KMEB02':;

SECTION_NUMBER 1
 '@T6G_MB_LIB.T6G(SCH_1):PAGE69_I86@PURE_QUANTA.Q_CAP(CHIPS)':
 C_PATH='@t6g_mb_lib.t6g(sch_1):page69_i86@pure_quanta.q_cap(chips)',
 P_PATH='@t6g_mb_lib.t6g(sch_1):page70_i86@pure_quanta.q_cap(chips)',
 PATH='I86',
 DRAWING='@T6G_MB_LIB.T6G(SCH_1):PAGE69',
 TOLERANCE='20%',
 MATERIAL='X6S',
 PHYS_PAGE='70',
 XY='(-7300,5900)',
 ROT='0',
 VER='1',
 PACK_TYPE='C0402',
 LOCATION='C2555',
 CDS_LIB='pure_quanta',
 CDS_PART_NAME='Q_CAP_C0402-22UF,4V,20%,X6S,CH622KMEB02',
 VOLTAGE='4V',
 PART_NUMBER='CH622KMEB02',
 VALUE='22UF',
 PRIM_FILE='./archive_libs/logical/q_cap/chips/chips.prt';

PART_NAME
 C2556 'Q_CAP_C0402-22UF,4V,20%,X6S,CH622KMEB02':;

SECTION_NUMBER 1
 '@T6G_MB_LIB.T6G(SCH_1):PAGE69_I83@PURE_QUANTA.Q_CAP(CHIPS)':
 C_PATH='@t6g_mb_lib.t6g(sch_1):page69_i83@pure_quanta.q_cap(chips)',
 P_PATH='@t6g_mb_lib.t6g(sch_1):page70_i83@pure_quanta.q_cap(chips)',
 PATH='I83',
 DRAWING='@T6G_MB_LIB.T6G(SCH_1):PAGE69',
 TOLERANCE='20%',
 MATERIAL='X6S',
 PHYS_PAGE='70',
 XY='(-7300,5150)',
 ROT='0',
 VER='1',
 PACK_TYPE='C0402',
 LOCATION='C2556',
 CDS_LIB='pure_quanta',
 CDS_PART_NAME='Q_CAP_C0402-22UF,4V,20%,X6S,CH622KMEB02',
 VOLTAGE='4V',
 PART_NUMBER='CH622KMEB02',
 VALUE='22UF',
 PRIM_FILE='./archive_libs/logical/q_cap/chips/chips.prt';

PART_NAME
 C2557 'Q_CAP_C0402-22UF,4V,20%,X6S,CH622KMEB02':;

SECTION_NUMBER 1
 '@T6G_MB_LIB.T6G(SCH_1):PAGE69_I82@PURE_QUANTA.Q_CAP(CHIPS)':
 C_PATH='@t6g_mb_lib.t6g(sch_1):page69_i82@pure_quanta.q_cap(chips)',
 P_PATH='@t6g_mb_lib.t6g(sch_1):page70_i82@pure_quanta.q_cap(chips)',
 PATH='I82',
 DRAWING='@T6G_MB_LIB.T6G(SCH_1):PAGE69',
 TOLERANCE='20%',
 MATERIAL='X6S',
 PHYS_PAGE='70',
 XY='(-7300,4425)',
 ROT='0',
 VER='1',
 PACK_TYPE='C0402',
 LOCATION='C2557',
 CDS_LIB='pure_quanta',
 CDS_PART_NAME='Q_CAP_C0402-22UF,4V,20%,X6S,CH622KMEB02',
 VOLTAGE='4V',
 PART_NUMBER='CH622KMEB02',
 VALUE='22UF',
 PRIM_FILE='./archive_libs/logical/q_cap/chips/chips.prt';

PART_NAME
 C2558 'Q_CAP_C0402-22UF,4V,20%,X6S,CH622KMEB02':;

SECTION_NUMBER 1
 '@T6G_MB_LIB.T6G(SCH_1):PAGE69_I44@PURE_QUANTA.Q_CAP(CHIPS)':
 C_PATH='@t6g_mb_lib.t6g(sch_1):page69_i44@pure_quanta.q_cap(chips)',
 P_PATH='@t6g_mb_lib.t6g(sch_1):page70_i44@pure_quanta.q_cap(chips)',
 PATH='I44',
 DRAWING='@T6G_MB_LIB.T6G(SCH_1):PAGE69',
 TOLERANCE='20%',
 MATERIAL='X6S',
 PHYS_PAGE='70',
 XY='(-7275,3725)',
 ROT='0',
 VER='1',
 PACK_TYPE='C0402',
 LOCATION='C2558',
 CDS_LIB='pure_quanta',
 CDS_PART_NAME='Q_CAP_C0402-22UF,4V,20%,X6S,CH622KMEB02',
 VOLTAGE='4V',
 PART_NUMBER='CH622KMEB02',
 VALUE='22UF',
 PRIM_FILE='./archive_libs/logical/q_cap/chips/chips.prt';

PART_NAME
 C2559 'Q_CAP_C0402-22UF,4V,20%,X6S,CH622KMEB02':;

SECTION_NUMBER 1
 '@T6G_MB_LIB.T6G(SCH_1):PAGE69_I41@PURE_QUANTA.Q_CAP(CHIPS)':
 C_PATH='@t6g_mb_lib.t6g(sch_1):page69_i41@pure_quanta.q_cap(chips)',
 P_PATH='@t6g_mb_lib.t6g(sch_1):page70_i41@pure_quanta.q_cap(chips)',
 PATH='I41',
 DRAWING='@T6G_MB_LIB.T6G(SCH_1):PAGE69',
 TOLERANCE='20%',
 MATERIAL='X6S',
 PHYS_PAGE='70',
 XY='(-7275,3000)',
 ROT='0',
 VER='1',
 PACK_TYPE='C0402',
 LOCATION='C2559',
 CDS_LIB='pure_quanta',
 CDS_PART_NAME='Q_CAP_C0402-22UF,4V,20%,X6S,CH622KMEB02',
 VOLTAGE='4V',
 PART_NUMBER='CH622KMEB02',
 VALUE='22UF',
 PRIM_FILE='./archive_libs/logical/q_cap/chips/chips.prt';

PART_NAME
 C2560 'Q_CAP_C0402-22UF,4V,20%,X6S,CH622KMEB02':;

SECTION_NUMBER 1
 '@T6G_MB_LIB.T6G(SCH_1):PAGE69_I39@PURE_QUANTA.Q_CAP(CHIPS)':
 C_PATH='@t6g_mb_lib.t6g(sch_1):page69_i39@pure_quanta.q_cap(chips)',
 P_PATH='@t6g_mb_lib.t6g(sch_1):page70_i39@pure_quanta.q_cap(chips)',
 PATH='I39',
 DRAWING='@T6G_MB_LIB.T6G(SCH_1):PAGE69',
 TOLERANCE='20%',
 MATERIAL='X6S',
 PHYS_PAGE='70',
 XY='(-7275,2300)',
 ROT='0',
 VER='1',
 PACK_TYPE='C0402',
 LOCATION='C2560',
 CDS_LIB='pure_quanta',
 CDS_PART_NAME='Q_CAP_C0402-22UF,4V,20%,X6S,CH622KMEB02',
 VOLTAGE='4V',
 PART_NUMBER='CH622KMEB02',
 VALUE='22UF',
 PRIM_FILE='./archive_libs/logical/q_cap/chips/chips.prt';

PART_NAME
 C2561 'Q_CAP_C0402-22UF,4V,20%,X6S,CH622KMEB02':;

SECTION_NUMBER 1
 '@T6G_MB_LIB.T6G(SCH_1):PAGE69_I30@PURE_QUANTA.Q_CAP(CHIPS)':
 C_PATH='@t6g_mb_lib.t6g(sch_1):page69_i30@pure_quanta.q_cap(chips)',
 P_PATH='@t6g_mb_lib.t6g(sch_1):page70_i30@pure_quanta.q_cap(chips)',
 PATH='I30',
 DRAWING='@T6G_MB_LIB.T6G(SCH_1):PAGE69',
 TOLERANCE='20%',
 MATERIAL='X6S',
 PHYS_PAGE='70',
 XY='(-7275,1575)',
 ROT='0',
 VER='1',
 PACK_TYPE='C0402',
 LOCATION='C2561',
 CDS_LIB='pure_quanta',
 CDS_PART_NAME='Q_CAP_C0402-22UF,4V,20%,X6S,CH622KMEB02',
 VOLTAGE='4V',
 PART_NUMBER='CH622KMEB02',
 VALUE='22UF',
 PRIM_FILE='./archive_libs/logical/q_cap/chips/chips.prt';

PART_NAME
 C2562 'Q_CAP_C0402-22UF,4V,20%,X6S,CH622KMEB02':;

SECTION_NUMBER 1
 '@T6G_MB_LIB.T6G(SCH_1):PAGE69_I91@PURE_QUANTA.Q_CAP(CHIPS)':
 C_PATH='@t6g_mb_lib.t6g(sch_1):page69_i91@pure_quanta.q_cap(chips)',
 P_PATH='@t6g_mb_lib.t6g(sch_1):page70_i91@pure_quanta.q_cap(chips)',
 PATH='I91',
 DRAWING='@T6G_MB_LIB.T6G(SCH_1):PAGE69',
 TOLERANCE='20%',
 MATERIAL='X6S',
 PHYS_PAGE='70',
 XY='(-6850,5900)',
 ROT='0',
 VER='1',
 PACK_TYPE='C0402',
 LOCATION='C2562',
 CDS_LIB='pure_quanta',
 CDS_PART_NAME='Q_CAP_C0402-22UF,4V,20%,X6S,CH622KMEB02',
 VOLTAGE='4V',
 PART_NUMBER='CH622KMEB02',
 VALUE='22UF',
 PRIM_FILE='./archive_libs/logical/q_cap/chips/chips.prt';

PART_NAME
 C2563 'Q_CAP_C0402-22UF,4V,20%,X6S,CH622KMEB02':;

SECTION_NUMBER 1
 '@T6G_MB_LIB.T6G(SCH_1):PAGE69_I88@PURE_QUANTA.Q_CAP(CHIPS)':
 C_PATH='@t6g_mb_lib.t6g(sch_1):page69_i88@pure_quanta.q_cap(chips)',
 P_PATH='@t6g_mb_lib.t6g(sch_1):page70_i88@pure_quanta.q_cap(chips)',
 PATH='I88',
 DRAWING='@T6G_MB_LIB.T6G(SCH_1):PAGE69',
 TOLERANCE='20%',
 MATERIAL='X6S',
 PHYS_PAGE='70',
 XY='(-6850,5150)',
 ROT='0',
 VER='1',
 PACK_TYPE='C0402',
 LOCATION='C2563',
 CDS_LIB='pure_quanta',
 CDS_PART_NAME='Q_CAP_C0402-22UF,4V,20%,X6S,CH622KMEB02',
 VOLTAGE='4V',
 PART_NUMBER='CH622KMEB02',
 VALUE='22UF',
 PRIM_FILE='./archive_libs/logical/q_cap/chips/chips.prt';

PART_NAME
 C2564 'Q_CAP_C0402-22UF,4V,20%,X6S,CH622KMEB02':;

SECTION_NUMBER 1
 '@T6G_MB_LIB.T6G(SCH_1):PAGE69_I87@PURE_QUANTA.Q_CAP(CHIPS)':
 C_PATH='@t6g_mb_lib.t6g(sch_1):page69_i87@pure_quanta.q_cap(chips)',
 P_PATH='@t6g_mb_lib.t6g(sch_1):page70_i87@pure_quanta.q_cap(chips)',
 PATH='I87',
 DRAWING='@T6G_MB_LIB.T6G(SCH_1):PAGE69',
 TOLERANCE='20%',
 MATERIAL='X6S',
 PHYS_PAGE='70',
 XY='(-6850,4425)',
 ROT='0',
 VER='1',
 PACK_TYPE='C0402',
 LOCATION='C2564',
 CDS_LIB='pure_quanta',
 CDS_PART_NAME='Q_CAP_C0402-22UF,4V,20%,X6S,CH622KMEB02',
 VOLTAGE='4V',
 PART_NUMBER='CH622KMEB02',
 VALUE='22UF',
 PRIM_FILE='./archive_libs/logical/q_cap/chips/chips.prt';

PART_NAME
 C2565 'Q_CAP_C0402-22UF,4V,20%,X6S,CH622KMEB02':;

SECTION_NUMBER 1
 '@T6G_MB_LIB.T6G(SCH_1):PAGE69_I49@PURE_QUANTA.Q_CAP(CHIPS)':
 C_PATH='@t6g_mb_lib.t6g(sch_1):page69_i49@pure_quanta.q_cap(chips)',
 P_PATH='@t6g_mb_lib.t6g(sch_1):page70_i49@pure_quanta.q_cap(chips)',
 PATH='I49',
 DRAWING='@T6G_MB_LIB.T6G(SCH_1):PAGE69',
 TOLERANCE='20%',
 MATERIAL='X6S',
 PHYS_PAGE='70',
 XY='(-6825,3725)',
 ROT='0',
 VER='1',
 PACK_TYPE='C0402',
 LOCATION='C2565',
 CDS_LIB='pure_quanta',
 CDS_PART_NAME='Q_CAP_C0402-22UF,4V,20%,X6S,CH622KMEB02',
 VOLTAGE='4V',
 PART_NUMBER='CH622KMEB02',
 VALUE='22UF',
 PRIM_FILE='./archive_libs/logical/q_cap/chips/chips.prt';

PART_NAME
 C2566 'Q_CAP_C0402-22UF,4V,20%,X6S,CH622KMEB02':;

SECTION_NUMBER 1
 '@T6G_MB_LIB.T6G(SCH_1):PAGE69_I46@PURE_QUANTA.Q_CAP(CHIPS)':
 C_PATH='@t6g_mb_lib.t6g(sch_1):page69_i46@pure_quanta.q_cap(chips)',
 P_PATH='@t6g_mb_lib.t6g(sch_1):page70_i46@pure_quanta.q_cap(chips)',
 PATH='I46',
 DRAWING='@T6G_MB_LIB.T6G(SCH_1):PAGE69',
 TOLERANCE='20%',
 MATERIAL='X6S',
 PHYS_PAGE='70',
 XY='(-6825,3000)',
 ROT='0',
 VER='1',
 PACK_TYPE='C0402',
 LOCATION='C2566',
 CDS_LIB='pure_quanta',
 CDS_PART_NAME='Q_CAP_C0402-22UF,4V,20%,X6S,CH622KMEB02',
 VOLTAGE='4V',
 PART_NUMBER='CH622KMEB02',
 VALUE='22UF',
 PRIM_FILE='./archive_libs/logical/q_cap/chips/chips.prt';

PART_NAME
 C2567 'Q_CAP_C0402-22UF,4V,20%,X6S,CH622KMEB02':;

SECTION_NUMBER 1
 '@T6G_MB_LIB.T6G(SCH_1):PAGE69_I45@PURE_QUANTA.Q_CAP(CHIPS)':
 C_PATH='@t6g_mb_lib.t6g(sch_1):page69_i45@pure_quanta.q_cap(chips)',
 P_PATH='@t6g_mb_lib.t6g(sch_1):page70_i45@pure_quanta.q_cap(chips)',
 PATH='I45',
 DRAWING='@T6G_MB_LIB.T6G(SCH_1):PAGE69',
 TOLERANCE='20%',
 MATERIAL='X6S',
 PHYS_PAGE='70',
 XY='(-6825,2300)',
 ROT='0',
 VER='1',
 PACK_TYPE='C0402',
 LOCATION='C2567',
 CDS_LIB='pure_quanta',
 CDS_PART_NAME='Q_CAP_C0402-22UF,4V,20%,X6S,CH622KMEB02',
 VOLTAGE='4V',
 PART_NUMBER='CH622KMEB02',
 VALUE='22UF',
 PRIM_FILE='./archive_libs/logical/q_cap/chips/chips.prt';

PART_NAME
 C2568 'Q_CAP_C0402-22UF,4V,20%,X6S,CH622KMEB02':;

SECTION_NUMBER 1
 '@T6G_MB_LIB.T6G(SCH_1):PAGE69_I34@PURE_QUANTA.Q_CAP(CHIPS)':
 C_PATH='@t6g_mb_lib.t6g(sch_1):page69_i34@pure_quanta.q_cap(chips)',
 P_PATH='@t6g_mb_lib.t6g(sch_1):page70_i34@pure_quanta.q_cap(chips)',
 PATH='I34',
 DRAWING='@T6G_MB_LIB.T6G(SCH_1):PAGE69',
 TOLERANCE='20%',
 MATERIAL='X6S',
 PHYS_PAGE='70',
 XY='(-6825,1575)',
 ROT='0',
 VER='1',
 PACK_TYPE='C0402',
 LOCATION='C2568',
 CDS_LIB='pure_quanta',
 CDS_PART_NAME='Q_CAP_C0402-22UF,4V,20%,X6S,CH622KMEB02',
 VOLTAGE='4V',
 PART_NUMBER='CH622KMEB02',
 VALUE='22UF',
 PRIM_FILE='./archive_libs/logical/q_cap/chips/chips.prt';

PART_NAME
 C2569 'Q_CAP_C0402-22UF,4V,20%,X6S,CH622KMEB02':;

SECTION_NUMBER 1
 '@T6G_MB_LIB.T6G(SCH_1):PAGE69_I92@PURE_QUANTA.Q_CAP(CHIPS)':
 C_PATH='@t6g_mb_lib.t6g(sch_1):page69_i92@pure_quanta.q_cap(chips)',
 P_PATH='@t6g_mb_lib.t6g(sch_1):page70_i92@pure_quanta.q_cap(chips)',
 PATH='I92',
 DRAWING='@T6G_MB_LIB.T6G(SCH_1):PAGE69',
 TOLERANCE='20%',
 MATERIAL='X6S',
 PHYS_PAGE='70',
 XY='(-6400,5900)',
 ROT='0',
 VER='1',
 PACK_TYPE='C0402',
 LOCATION='C2569',
 CDS_LIB='pure_quanta',
 CDS_PART_NAME='Q_CAP_C0402-22UF,4V,20%,X6S,CH622KMEB02',
 VOLTAGE='4V',
 PART_NUMBER='CH622KMEB02',
 VALUE='22UF',
 PRIM_FILE='./archive_libs/logical/q_cap/chips/chips.prt';

PART_NAME
 C2570 'Q_CAP_C0402-22UF,4V,20%,X6S,CH622KMEB02':;

SECTION_NUMBER 1
 '@T6G_MB_LIB.T6G(SCH_1):PAGE69_I90@PURE_QUANTA.Q_CAP(CHIPS)':
 C_PATH='@t6g_mb_lib.t6g(sch_1):page69_i90@pure_quanta.q_cap(chips)',
 P_PATH='@t6g_mb_lib.t6g(sch_1):page70_i90@pure_quanta.q_cap(chips)',
 PATH='I90',
 DRAWING='@T6G_MB_LIB.T6G(SCH_1):PAGE69',
 TOLERANCE='20%',
 MATERIAL='X6S',
 PHYS_PAGE='70',
 XY='(-6400,5150)',
 ROT='0',
 VER='1',
 PACK_TYPE='C0402',
 LOCATION='C2570',
 CDS_LIB='pure_quanta',
 CDS_PART_NAME='Q_CAP_C0402-22UF,4V,20%,X6S,CH622KMEB02',
 VOLTAGE='4V',
 PART_NUMBER='CH622KMEB02',
 VALUE='22UF',
 PRIM_FILE='./archive_libs/logical/q_cap/chips/chips.prt';

PART_NAME
 C2571 'Q_CAP_C0402-22UF,4V,20%,X6S,CH622KMEB02':;

SECTION_NUMBER 1
 '@T6G_MB_LIB.T6G(SCH_1):PAGE69_I89@PURE_QUANTA.Q_CAP(CHIPS)':
 C_PATH='@t6g_mb_lib.t6g(sch_1):page69_i89@pure_quanta.q_cap(chips)',
 P_PATH='@t6g_mb_lib.t6g(sch_1):page70_i89@pure_quanta.q_cap(chips)',
 PATH='I89',
 DRAWING='@T6G_MB_LIB.T6G(SCH_1):PAGE69',
 TOLERANCE='20%',
 MATERIAL='X6S',
 PHYS_PAGE='70',
 XY='(-6400,4425)',
 ROT='0',
 VER='1',
 PACK_TYPE='C0402',
 LOCATION='C2571',
 CDS_LIB='pure_quanta',
 CDS_PART_NAME='Q_CAP_C0402-22UF,4V,20%,X6S,CH622KMEB02',
 VOLTAGE='4V',
 PART_NUMBER='CH622KMEB02',
 VALUE='22UF',
 PRIM_FILE='./archive_libs/logical/q_cap/chips/chips.prt';

PART_NAME
 C2572 'Q_CAP_C0402-22UF,4V,20%,X6S,CH622KMEB02':;

SECTION_NUMBER 1
 '@T6G_MB_LIB.T6G(SCH_1):PAGE69_I50@PURE_QUANTA.Q_CAP(CHIPS)':
 C_PATH='@t6g_mb_lib.t6g(sch_1):page69_i50@pure_quanta.q_cap(chips)',
 P_PATH='@t6g_mb_lib.t6g(sch_1):page70_i50@pure_quanta.q_cap(chips)',
 PATH='I50',
 DRAWING='@T6G_MB_LIB.T6G(SCH_1):PAGE69',
 TOLERANCE='20%',
 MATERIAL='X6S',
 PHYS_PAGE='70',
 XY='(-6375,3725)',
 ROT='0',
 VER='1',
 PACK_TYPE='C0402',
 LOCATION='C2572',
 CDS_LIB='pure_quanta',
 CDS_PART_NAME='Q_CAP_C0402-22UF,4V,20%,X6S,CH622KMEB02',
 VOLTAGE='4V',
 PART_NUMBER='CH622KMEB02',
 VALUE='22UF',
 PRIM_FILE='./archive_libs/logical/q_cap/chips/chips.prt';

PART_NAME
 C2573 'Q_CAP_C0402-22UF,4V,20%,X6S,CH622KMEB02':;

SECTION_NUMBER 1
 '@T6G_MB_LIB.T6G(SCH_1):PAGE69_I48@PURE_QUANTA.Q_CAP(CHIPS)':
 C_PATH='@t6g_mb_lib.t6g(sch_1):page69_i48@pure_quanta.q_cap(chips)',
 P_PATH='@t6g_mb_lib.t6g(sch_1):page70_i48@pure_quanta.q_cap(chips)',
 PATH='I48',
 DRAWING='@T6G_MB_LIB.T6G(SCH_1):PAGE69',
 TOLERANCE='20%',
 MATERIAL='X6S',
 PHYS_PAGE='70',
 XY='(-6375,3000)',
 ROT='0',
 VER='1',
 PACK_TYPE='C0402',
 LOCATION='C2573',
 CDS_LIB='pure_quanta',
 CDS_PART_NAME='Q_CAP_C0402-22UF,4V,20%,X6S,CH622KMEB02',
 VOLTAGE='4V',
 PART_NUMBER='CH622KMEB02',
 VALUE='22UF',
 PRIM_FILE='./archive_libs/logical/q_cap/chips/chips.prt';

PART_NAME
 C2574 'Q_CAP_C0402-22UF,4V,20%,X6S,CH622KMEB02':;

SECTION_NUMBER 1
 '@T6G_MB_LIB.T6G(SCH_1):PAGE69_I47@PURE_QUANTA.Q_CAP(CHIPS)':
 C_PATH='@t6g_mb_lib.t6g(sch_1):page69_i47@pure_quanta.q_cap(chips)',
 P_PATH='@t6g_mb_lib.t6g(sch_1):page70_i47@pure_quanta.q_cap(chips)',
 PATH='I47',
 DRAWING='@T6G_MB_LIB.T6G(SCH_1):PAGE69',
 TOLERANCE='20%',
 MATERIAL='X6S',
 PHYS_PAGE='70',
 XY='(-6375,2300)',
 ROT='0',
 VER='1',
 PACK_TYPE='C0402',
 LOCATION='C2574',
 CDS_LIB='pure_quanta',
 CDS_PART_NAME='Q_CAP_C0402-22UF,4V,20%,X6S,CH622KMEB02',
 VOLTAGE='4V',
 PART_NUMBER='CH622KMEB02',
 VALUE='22UF',
 PRIM_FILE='./archive_libs/logical/q_cap/chips/chips.prt';

PART_NAME
 C2575 'Q_CAP_C0402-22UF,4V,20%,X6S,CH622KMEB02':;

SECTION_NUMBER 1
 '@T6G_MB_LIB.T6G(SCH_1):PAGE69_I35@PURE_QUANTA.Q_CAP(CHIPS)':
 C_PATH='@t6g_mb_lib.t6g(sch_1):page69_i35@pure_quanta.q_cap(chips)',
 P_PATH='@t6g_mb_lib.t6g(sch_1):page70_i35@pure_quanta.q_cap(chips)',
 PATH='I35',
 DRAWING='@T6G_MB_LIB.T6G(SCH_1):PAGE69',
 TOLERANCE='20%',
 MATERIAL='X6S',
 PHYS_PAGE='70',
 XY='(-6375,1575)',
 ROT='0',
 VER='1',
 PACK_TYPE='C0402',
 LOCATION='C2575',
 CDS_LIB='pure_quanta',
 CDS_PART_NAME='Q_CAP_C0402-22UF,4V,20%,X6S,CH622KMEB02',
 VOLTAGE='4V',
 PART_NUMBER='CH622KMEB02',
 VALUE='22UF',
 PRIM_FILE='./archive_libs/logical/q_cap/chips/chips.prt';

PART_NAME
 C2576 'Q_CAP_C0402-22UF,4V,20%,X6S,CH622KMEB02':;

SECTION_NUMBER 1
 '@T6G_MB_LIB.T6G(SCH_1):PAGE69_I97@PURE_QUANTA.Q_CAP(CHIPS)':
 C_PATH='@t6g_mb_lib.t6g(sch_1):page69_i97@pure_quanta.q_cap(chips)',
 P_PATH='@t6g_mb_lib.t6g(sch_1):page70_i97@pure_quanta.q_cap(chips)',
 PATH='I97',
 DRAWING='@T6G_MB_LIB.T6G(SCH_1):PAGE69',
 TOLERANCE='20%',
 MATERIAL='X6S',
 PHYS_PAGE='70',
 XY='(-5950,5900)',
 ROT='0',
 VER='1',
 PACK_TYPE='C0402',
 LOCATION='C2576',
 CDS_LIB='pure_quanta',
 CDS_PART_NAME='Q_CAP_C0402-22UF,4V,20%,X6S,CH622KMEB02',
 VOLTAGE='4V',
 PART_NUMBER='CH622KMEB02',
 VALUE='22UF',
 PRIM_FILE='./archive_libs/logical/q_cap/chips/chips.prt';

PART_NAME
 C2577 'Q_CAP_C0402-22UF,4V,20%,X6S,CH622KMEB02':;

SECTION_NUMBER 1
 '@T6G_MB_LIB.T6G(SCH_1):PAGE69_I94@PURE_QUANTA.Q_CAP(CHIPS)':
 C_PATH='@t6g_mb_lib.t6g(sch_1):page69_i94@pure_quanta.q_cap(chips)',
 P_PATH='@t6g_mb_lib.t6g(sch_1):page70_i94@pure_quanta.q_cap(chips)',
 PATH='I94',
 DRAWING='@T6G_MB_LIB.T6G(SCH_1):PAGE69',
 TOLERANCE='20%',
 MATERIAL='X6S',
 PHYS_PAGE='70',
 XY='(-5950,5150)',
 ROT='0',
 VER='1',
 PACK_TYPE='C0402',
 LOCATION='C2577',
 CDS_LIB='pure_quanta',
 CDS_PART_NAME='Q_CAP_C0402-22UF,4V,20%,X6S,CH622KMEB02',
 VOLTAGE='4V',
 PART_NUMBER='CH622KMEB02',
 VALUE='22UF',
 PRIM_FILE='./archive_libs/logical/q_cap/chips/chips.prt';

PART_NAME
 C2578 'Q_CAP_C0402-22UF,4V,20%,X6S,CH622KMEB02':;

SECTION_NUMBER 1
 '@T6G_MB_LIB.T6G(SCH_1):PAGE69_I93@PURE_QUANTA.Q_CAP(CHIPS)':
 C_PATH='@t6g_mb_lib.t6g(sch_1):page69_i93@pure_quanta.q_cap(chips)',
 P_PATH='@t6g_mb_lib.t6g(sch_1):page70_i93@pure_quanta.q_cap(chips)',
 PATH='I93',
 DRAWING='@T6G_MB_LIB.T6G(SCH_1):PAGE69',
 TOLERANCE='20%',
 MATERIAL='X6S',
 PHYS_PAGE='70',
 XY='(-5950,4425)',
 ROT='0',
 VER='1',
 PACK_TYPE='C0402',
 LOCATION='C2578',
 CDS_LIB='pure_quanta',
 CDS_PART_NAME='Q_CAP_C0402-22UF,4V,20%,X6S,CH622KMEB02',
 VOLTAGE='4V',
 PART_NUMBER='CH622KMEB02',
 VALUE='22UF',
 PRIM_FILE='./archive_libs/logical/q_cap/chips/chips.prt';

PART_NAME
 C2579 'Q_CAP_C0402-22UF,4V,20%,X6S,CH622KMEB02':;

SECTION_NUMBER 1
 '@T6G_MB_LIB.T6G(SCH_1):PAGE69_I65@PURE_QUANTA.Q_CAP(CHIPS)':
 C_PATH='@t6g_mb_lib.t6g(sch_1):page69_i65@pure_quanta.q_cap(chips)',
 P_PATH='@t6g_mb_lib.t6g(sch_1):page70_i65@pure_quanta.q_cap(chips)',
 PATH='I65',
 DRAWING='@T6G_MB_LIB.T6G(SCH_1):PAGE69',
 TOLERANCE='20%',
 MATERIAL='X6S',
 PHYS_PAGE='70',
 XY='(-5925,3725)',
 ROT='0',
 VER='1',
 PACK_TYPE='C0402',
 LOCATION='C2579',
 CDS_LIB='pure_quanta',
 CDS_PART_NAME='Q_CAP_C0402-22UF,4V,20%,X6S,CH622KMEB02',
 VOLTAGE='4V',
 PART_NUMBER='CH622KMEB02',
 VALUE='22UF',
 PRIM_FILE='./archive_libs/logical/q_cap/chips/chips.prt';

PART_NAME
 C2580 'Q_CAP_C0402-22UF,4V,20%,X6S,CH622KMEB02':;

SECTION_NUMBER 1
 '@T6G_MB_LIB.T6G(SCH_1):PAGE69_I62@PURE_QUANTA.Q_CAP(CHIPS)':
 C_PATH='@t6g_mb_lib.t6g(sch_1):page69_i62@pure_quanta.q_cap(chips)',
 P_PATH='@t6g_mb_lib.t6g(sch_1):page70_i62@pure_quanta.q_cap(chips)',
 PATH='I62',
 DRAWING='@T6G_MB_LIB.T6G(SCH_1):PAGE69',
 TOLERANCE='20%',
 MATERIAL='X6S',
 PHYS_PAGE='70',
 XY='(-5925,3000)',
 ROT='0',
 VER='1',
 PACK_TYPE='C0402',
 LOCATION='C2580',
 CDS_LIB='pure_quanta',
 CDS_PART_NAME='Q_CAP_C0402-22UF,4V,20%,X6S,CH622KMEB02',
 VOLTAGE='4V',
 PART_NUMBER='CH622KMEB02',
 VALUE='22UF',
 PRIM_FILE='./archive_libs/logical/q_cap/chips/chips.prt';

PART_NAME
 C2581 'Q_CAP_C0402-22UF,4V,20%,X6S,CH622KMEB02':;

SECTION_NUMBER 1
 '@T6G_MB_LIB.T6G(SCH_1):PAGE69_I61@PURE_QUANTA.Q_CAP(CHIPS)':
 C_PATH='@t6g_mb_lib.t6g(sch_1):page69_i61@pure_quanta.q_cap(chips)',
 P_PATH='@t6g_mb_lib.t6g(sch_1):page70_i61@pure_quanta.q_cap(chips)',
 PATH='I61',
 DRAWING='@T6G_MB_LIB.T6G(SCH_1):PAGE69',
 TOLERANCE='20%',
 MATERIAL='X6S',
 PHYS_PAGE='70',
 XY='(-5925,2300)',
 ROT='0',
 VER='1',
 PACK_TYPE='C0402',
 LOCATION='C2581',
 CDS_LIB='pure_quanta',
 CDS_PART_NAME='Q_CAP_C0402-22UF,4V,20%,X6S,CH622KMEB02',
 VOLTAGE='4V',
 PART_NUMBER='CH622KMEB02',
 VALUE='22UF',
 PRIM_FILE='./archive_libs/logical/q_cap/chips/chips.prt';

PART_NAME
 C2582 'Q_CAP_C0402-22UF,4V,20%,X6S,CH622KMEB02':;

SECTION_NUMBER 1
 '@T6G_MB_LIB.T6G(SCH_1):PAGE69_I51@PURE_QUANTA.Q_CAP(CHIPS)':
 C_PATH='@t6g_mb_lib.t6g(sch_1):page69_i51@pure_quanta.q_cap(chips)',
 P_PATH='@t6g_mb_lib.t6g(sch_1):page70_i51@pure_quanta.q_cap(chips)',
 PATH='I51',
 DRAWING='@T6G_MB_LIB.T6G(SCH_1):PAGE69',
 TOLERANCE='20%',
 MATERIAL='X6S',
 PHYS_PAGE='70',
 XY='(-5925,1575)',
 ROT='0',
 VER='1',
 PACK_TYPE='C0402',
 LOCATION='C2582',
 CDS_LIB='pure_quanta',
 CDS_PART_NAME='Q_CAP_C0402-22UF,4V,20%,X6S,CH622KMEB02',
 VOLTAGE='4V',
 PART_NUMBER='CH622KMEB02',
 VALUE='22UF',
 PRIM_FILE='./archive_libs/logical/q_cap/chips/chips.prt';

PART_NAME
 C2583 'Q_CAP_C0402-22UF,4V,20%,X6S,CH622KMEB02':;

SECTION_NUMBER 1
 '@T6G_MB_LIB.T6G(SCH_1):PAGE69_I98@PURE_QUANTA.Q_CAP(CHIPS)':
 C_PATH='@t6g_mb_lib.t6g(sch_1):page69_i98@pure_quanta.q_cap(chips)',
 P_PATH='@t6g_mb_lib.t6g(sch_1):page70_i98@pure_quanta.q_cap(chips)',
 PATH='I98',
 DRAWING='@T6G_MB_LIB.T6G(SCH_1):PAGE69',
 TOLERANCE='20%',
 MATERIAL='X6S',
 PHYS_PAGE='70',
 XY='(-5500,5900)',
 ROT='0',
 VER='1',
 PACK_TYPE='C0402',
 LOCATION='C2583',
 CDS_LIB='pure_quanta',
 CDS_PART_NAME='Q_CAP_C0402-22UF,4V,20%,X6S,CH622KMEB02',
 VOLTAGE='4V',
 PART_NUMBER='CH622KMEB02',
 VALUE='22UF',
 PRIM_FILE='./archive_libs/logical/q_cap/chips/chips.prt';

PART_NAME
 C2584 'Q_CAP_C0402-22UF,4V,20%,X6S,CH622KMEB02':;

SECTION_NUMBER 1
 '@T6G_MB_LIB.T6G(SCH_1):PAGE69_I96@PURE_QUANTA.Q_CAP(CHIPS)':
 C_PATH='@t6g_mb_lib.t6g(sch_1):page69_i96@pure_quanta.q_cap(chips)',
 P_PATH='@t6g_mb_lib.t6g(sch_1):page70_i96@pure_quanta.q_cap(chips)',
 PATH='I96',
 DRAWING='@T6G_MB_LIB.T6G(SCH_1):PAGE69',
 TOLERANCE='20%',
 MATERIAL='X6S',
 PHYS_PAGE='70',
 XY='(-5500,5150)',
 ROT='0',
 VER='1',
 PACK_TYPE='C0402',
 LOCATION='C2584',
 CDS_LIB='pure_quanta',
 CDS_PART_NAME='Q_CAP_C0402-22UF,4V,20%,X6S,CH622KMEB02',
 VOLTAGE='4V',
 PART_NUMBER='CH622KMEB02',
 VALUE='22UF',
 PRIM_FILE='./archive_libs/logical/q_cap/chips/chips.prt';

PART_NAME
 C2585 'Q_CAP_C0402-22UF,4V,20%,X6S,CH622KMEB02':;

SECTION_NUMBER 1
 '@T6G_MB_LIB.T6G(SCH_1):PAGE69_I95@PURE_QUANTA.Q_CAP(CHIPS)':
 C_PATH='@t6g_mb_lib.t6g(sch_1):page69_i95@pure_quanta.q_cap(chips)',
 P_PATH='@t6g_mb_lib.t6g(sch_1):page70_i95@pure_quanta.q_cap(chips)',
 PATH='I95',
 DRAWING='@T6G_MB_LIB.T6G(SCH_1):PAGE69',
 TOLERANCE='20%',
 MATERIAL='X6S',
 PHYS_PAGE='70',
 XY='(-5500,4425)',
 ROT='0',
 VER='1',
 PACK_TYPE='C0402',
 LOCATION='C2585',
 CDS_LIB='pure_quanta',
 CDS_PART_NAME='Q_CAP_C0402-22UF,4V,20%,X6S,CH622KMEB02',
 VOLTAGE='4V',
 PART_NUMBER='CH622KMEB02',
 VALUE='22UF',
 PRIM_FILE='./archive_libs/logical/q_cap/chips/chips.prt';

PART_NAME
 C2586 'Q_CAP_C0402-22UF,4V,20%,X6S,CH622KMEB02':;

SECTION_NUMBER 1
 '@T6G_MB_LIB.T6G(SCH_1):PAGE69_I66@PURE_QUANTA.Q_CAP(CHIPS)':
 C_PATH='@t6g_mb_lib.t6g(sch_1):page69_i66@pure_quanta.q_cap(chips)',
 P_PATH='@t6g_mb_lib.t6g(sch_1):page70_i66@pure_quanta.q_cap(chips)',
 PATH='I66',
 DRAWING='@T6G_MB_LIB.T6G(SCH_1):PAGE69',
 TOLERANCE='20%',
 MATERIAL='X6S',
 PHYS_PAGE='70',
 XY='(-5475,3725)',
 ROT='0',
 VER='1',
 PACK_TYPE='C0402',
 LOCATION='C2586',
 CDS_LIB='pure_quanta',
 CDS_PART_NAME='Q_CAP_C0402-22UF,4V,20%,X6S,CH622KMEB02',
 VOLTAGE='4V',
 PART_NUMBER='CH622KMEB02',
 VALUE='22UF',
 PRIM_FILE='./archive_libs/logical/q_cap/chips/chips.prt';

PART_NAME
 C2587 'Q_CAP_C0402-22UF,4V,20%,X6S,CH622KMEB02':;

SECTION_NUMBER 1
 '@T6G_MB_LIB.T6G(SCH_1):PAGE69_I64@PURE_QUANTA.Q_CAP(CHIPS)':
 C_PATH='@t6g_mb_lib.t6g(sch_1):page69_i64@pure_quanta.q_cap(chips)',
 P_PATH='@t6g_mb_lib.t6g(sch_1):page70_i64@pure_quanta.q_cap(chips)',
 PATH='I64',
 DRAWING='@T6G_MB_LIB.T6G(SCH_1):PAGE69',
 TOLERANCE='20%',
 MATERIAL='X6S',
 PHYS_PAGE='70',
 XY='(-5475,3000)',
 ROT='0',
 VER='1',
 PACK_TYPE='C0402',
 LOCATION='C2587',
 CDS_LIB='pure_quanta',
 CDS_PART_NAME='Q_CAP_C0402-22UF,4V,20%,X6S,CH622KMEB02',
 VOLTAGE='4V',
 PART_NUMBER='CH622KMEB02',
 VALUE='22UF',
 PRIM_FILE='./archive_libs/logical/q_cap/chips/chips.prt';

PART_NAME
 C2588 'Q_CAP_C0402-22UF,4V,20%,X6S,CH622KMEB02':;

SECTION_NUMBER 1
 '@T6G_MB_LIB.T6G(SCH_1):PAGE69_I63@PURE_QUANTA.Q_CAP(CHIPS)':
 C_PATH='@t6g_mb_lib.t6g(sch_1):page69_i63@pure_quanta.q_cap(chips)',
 P_PATH='@t6g_mb_lib.t6g(sch_1):page70_i63@pure_quanta.q_cap(chips)',
 PATH='I63',
 DRAWING='@T6G_MB_LIB.T6G(SCH_1):PAGE69',
 TOLERANCE='20%',
 MATERIAL='X6S',
 PHYS_PAGE='70',
 XY='(-5475,2300)',
 ROT='0',
 VER='1',
 PACK_TYPE='C0402',
 LOCATION='C2588',
 CDS_LIB='pure_quanta',
 CDS_PART_NAME='Q_CAP_C0402-22UF,4V,20%,X6S,CH622KMEB02',
 VOLTAGE='4V',
 PART_NUMBER='CH622KMEB02',
 VALUE='22UF',
 PRIM_FILE='./archive_libs/logical/q_cap/chips/chips.prt';

PART_NAME
 C2589 'Q_CAP_C0402-22UF,4V,20%,X6S,CH622KMEB02':;

SECTION_NUMBER 1
 '@T6G_MB_LIB.T6G(SCH_1):PAGE69_I52@PURE_QUANTA.Q_CAP(CHIPS)':
 C_PATH='@t6g_mb_lib.t6g(sch_1):page69_i52@pure_quanta.q_cap(chips)',
 P_PATH='@t6g_mb_lib.t6g(sch_1):page70_i52@pure_quanta.q_cap(chips)',
 PATH='I52',
 DRAWING='@T6G_MB_LIB.T6G(SCH_1):PAGE69',
 TOLERANCE='20%',
 MATERIAL='X6S',
 PHYS_PAGE='70',
 XY='(-5475,1575)',
 ROT='0',
 VER='1',
 PACK_TYPE='C0402',
 LOCATION='C2589',
 CDS_LIB='pure_quanta',
 CDS_PART_NAME='Q_CAP_C0402-22UF,4V,20%,X6S,CH622KMEB02',
 VOLTAGE='4V',
 PART_NUMBER='CH622KMEB02',
 VALUE='22UF',
 PRIM_FILE='./archive_libs/logical/q_cap/chips/chips.prt';

PART_NAME
 C2590 'Q_CAP_C0402-22UF,4V,20%,X6S,CH622KMEB02':;

SECTION_NUMBER 1
 '@T6G_MB_LIB.T6G(SCH_1):PAGE69_I106@PURE_QUANTA.Q_CAP(CHIPS)':
 C_PATH='@t6g_mb_lib.t6g(sch_1):page69_i106@pure_quanta.q_cap(chips)',
 P_PATH='@t6g_mb_lib.t6g(sch_1):page70_i106@pure_quanta.q_cap(chips)',
 PATH='I106',
 DRAWING='@T6G_MB_LIB.T6G(SCH_1):PAGE69',
 TOLERANCE='20%',
 MATERIAL='X6S',
 PHYS_PAGE='70',
 XY='(-5100,5900)',
 ROT='0',
 VER='1',
 PACK_TYPE='C0402',
 LOCATION='C2590',
 CDS_LIB='pure_quanta',
 CDS_PART_NAME='Q_CAP_C0402-22UF,4V,20%,X6S,CH622KMEB02',
 VOLTAGE='4V',
 PART_NUMBER='CH622KMEB02',
 VALUE='22UF',
 PRIM_FILE='./archive_libs/logical/q_cap/chips/chips.prt';

PART_NAME
 C2591 'Q_CAP_C0402-22UF,4V,20%,X6S,CH622KMEB02':;

SECTION_NUMBER 1
 '@T6G_MB_LIB.T6G(SCH_1):PAGE69_I101@PURE_QUANTA.Q_CAP(CHIPS)':
 C_PATH='@t6g_mb_lib.t6g(sch_1):page69_i101@pure_quanta.q_cap(chips)',
 P_PATH='@t6g_mb_lib.t6g(sch_1):page70_i101@pure_quanta.q_cap(chips)',
 PATH='I101',
 DRAWING='@T6G_MB_LIB.T6G(SCH_1):PAGE69',
 TOLERANCE='20%',
 MATERIAL='X6S',
 PHYS_PAGE='70',
 XY='(-5100,5150)',
 ROT='0',
 VER='1',
 PACK_TYPE='C0402',
 LOCATION='C2591',
 CDS_LIB='pure_quanta',
 CDS_PART_NAME='Q_CAP_C0402-22UF,4V,20%,X6S,CH622KMEB02',
 VOLTAGE='4V',
 PART_NUMBER='CH622KMEB02',
 VALUE='22UF',
 PRIM_FILE='./archive_libs/logical/q_cap/chips/chips.prt';

PART_NAME
 C2592 'Q_CAP_C0402-22UF,4V,20%,X6S,CH622KMEB02':;

SECTION_NUMBER 1
 '@T6G_MB_LIB.T6G(SCH_1):PAGE69_I99@PURE_QUANTA.Q_CAP(CHIPS)':
 C_PATH='@t6g_mb_lib.t6g(sch_1):page69_i99@pure_quanta.q_cap(chips)',
 P_PATH='@t6g_mb_lib.t6g(sch_1):page70_i99@pure_quanta.q_cap(chips)',
 PATH='I99',
 DRAWING='@T6G_MB_LIB.T6G(SCH_1):PAGE69',
 TOLERANCE='20%',
 MATERIAL='X6S',
 PHYS_PAGE='70',
 XY='(-5100,4425)',
 ROT='0',
 VER='1',
 PACK_TYPE='C0402',
 LOCATION='C2592',
 CDS_LIB='pure_quanta',
 CDS_PART_NAME='Q_CAP_C0402-22UF,4V,20%,X6S,CH622KMEB02',
 VOLTAGE='4V',
 PART_NUMBER='CH622KMEB02',
 VALUE='22UF',
 PRIM_FILE='./archive_libs/logical/q_cap/chips/chips.prt';

PART_NAME
 C2593 'Q_CAP_C0402-22UF,4V,20%,X6S,CH622KMEB02':;

SECTION_NUMBER 1
 '@T6G_MB_LIB.T6G(SCH_1):PAGE69_I74@PURE_QUANTA.Q_CAP(CHIPS)':
 C_PATH='@t6g_mb_lib.t6g(sch_1):page69_i74@pure_quanta.q_cap(chips)',
 P_PATH='@t6g_mb_lib.t6g(sch_1):page70_i74@pure_quanta.q_cap(chips)',
 PATH='I74',
 DRAWING='@T6G_MB_LIB.T6G(SCH_1):PAGE69',
 TOLERANCE='20%',
 MATERIAL='X6S',
 PHYS_PAGE='70',
 XY='(-5075,3725)',
 ROT='0',
 VER='1',
 PACK_TYPE='C0402',
 LOCATION='C2593',
 CDS_LIB='pure_quanta',
 CDS_PART_NAME='Q_CAP_C0402-22UF,4V,20%,X6S,CH622KMEB02',
 VOLTAGE='4V',
 PART_NUMBER='CH622KMEB02',
 VALUE='22UF',
 PRIM_FILE='./archive_libs/logical/q_cap/chips/chips.prt';

PART_NAME
 C2594 'Q_CAP_C0402-22UF,4V,20%,X6S,CH622KMEB02':;

SECTION_NUMBER 1
 '@T6G_MB_LIB.T6G(SCH_1):PAGE69_I69@PURE_QUANTA.Q_CAP(CHIPS)':
 C_PATH='@t6g_mb_lib.t6g(sch_1):page69_i69@pure_quanta.q_cap(chips)',
 P_PATH='@t6g_mb_lib.t6g(sch_1):page70_i69@pure_quanta.q_cap(chips)',
 PATH='I69',
 DRAWING='@T6G_MB_LIB.T6G(SCH_1):PAGE69',
 TOLERANCE='20%',
 MATERIAL='X6S',
 PHYS_PAGE='70',
 XY='(-5075,3000)',
 ROT='0',
 VER='1',
 PACK_TYPE='C0402',
 LOCATION='C2594',
 CDS_LIB='pure_quanta',
 CDS_PART_NAME='Q_CAP_C0402-22UF,4V,20%,X6S,CH622KMEB02',
 VOLTAGE='4V',
 PART_NUMBER='CH622KMEB02',
 VALUE='22UF',
 PRIM_FILE='./archive_libs/logical/q_cap/chips/chips.prt';

PART_NAME
 C2595 'Q_CAP_C0402-22UF,4V,20%,X6S,CH622KMEB02':;

SECTION_NUMBER 1
 '@T6G_MB_LIB.T6G(SCH_1):PAGE69_I67@PURE_QUANTA.Q_CAP(CHIPS)':
 C_PATH='@t6g_mb_lib.t6g(sch_1):page69_i67@pure_quanta.q_cap(chips)',
 P_PATH='@t6g_mb_lib.t6g(sch_1):page70_i67@pure_quanta.q_cap(chips)',
 PATH='I67',
 DRAWING='@T6G_MB_LIB.T6G(SCH_1):PAGE69',
 TOLERANCE='20%',
 MATERIAL='X6S',
 PHYS_PAGE='70',
 XY='(-5075,2300)',
 ROT='0',
 VER='1',
 PACK_TYPE='C0402',
 LOCATION='C2595',
 CDS_LIB='pure_quanta',
 CDS_PART_NAME='Q_CAP_C0402-22UF,4V,20%,X6S,CH622KMEB02',
 VOLTAGE='4V',
 PART_NUMBER='CH622KMEB02',
 VALUE='22UF',
 PRIM_FILE='./archive_libs/logical/q_cap/chips/chips.prt';

PART_NAME
 C2596 'Q_CAP_C0402-22UF,4V,20%,X6S,CH622KMEB02':;

SECTION_NUMBER 1
 '@T6G_MB_LIB.T6G(SCH_1):PAGE69_I56@PURE_QUANTA.Q_CAP(CHIPS)':
 C_PATH='@t6g_mb_lib.t6g(sch_1):page69_i56@pure_quanta.q_cap(chips)',
 P_PATH='@t6g_mb_lib.t6g(sch_1):page70_i56@pure_quanta.q_cap(chips)',
 PATH='I56',
 DRAWING='@T6G_MB_LIB.T6G(SCH_1):PAGE69',
 TOLERANCE='20%',
 MATERIAL='X6S',
 PHYS_PAGE='70',
 XY='(-5075,1575)',
 ROT='0',
 VER='1',
 PACK_TYPE='C0402',
 LOCATION='C2596',
 CDS_LIB='pure_quanta',
 CDS_PART_NAME='Q_CAP_C0402-22UF,4V,20%,X6S,CH622KMEB02',
 VOLTAGE='4V',
 PART_NUMBER='CH622KMEB02',
 VALUE='22UF',
 PRIM_FILE='./archive_libs/logical/q_cap/chips/chips.prt';

PART_NAME
 C2597 'Q_CAP_C0402-22UF,4V,20%,X6S,CH622KMEB02':;

SECTION_NUMBER 1
 '@T6G_MB_LIB.T6G(SCH_1):PAGE69_I108@PURE_QUANTA.Q_CAP(CHIPS)':
 C_PATH='@t6g_mb_lib.t6g(sch_1):page69_i108@pure_quanta.q_cap(chips)',
 P_PATH='@t6g_mb_lib.t6g(sch_1):page70_i108@pure_quanta.q_cap(chips)',
 PATH='I108',
 DRAWING='@T6G_MB_LIB.T6G(SCH_1):PAGE69',
 TOLERANCE='20%',
 MATERIAL='X6S',
 PHYS_PAGE='70',
 XY='(-4525,5900)',
 ROT='0',
 VER='1',
 PACK_TYPE='C0402',
 LOCATION='C2597',
 CDS_LIB='pure_quanta',
 CDS_PART_NAME='Q_CAP_C0402-22UF,4V,20%,X6S,CH622KMEB02',
 VOLTAGE='4V',
 PART_NUMBER='CH622KMEB02',
 VALUE='22UF',
 PRIM_FILE='./archive_libs/logical/q_cap/chips/chips.prt';

PART_NAME
 C2598 'Q_CAP_C0402-22UF,4V,20%,X6S,CH622KMEB02':;

SECTION_NUMBER 1
 '@T6G_MB_LIB.T6G(SCH_1):PAGE69_I104@PURE_QUANTA.Q_CAP(CHIPS)':
 C_PATH='@t6g_mb_lib.t6g(sch_1):page69_i104@pure_quanta.q_cap(chips)',
 P_PATH='@t6g_mb_lib.t6g(sch_1):page70_i104@pure_quanta.q_cap(chips)',
 PATH='I104',
 DRAWING='@T6G_MB_LIB.T6G(SCH_1):PAGE69',
 TOLERANCE='20%',
 MATERIAL='X6S',
 PHYS_PAGE='70',
 XY='(-4525,5100)',
 ROT='0',
 VER='1',
 PACK_TYPE='C0402',
 LOCATION='C2598',
 CDS_LIB='pure_quanta',
 CDS_PART_NAME='Q_CAP_C0402-22UF,4V,20%,X6S,CH622KMEB02',
 VOLTAGE='4V',
 PART_NUMBER='CH622KMEB02',
 VALUE='22UF',
 PRIM_FILE='./archive_libs/logical/q_cap/chips/chips.prt';

PART_NAME
 C2599 'Q_CAP_C0402-22UF,4V,20%,X6S,CH622KMEB02':;

SECTION_NUMBER 1
 '@T6G_MB_LIB.T6G(SCH_1):PAGE69_I102@PURE_QUANTA.Q_CAP(CHIPS)':
 C_PATH='@t6g_mb_lib.t6g(sch_1):page69_i102@pure_quanta.q_cap(chips)',
 P_PATH='@t6g_mb_lib.t6g(sch_1):page70_i102@pure_quanta.q_cap(chips)',
 PATH='I102',
 DRAWING='@T6G_MB_LIB.T6G(SCH_1):PAGE69',
 TOLERANCE='20%',
 MATERIAL='X6S',
 PHYS_PAGE='70',
 XY='(-4500,4325)',
 ROT='0',
 VER='1',
 PACK_TYPE='C0402',
 LOCATION='C2599',
 CDS_LIB='pure_quanta',
 CDS_PART_NAME='Q_CAP_C0402-22UF,4V,20%,X6S,CH622KMEB02',
 VOLTAGE='4V',
 PART_NUMBER='CH622KMEB02',
 VALUE='22UF',
 PRIM_FILE='./archive_libs/logical/q_cap/chips/chips.prt';

PART_NAME
 C2600 'Q_CAP_C0402-22UF,4V,20%,X6S,CH622KMEB02':;

SECTION_NUMBER 1
 '@T6G_MB_LIB.T6G(SCH_1):PAGE69_I76@PURE_QUANTA.Q_CAP(CHIPS)':
 C_PATH='@t6g_mb_lib.t6g(sch_1):page69_i76@pure_quanta.q_cap(chips)',
 P_PATH='@t6g_mb_lib.t6g(sch_1):page70_i76@pure_quanta.q_cap(chips)',
 PATH='I76',
 DRAWING='@T6G_MB_LIB.T6G(SCH_1):PAGE69',
 TOLERANCE='20%',
 MATERIAL='X6S',
 PHYS_PAGE='70',
 XY='(-4500,3275)',
 ROT='0',
 VER='1',
 PACK_TYPE='C0402',
 LOCATION='C2600',
 CDS_LIB='pure_quanta',
 CDS_PART_NAME='Q_CAP_C0402-22UF,4V,20%,X6S,CH622KMEB02',
 VOLTAGE='4V',
 PART_NUMBER='CH622KMEB02',
 VALUE='22UF',
 PRIM_FILE='./archive_libs/logical/q_cap/chips/chips.prt';

PART_NAME
 C2601 'Q_CAP_C0402-22UF,4V,20%,X6S,CH622KMEB02':;

SECTION_NUMBER 1
 '@T6G_MB_LIB.T6G(SCH_1):PAGE69_I71@PURE_QUANTA.Q_CAP(CHIPS)':
 C_PATH='@t6g_mb_lib.t6g(sch_1):page69_i71@pure_quanta.q_cap(chips)',
 P_PATH='@t6g_mb_lib.t6g(sch_1):page70_i71@pure_quanta.q_cap(chips)',
 PATH='I71',
 DRAWING='@T6G_MB_LIB.T6G(SCH_1):PAGE69',
 TOLERANCE='20%',
 MATERIAL='X6S',
 PHYS_PAGE='70',
 XY='(-4500,2625)',
 ROT='0',
 VER='1',
 PACK_TYPE='C0402',
 LOCATION='C2601',
 CDS_LIB='pure_quanta',
 CDS_PART_NAME='Q_CAP_C0402-22UF,4V,20%,X6S,CH622KMEB02',
 VOLTAGE='4V',
 PART_NUMBER='CH622KMEB02',
 VALUE='22UF',
 PRIM_FILE='./archive_libs/logical/q_cap/chips/chips.prt';

PART_NAME
 C2602 'Q_CAP_C0402-22UF,4V,20%,X6S,CH622KMEB02':;

SECTION_NUMBER 1
 '@T6G_MB_LIB.T6G(SCH_1):PAGE69_I60@PURE_QUANTA.Q_CAP(CHIPS)':
 C_PATH='@t6g_mb_lib.t6g(sch_1):page69_i60@pure_quanta.q_cap(chips)',
 P_PATH='@t6g_mb_lib.t6g(sch_1):page70_i60@pure_quanta.q_cap(chips)',
 PATH='I60',
 DRAWING='@T6G_MB_LIB.T6G(SCH_1):PAGE69',
 TOLERANCE='20%',
 MATERIAL='X6S',
 PHYS_PAGE='70',
 XY='(-4500,2000)',
 ROT='0',
 VER='1',
 PACK_TYPE='C0402',
 LOCATION='C2602',
 CDS_LIB='pure_quanta',
 CDS_PART_NAME='Q_CAP_C0402-22UF,4V,20%,X6S,CH622KMEB02',
 VOLTAGE='4V',
 PART_NUMBER='CH622KMEB02',
 VALUE='22UF',
 PRIM_FILE='./archive_libs/logical/q_cap/chips/chips.prt';

PART_NAME
 C2603 'Q_CAP_C0402-22UF,4V,20%,X6S,CH622KMEB02':;

SECTION_NUMBER 1
 '@T6G_MB_LIB.T6G(SCH_1):PAGE69_I58@PURE_QUANTA.Q_CAP(CHIPS)':
 C_PATH='@t6g_mb_lib.t6g(sch_1):page69_i58@pure_quanta.q_cap(chips)',
 P_PATH='@t6g_mb_lib.t6g(sch_1):page70_i58@pure_quanta.q_cap(chips)',
 PATH='I58',
 DRAWING='@T6G_MB_LIB.T6G(SCH_1):PAGE69',
 TOLERANCE='20%',
 MATERIAL='X6S',
 PHYS_PAGE='70',
 XY='(-4500,1400)',
 ROT='0',
 VER='1',
 PACK_TYPE='C0402',
 LOCATION='C2603',
 CDS_LIB='pure_quanta',
 CDS_PART_NAME='Q_CAP_C0402-22UF,4V,20%,X6S,CH622KMEB02',
 VOLTAGE='4V',
 PART_NUMBER='CH622KMEB02',
 VALUE='22UF',
 PRIM_FILE='./archive_libs/logical/q_cap/chips/chips.prt';

PART_NAME
 C2604 'Q_CAP_C0402-22UF,4V,20%,X6S,CH622KMEB02':;

SECTION_NUMBER 1
 '@T6G_MB_LIB.T6G(SCH_1):PAGE69_I158@PURE_QUANTA.Q_CAP(CHIPS)':
 C_PATH='@t6g_mb_lib.t6g(sch_1):page69_i158@pure_quanta.q_cap(chips)',
 P_PATH='@t6g_mb_lib.t6g(sch_1):page70_i158@pure_quanta.q_cap(chips)',
 PATH='I158',
 DRAWING='@T6G_MB_LIB.T6G(SCH_1):PAGE69',
 TOLERANCE='20%',
 MATERIAL='X6S',
 PHYS_PAGE='70',
 XY='(-4075,5900)',
 ROT='0',
 VER='1',
 PACK_TYPE='C0402',
 LOCATION='C2604',
 CDS_LIB='pure_quanta',
 CDS_PART_NAME='Q_CAP_C0402-22UF,4V,20%,X6S,CH622KMEB02',
 VOLTAGE='4V',
 PART_NUMBER='CH622KMEB02',
 VALUE='22UF',
 PRIM_FILE='./archive_libs/logical/q_cap/chips/chips.prt';

PART_NAME
 C2605 'Q_CAP_C0402-22UF,4V,20%,X6S,CH622KMEB02':;

SECTION_NUMBER 1
 '@T6G_MB_LIB.T6G(SCH_1):PAGE69_I154@PURE_QUANTA.Q_CAP(CHIPS)':
 C_PATH='@t6g_mb_lib.t6g(sch_1):page69_i154@pure_quanta.q_cap(chips)',
 P_PATH='@t6g_mb_lib.t6g(sch_1):page70_i154@pure_quanta.q_cap(chips)',
 PATH='I154',
 DRAWING='@T6G_MB_LIB.T6G(SCH_1):PAGE69',
 TOLERANCE='20%',
 MATERIAL='X6S',
 PHYS_PAGE='70',
 XY='(-4075,5100)',
 ROT='0',
 VER='1',
 PACK_TYPE='C0402',
 LOCATION='C2605',
 CDS_LIB='pure_quanta',
 CDS_PART_NAME='Q_CAP_C0402-22UF,4V,20%,X6S,CH622KMEB02',
 VOLTAGE='4V',
 PART_NUMBER='CH622KMEB02',
 VALUE='22UF',
 PRIM_FILE='./archive_libs/logical/q_cap/chips/chips.prt';

PART_NAME
 C2606 'Q_CAP_C0402-22UF,4V,20%,X6S,CH622KMEB02':;

SECTION_NUMBER 1
 '@T6G_MB_LIB.T6G(SCH_1):PAGE69_I153@PURE_QUANTA.Q_CAP(CHIPS)':
 C_PATH='@t6g_mb_lib.t6g(sch_1):page69_i153@pure_quanta.q_cap(chips)',
 P_PATH='@t6g_mb_lib.t6g(sch_1):page70_i153@pure_quanta.q_cap(chips)',
 PATH='I153',
 DRAWING='@T6G_MB_LIB.T6G(SCH_1):PAGE69',
 TOLERANCE='20%',
 MATERIAL='X6S',
 PHYS_PAGE='70',
 XY='(-4050,4325)',
 ROT='0',
 VER='1',
 PACK_TYPE='C0402',
 LOCATION='C2606',
 CDS_LIB='pure_quanta',
 CDS_PART_NAME='Q_CAP_C0402-22UF,4V,20%,X6S,CH622KMEB02',
 VOLTAGE='4V',
 PART_NUMBER='CH622KMEB02',
 VALUE='22UF',
 PRIM_FILE='./archive_libs/logical/q_cap/chips/chips.prt';

PART_NAME
 C2607 'Q_CAP_C0402-22UF,4V,20%,X6S,CH622KMEB02':;

SECTION_NUMBER 1
 '@T6G_MB_LIB.T6G(SCH_1):PAGE69_I124@PURE_QUANTA.Q_CAP(CHIPS)':
 C_PATH='@t6g_mb_lib.t6g(sch_1):page69_i124@pure_quanta.q_cap(chips)',
 P_PATH='@t6g_mb_lib.t6g(sch_1):page70_i124@pure_quanta.q_cap(chips)',
 PATH='I124',
 DRAWING='@T6G_MB_LIB.T6G(SCH_1):PAGE69',
 TOLERANCE='20%',
 MATERIAL='X6S',
 PHYS_PAGE='70',
 XY='(-4050,3275)',
 ROT='0',
 VER='1',
 PACK_TYPE='C0402',
 LOCATION='C2607',
 CDS_LIB='pure_quanta',
 CDS_PART_NAME='Q_CAP_C0402-22UF,4V,20%,X6S,CH622KMEB02',
 VOLTAGE='4V',
 PART_NUMBER='CH622KMEB02',
 VALUE='22UF',
 PRIM_FILE='./archive_libs/logical/q_cap/chips/chips.prt';

PART_NAME
 C2608 'Q_CAP_C0402-22UF,4V,20%,X6S,CH622KMEB02':;

SECTION_NUMBER 1
 '@T6G_MB_LIB.T6G(SCH_1):PAGE69_I122@PURE_QUANTA.Q_CAP(CHIPS)':
 C_PATH='@t6g_mb_lib.t6g(sch_1):page69_i122@pure_quanta.q_cap(chips)',
 P_PATH='@t6g_mb_lib.t6g(sch_1):page70_i122@pure_quanta.q_cap(chips)',
 PATH='I122',
 DRAWING='@T6G_MB_LIB.T6G(SCH_1):PAGE69',
 TOLERANCE='20%',
 MATERIAL='X6S',
 PHYS_PAGE='70',
 XY='(-4050,2625)',
 ROT='0',
 VER='1',
 PACK_TYPE='C0402',
 LOCATION='C2608',
 CDS_LIB='pure_quanta',
 CDS_PART_NAME='Q_CAP_C0402-22UF,4V,20%,X6S,CH622KMEB02',
 VOLTAGE='4V',
 PART_NUMBER='CH622KMEB02',
 VALUE='22UF',
 PRIM_FILE='./archive_libs/logical/q_cap/chips/chips.prt';

PART_NAME
 C2609 'Q_CAP_C0402-22UF,4V,20%,X6S,CH622KMEB02':;

SECTION_NUMBER 1
 '@T6G_MB_LIB.T6G(SCH_1):PAGE69_I113@PURE_QUANTA.Q_CAP(CHIPS)':
 C_PATH='@t6g_mb_lib.t6g(sch_1):page69_i113@pure_quanta.q_cap(chips)',
 P_PATH='@t6g_mb_lib.t6g(sch_1):page70_i113@pure_quanta.q_cap(chips)',
 PATH='I113',
 DRAWING='@T6G_MB_LIB.T6G(SCH_1):PAGE69',
 TOLERANCE='20%',
 MATERIAL='X6S',
 PHYS_PAGE='70',
 XY='(-4050,2000)',
 ROT='0',
 VER='1',
 PACK_TYPE='C0402',
 LOCATION='C2609',
 CDS_LIB='pure_quanta',
 CDS_PART_NAME='Q_CAP_C0402-22UF,4V,20%,X6S,CH622KMEB02',
 VOLTAGE='4V',
 PART_NUMBER='CH622KMEB02',
 VALUE='22UF',
 PRIM_FILE='./archive_libs/logical/q_cap/chips/chips.prt';

PART_NAME
 C2610 'Q_CAP_C0402-22UF,4V,20%,X6S,CH622KMEB02':;

SECTION_NUMBER 1
 '@T6G_MB_LIB.T6G(SCH_1):PAGE69_I112@PURE_QUANTA.Q_CAP(CHIPS)':
 C_PATH='@t6g_mb_lib.t6g(sch_1):page69_i112@pure_quanta.q_cap(chips)',
 P_PATH='@t6g_mb_lib.t6g(sch_1):page70_i112@pure_quanta.q_cap(chips)',
 PATH='I112',
 DRAWING='@T6G_MB_LIB.T6G(SCH_1):PAGE69',
 TOLERANCE='20%',
 MATERIAL='X6S',
 PHYS_PAGE='70',
 XY='(-4050,1400)',
 ROT='0',
 VER='1',
 PACK_TYPE='C0402',
 LOCATION='C2610',
 CDS_LIB='pure_quanta',
 CDS_PART_NAME='Q_CAP_C0402-22UF,4V,20%,X6S,CH622KMEB02',
 VOLTAGE='4V',
 PART_NUMBER='CH622KMEB02',
 VALUE='22UF',
 PRIM_FILE='./archive_libs/logical/q_cap/chips/chips.prt';

PART_NAME
 C2611 'Q_CAP_C0402-22UF,4V,20%,X6S,CH622KMEB02':;

SECTION_NUMBER 1
 '@T6G_MB_LIB.T6G(SCH_1):PAGE69_I159@PURE_QUANTA.Q_CAP(CHIPS)':
 C_PATH='@t6g_mb_lib.t6g(sch_1):page69_i159@pure_quanta.q_cap(chips)',
 P_PATH='@t6g_mb_lib.t6g(sch_1):page70_i159@pure_quanta.q_cap(chips)',
 PATH='I159',
 DRAWING='@T6G_MB_LIB.T6G(SCH_1):PAGE69',
 TOLERANCE='20%',
 MATERIAL='X6S',
 PHYS_PAGE='70',
 XY='(-3625,5900)',
 ROT='0',
 VER='1',
 PACK_TYPE='C0402',
 LOCATION='C2611',
 CDS_LIB='pure_quanta',
 CDS_PART_NAME='Q_CAP_C0402-22UF,4V,20%,X6S,CH622KMEB02',
 VOLTAGE='4V',
 PART_NUMBER='CH622KMEB02',
 VALUE='22UF',
 PRIM_FILE='./archive_libs/logical/q_cap/chips/chips.prt';

PART_NAME
 C2612 'Q_CAP_C0402-22UF,4V,20%,X6S,CH622KMEB02':;

SECTION_NUMBER 1
 '@T6G_MB_LIB.T6G(SCH_1):PAGE69_I156@PURE_QUANTA.Q_CAP(CHIPS)':
 C_PATH='@t6g_mb_lib.t6g(sch_1):page69_i156@pure_quanta.q_cap(chips)',
 P_PATH='@t6g_mb_lib.t6g(sch_1):page70_i156@pure_quanta.q_cap(chips)',
 PATH='I156',
 DRAWING='@T6G_MB_LIB.T6G(SCH_1):PAGE69',
 TOLERANCE='20%',
 MATERIAL='X6S',
 PHYS_PAGE='70',
 XY='(-3625,5100)',
 ROT='0',
 VER='1',
 PACK_TYPE='C0402',
 LOCATION='C2612',
 CDS_LIB='pure_quanta',
 CDS_PART_NAME='Q_CAP_C0402-22UF,4V,20%,X6S,CH622KMEB02',
 VOLTAGE='4V',
 PART_NUMBER='CH622KMEB02',
 VALUE='22UF',
 PRIM_FILE='./archive_libs/logical/q_cap/chips/chips.prt';

PART_NAME
 C2613 'Q_CAP_C0402-22UF,4V,20%,X6S,CH622KMEB02':;

SECTION_NUMBER 1
 '@T6G_MB_LIB.T6G(SCH_1):PAGE69_I155@PURE_QUANTA.Q_CAP(CHIPS)':
 C_PATH='@t6g_mb_lib.t6g(sch_1):page69_i155@pure_quanta.q_cap(chips)',
 P_PATH='@t6g_mb_lib.t6g(sch_1):page70_i155@pure_quanta.q_cap(chips)',
 PATH='I155',
 DRAWING='@T6G_MB_LIB.T6G(SCH_1):PAGE69',
 TOLERANCE='20%',
 MATERIAL='X6S',
 PHYS_PAGE='70',
 XY='(-3600,4325)',
 ROT='0',
 VER='1',
 PACK_TYPE='C0402',
 LOCATION='C2613',
 CDS_LIB='pure_quanta',
 CDS_PART_NAME='Q_CAP_C0402-22UF,4V,20%,X6S,CH622KMEB02',
 VOLTAGE='4V',
 PART_NUMBER='CH622KMEB02',
 VALUE='22UF',
 PRIM_FILE='./archive_libs/logical/q_cap/chips/chips.prt';

PART_NAME
 C2614 'Q_CAP_C0402-22UF,4V,20%,X6S,CH622KMEB02':;

SECTION_NUMBER 1
 '@T6G_MB_LIB.T6G(SCH_1):PAGE69_I125@PURE_QUANTA.Q_CAP(CHIPS)':
 C_PATH='@t6g_mb_lib.t6g(sch_1):page69_i125@pure_quanta.q_cap(chips)',
 P_PATH='@t6g_mb_lib.t6g(sch_1):page70_i125@pure_quanta.q_cap(chips)',
 PATH='I125',
 DRAWING='@T6G_MB_LIB.T6G(SCH_1):PAGE69',
 TOLERANCE='20%',
 MATERIAL='X6S',
 PHYS_PAGE='70',
 XY='(-3600,3275)',
 ROT='0',
 VER='1',
 PACK_TYPE='C0402',
 LOCATION='C2614',
 CDS_LIB='pure_quanta',
 CDS_PART_NAME='Q_CAP_C0402-22UF,4V,20%,X6S,CH622KMEB02',
 VOLTAGE='4V',
 PART_NUMBER='CH622KMEB02',
 VALUE='22UF',
 PRIM_FILE='./archive_libs/logical/q_cap/chips/chips.prt';

PART_NAME
 C2615 'Q_CAP_C0402-22UF,4V,20%,X6S,CH622KMEB02':;

SECTION_NUMBER 1
 '@T6G_MB_LIB.T6G(SCH_1):PAGE69_I123@PURE_QUANTA.Q_CAP(CHIPS)':
 C_PATH='@t6g_mb_lib.t6g(sch_1):page69_i123@pure_quanta.q_cap(chips)',
 P_PATH='@t6g_mb_lib.t6g(sch_1):page70_i123@pure_quanta.q_cap(chips)',
 PATH='I123',
 DRAWING='@T6G_MB_LIB.T6G(SCH_1):PAGE69',
 TOLERANCE='20%',
 MATERIAL='X6S',
 PHYS_PAGE='70',
 XY='(-3600,2625)',
 ROT='0',
 VER='1',
 PACK_TYPE='C0402',
 LOCATION='C2615',
 CDS_LIB='pure_quanta',
 CDS_PART_NAME='Q_CAP_C0402-22UF,4V,20%,X6S,CH622KMEB02',
 VOLTAGE='4V',
 PART_NUMBER='CH622KMEB02',
 VALUE='22UF',
 PRIM_FILE='./archive_libs/logical/q_cap/chips/chips.prt';

PART_NAME
 C2616 'Q_CAP_C0402-22UF,4V,20%,X6S,CH622KMEB02':;

SECTION_NUMBER 1
 '@T6G_MB_LIB.T6G(SCH_1):PAGE69_I115@PURE_QUANTA.Q_CAP(CHIPS)':
 C_PATH='@t6g_mb_lib.t6g(sch_1):page69_i115@pure_quanta.q_cap(chips)',
 P_PATH='@t6g_mb_lib.t6g(sch_1):page70_i115@pure_quanta.q_cap(chips)',
 PATH='I115',
 DRAWING='@T6G_MB_LIB.T6G(SCH_1):PAGE69',
 TOLERANCE='20%',
 MATERIAL='X6S',
 PHYS_PAGE='70',
 XY='(-3600,2000)',
 ROT='0',
 VER='1',
 PACK_TYPE='C0402',
 LOCATION='C2616',
 CDS_LIB='pure_quanta',
 CDS_PART_NAME='Q_CAP_C0402-22UF,4V,20%,X6S,CH622KMEB02',
 VOLTAGE='4V',
 PART_NUMBER='CH622KMEB02',
 VALUE='22UF',
 PRIM_FILE='./archive_libs/logical/q_cap/chips/chips.prt';

PART_NAME
 C2617 'Q_CAP_C0402-22UF,4V,20%,X6S,CH622KMEB02':;

SECTION_NUMBER 1
 '@T6G_MB_LIB.T6G(SCH_1):PAGE69_I114@PURE_QUANTA.Q_CAP(CHIPS)':
 C_PATH='@t6g_mb_lib.t6g(sch_1):page69_i114@pure_quanta.q_cap(chips)',
 P_PATH='@t6g_mb_lib.t6g(sch_1):page70_i114@pure_quanta.q_cap(chips)',
 PATH='I114',
 DRAWING='@T6G_MB_LIB.T6G(SCH_1):PAGE69',
 TOLERANCE='20%',
 MATERIAL='X6S',
 PHYS_PAGE='70',
 XY='(-3600,1400)',
 ROT='0',
 VER='1',
 PACK_TYPE='C0402',
 LOCATION='C2617',
 CDS_LIB='pure_quanta',
 CDS_PART_NAME='Q_CAP_C0402-22UF,4V,20%,X6S,CH622KMEB02',
 VOLTAGE='4V',
 PART_NUMBER='CH622KMEB02',
 VALUE='22UF',
 PRIM_FILE='./archive_libs/logical/q_cap/chips/chips.prt';

PART_NAME
 C2618 'Q_CAP_C0402-22UF,4V,20%,X6S,CH622KMEB02':;

SECTION_NUMBER 1
 '@T6G_MB_LIB.T6G(SCH_1):PAGE69_I160@PURE_QUANTA.Q_CAP(CHIPS)':
 C_PATH='@t6g_mb_lib.t6g(sch_1):page69_i160@pure_quanta.q_cap(chips)',
 P_PATH='@t6g_mb_lib.t6g(sch_1):page70_i160@pure_quanta.q_cap(chips)',
 PATH='I160',
 DRAWING='@T6G_MB_LIB.T6G(SCH_1):PAGE69',
 TOLERANCE='20%',
 MATERIAL='X6S',
 PHYS_PAGE='70',
 XY='(-3175,5900)',
 ROT='0',
 VER='1',
 PACK_TYPE='C0402',
 LOCATION='C2618',
 CDS_LIB='pure_quanta',
 CDS_PART_NAME='Q_CAP_C0402-22UF,4V,20%,X6S,CH622KMEB02',
 VOLTAGE='4V',
 PART_NUMBER='CH622KMEB02',
 VALUE='22UF',
 PRIM_FILE='./archive_libs/logical/q_cap/chips/chips.prt';

PART_NAME
 C2619 'Q_CAP_C0402-22UF,4V,20%,X6S,CH622KMEB02':;

SECTION_NUMBER 1
 '@T6G_MB_LIB.T6G(SCH_1):PAGE69_I157@PURE_QUANTA.Q_CAP(CHIPS)':
 C_PATH='@t6g_mb_lib.t6g(sch_1):page69_i157@pure_quanta.q_cap(chips)',
 P_PATH='@t6g_mb_lib.t6g(sch_1):page70_i157@pure_quanta.q_cap(chips)',
 PATH='I157',
 DRAWING='@T6G_MB_LIB.T6G(SCH_1):PAGE69',
 TOLERANCE='20%',
 MATERIAL='X6S',
 PHYS_PAGE='70',
 XY='(-3175,5100)',
 ROT='0',
 VER='1',
 PACK_TYPE='C0402',
 LOCATION='C2619',
 CDS_LIB='pure_quanta',
 CDS_PART_NAME='Q_CAP_C0402-22UF,4V,20%,X6S,CH622KMEB02',
 VOLTAGE='4V',
 PART_NUMBER='CH622KMEB02',
 VALUE='22UF',
 PRIM_FILE='./archive_libs/logical/q_cap/chips/chips.prt';

PART_NAME
 C2620 'Q_CAP_C0402-22UF,4V,20%,X6S,CH622KMEB02':;

SECTION_NUMBER 1
 '@T6G_MB_LIB.T6G(SCH_1):PAGE69_I161@PURE_QUANTA.Q_CAP(CHIPS)':
 C_PATH='@t6g_mb_lib.t6g(sch_1):page69_i161@pure_quanta.q_cap(chips)',
 P_PATH='@t6g_mb_lib.t6g(sch_1):page70_i161@pure_quanta.q_cap(chips)',
 PATH='I161',
 DRAWING='@T6G_MB_LIB.T6G(SCH_1):PAGE69',
 TOLERANCE='20%',
 MATERIAL='X6S',
 PHYS_PAGE='70',
 XY='(-3150,4325)',
 ROT='0',
 VER='1',
 PACK_TYPE='C0402',
 LOCATION='C2620',
 CDS_LIB='pure_quanta',
 CDS_PART_NAME='Q_CAP_C0402-22UF,4V,20%,X6S,CH622KMEB02',
 VOLTAGE='4V',
 PART_NUMBER='CH622KMEB02',
 VALUE='22UF',
 PRIM_FILE='./archive_libs/logical/q_cap/chips/chips.prt';

PART_NAME
 C2621 'Q_CAP_C0402-22UF,4V,20%,X6S,CH622KMEB02':;

SECTION_NUMBER 1
 '@T6G_MB_LIB.T6G(SCH_1):PAGE69_I127@PURE_QUANTA.Q_CAP(CHIPS)':
 C_PATH='@t6g_mb_lib.t6g(sch_1):page69_i127@pure_quanta.q_cap(chips)',
 P_PATH='@t6g_mb_lib.t6g(sch_1):page70_i127@pure_quanta.q_cap(chips)',
 PATH='I127',
 DRAWING='@T6G_MB_LIB.T6G(SCH_1):PAGE69',
 TOLERANCE='20%',
 MATERIAL='X6S',
 PHYS_PAGE='70',
 XY='(-3150,3275)',
 ROT='0',
 VER='1',
 PACK_TYPE='C0402',
 LOCATION='C2621',
 CDS_LIB='pure_quanta',
 CDS_PART_NAME='Q_CAP_C0402-22UF,4V,20%,X6S,CH622KMEB02',
 VOLTAGE='4V',
 PART_NUMBER='CH622KMEB02',
 VALUE='22UF',
 PRIM_FILE='./archive_libs/logical/q_cap/chips/chips.prt';

PART_NAME
 C2622 'Q_CAP_C0402-22UF,4V,20%,X6S,CH622KMEB02':;

SECTION_NUMBER 1
 '@T6G_MB_LIB.T6G(SCH_1):PAGE69_I126@PURE_QUANTA.Q_CAP(CHIPS)':
 C_PATH='@t6g_mb_lib.t6g(sch_1):page69_i126@pure_quanta.q_cap(chips)',
 P_PATH='@t6g_mb_lib.t6g(sch_1):page70_i126@pure_quanta.q_cap(chips)',
 PATH='I126',
 DRAWING='@T6G_MB_LIB.T6G(SCH_1):PAGE69',
 TOLERANCE='20%',
 MATERIAL='X6S',
 PHYS_PAGE='70',
 XY='(-3150,2625)',
 ROT='0',
 VER='1',
 PACK_TYPE='C0402',
 LOCATION='C2622',
 CDS_LIB='pure_quanta',
 CDS_PART_NAME='Q_CAP_C0402-22UF,4V,20%,X6S,CH622KMEB02',
 VOLTAGE='4V',
 PART_NUMBER='CH622KMEB02',
 VALUE='22UF',
 PRIM_FILE='./archive_libs/logical/q_cap/chips/chips.prt';

PART_NAME
 C2623 'Q_CAP_C0402-22UF,4V,20%,X6S,CH622KMEB02':;

SECTION_NUMBER 1
 '@T6G_MB_LIB.T6G(SCH_1):PAGE69_I117@PURE_QUANTA.Q_CAP(CHIPS)':
 C_PATH='@t6g_mb_lib.t6g(sch_1):page69_i117@pure_quanta.q_cap(chips)',
 P_PATH='@t6g_mb_lib.t6g(sch_1):page70_i117@pure_quanta.q_cap(chips)',
 PATH='I117',
 DRAWING='@T6G_MB_LIB.T6G(SCH_1):PAGE69',
 TOLERANCE='20%',
 MATERIAL='X6S',
 PHYS_PAGE='70',
 XY='(-3150,2000)',
 ROT='0',
 VER='1',
 PACK_TYPE='C0402',
 LOCATION='C2623',
 CDS_LIB='pure_quanta',
 CDS_PART_NAME='Q_CAP_C0402-22UF,4V,20%,X6S,CH622KMEB02',
 VOLTAGE='4V',
 PART_NUMBER='CH622KMEB02',
 VALUE='22UF',
 PRIM_FILE='./archive_libs/logical/q_cap/chips/chips.prt';

PART_NAME
 C2624 'Q_CAP_C0402-22UF,4V,20%,X6S,CH622KMEB02':;

SECTION_NUMBER 1
 '@T6G_MB_LIB.T6G(SCH_1):PAGE69_I116@PURE_QUANTA.Q_CAP(CHIPS)':
 C_PATH='@t6g_mb_lib.t6g(sch_1):page69_i116@pure_quanta.q_cap(chips)',
 P_PATH='@t6g_mb_lib.t6g(sch_1):page70_i116@pure_quanta.q_cap(chips)',
 PATH='I116',
 DRAWING='@T6G_MB_LIB.T6G(SCH_1):PAGE69',
 TOLERANCE='20%',
 MATERIAL='X6S',
 PHYS_PAGE='70',
 XY='(-3150,1400)',
 ROT='0',
 VER='1',
 PACK_TYPE='C0402',
 LOCATION='C2624',
 CDS_LIB='pure_quanta',
 CDS_PART_NAME='Q_CAP_C0402-22UF,4V,20%,X6S,CH622KMEB02',
 VOLTAGE='4V',
 PART_NUMBER='CH622KMEB02',
 VALUE='22UF',
 PRIM_FILE='./archive_libs/logical/q_cap/chips/chips.prt';

PART_NAME
 C2625 'Q_CAP_C0402-22UF,4V,20%,X6S,CH622KMEB02':;

SECTION_NUMBER 1
 '@T6G_MB_LIB.T6G(SCH_1):PAGE69_I164@PURE_QUANTA.Q_CAP(CHIPS)':
 C_PATH='@t6g_mb_lib.t6g(sch_1):page69_i164@pure_quanta.q_cap(chips)',
 P_PATH='@t6g_mb_lib.t6g(sch_1):page70_i164@pure_quanta.q_cap(chips)',
 PATH='I164',
 DRAWING='@T6G_MB_LIB.T6G(SCH_1):PAGE69',
 TOLERANCE='20%',
 MATERIAL='X6S',
 PHYS_PAGE='70',
 XY='(-2725,5900)',
 ROT='0',
 VER='1',
 PACK_TYPE='C0402',
 LOCATION='C2625',
 CDS_LIB='pure_quanta',
 CDS_PART_NAME='Q_CAP_C0402-22UF,4V,20%,X6S,CH622KMEB02',
 VOLTAGE='4V',
 PART_NUMBER='CH622KMEB02',
 VALUE='22UF',
 PRIM_FILE='./archive_libs/logical/q_cap/chips/chips.prt';

PART_NAME
 C2626 'Q_CAP_C0402-22UF,4V,20%,X6S,CH622KMEB02':;

SECTION_NUMBER 1
 '@T6G_MB_LIB.T6G(SCH_1):PAGE69_I162@PURE_QUANTA.Q_CAP(CHIPS)':
 C_PATH='@t6g_mb_lib.t6g(sch_1):page69_i162@pure_quanta.q_cap(chips)',
 P_PATH='@t6g_mb_lib.t6g(sch_1):page70_i162@pure_quanta.q_cap(chips)',
 PATH='I162',
 DRAWING='@T6G_MB_LIB.T6G(SCH_1):PAGE69',
 TOLERANCE='20%',
 MATERIAL='X6S',
 PHYS_PAGE='70',
 XY='(-2725,5100)',
 ROT='0',
 VER='1',
 PACK_TYPE='C0402',
 LOCATION='C2626',
 CDS_LIB='pure_quanta',
 CDS_PART_NAME='Q_CAP_C0402-22UF,4V,20%,X6S,CH622KMEB02',
 VOLTAGE='4V',
 PART_NUMBER='CH622KMEB02',
 VALUE='22UF',
 PRIM_FILE='./archive_libs/logical/q_cap/chips/chips.prt';

PART_NAME
 C2627 'Q_CAP_C0402-22UF,4V,20%,X6S,CH622KMEB02':;

SECTION_NUMBER 1
 '@T6G_MB_LIB.T6G(SCH_1):PAGE69_I131@PURE_QUANTA.Q_CAP(CHIPS)':
 C_PATH='@t6g_mb_lib.t6g(sch_1):page69_i131@pure_quanta.q_cap(chips)',
 P_PATH='@t6g_mb_lib.t6g(sch_1):page70_i131@pure_quanta.q_cap(chips)',
 PATH='I131',
 DRAWING='@T6G_MB_LIB.T6G(SCH_1):PAGE69',
 TOLERANCE='20%',
 MATERIAL='X6S',
 PHYS_PAGE='70',
 XY='(-2700,3275)',
 ROT='0',
 VER='1',
 PACK_TYPE='C0402',
 LOCATION='C2627',
 CDS_LIB='pure_quanta',
 CDS_PART_NAME='Q_CAP_C0402-22UF,4V,20%,X6S,CH622KMEB02',
 VOLTAGE='4V',
 PART_NUMBER='CH622KMEB02',
 VALUE='22UF',
 PRIM_FILE='./archive_libs/logical/q_cap/chips/chips.prt';

PART_NAME
 C2628 'Q_CAP_C0402-22UF,4V,20%,X6S,CH622KMEB02':;

SECTION_NUMBER 1
 '@T6G_MB_LIB.T6G(SCH_1):PAGE69_I129@PURE_QUANTA.Q_CAP(CHIPS)':
 C_PATH='@t6g_mb_lib.t6g(sch_1):page69_i129@pure_quanta.q_cap(chips)',
 P_PATH='@t6g_mb_lib.t6g(sch_1):page70_i129@pure_quanta.q_cap(chips)',
 PATH='I129',
 DRAWING='@T6G_MB_LIB.T6G(SCH_1):PAGE69',
 TOLERANCE='20%',
 MATERIAL='X6S',
 PHYS_PAGE='70',
 XY='(-2700,2625)',
 ROT='0',
 VER='1',
 PACK_TYPE='C0402',
 LOCATION='C2628',
 CDS_LIB='pure_quanta',
 CDS_PART_NAME='Q_CAP_C0402-22UF,4V,20%,X6S,CH622KMEB02',
 VOLTAGE='4V',
 PART_NUMBER='CH622KMEB02',
 VALUE='22UF',
 PRIM_FILE='./archive_libs/logical/q_cap/chips/chips.prt';

PART_NAME
 C2629 'Q_CAP_C0402-22UF,4V,20%,X6S,CH622KMEB02':;

SECTION_NUMBER 1
 '@T6G_MB_LIB.T6G(SCH_1):PAGE69_I119@PURE_QUANTA.Q_CAP(CHIPS)':
 C_PATH='@t6g_mb_lib.t6g(sch_1):page69_i119@pure_quanta.q_cap(chips)',
 P_PATH='@t6g_mb_lib.t6g(sch_1):page70_i119@pure_quanta.q_cap(chips)',
 PATH='I119',
 DRAWING='@T6G_MB_LIB.T6G(SCH_1):PAGE69',
 TOLERANCE='20%',
 MATERIAL='X6S',
 PHYS_PAGE='70',
 XY='(-2700,2000)',
 ROT='0',
 VER='1',
 PACK_TYPE='C0402',
 LOCATION='C2629',
 CDS_LIB='pure_quanta',
 CDS_PART_NAME='Q_CAP_C0402-22UF,4V,20%,X6S,CH622KMEB02',
 VOLTAGE='4V',
 PART_NUMBER='CH622KMEB02',
 VALUE='22UF',
 PRIM_FILE='./archive_libs/logical/q_cap/chips/chips.prt';

PART_NAME
 C2630 'Q_CAP_C0402-22UF,4V,20%,X6S,CH622KMEB02':;

SECTION_NUMBER 1
 '@T6G_MB_LIB.T6G(SCH_1):PAGE69_I118@PURE_QUANTA.Q_CAP(CHIPS)':
 C_PATH='@t6g_mb_lib.t6g(sch_1):page69_i118@pure_quanta.q_cap(chips)',
 P_PATH='@t6g_mb_lib.t6g(sch_1):page70_i118@pure_quanta.q_cap(chips)',
 PATH='I118',
 DRAWING='@T6G_MB_LIB.T6G(SCH_1):PAGE69',
 TOLERANCE='20%',
 MATERIAL='X6S',
 PHYS_PAGE='70',
 XY='(-2700,1400)',
 ROT='0',
 VER='1',
 PACK_TYPE='C0402',
 LOCATION='C2630',
 CDS_LIB='pure_quanta',
 CDS_PART_NAME='Q_CAP_C0402-22UF,4V,20%,X6S,CH622KMEB02',
 VOLTAGE='4V',
 PART_NUMBER='CH622KMEB02',
 VALUE='22UF',
 PRIM_FILE='./archive_libs/logical/q_cap/chips/chips.prt';

PART_NAME
 C2631 'Q_CAP_C0402-22UF,4V,20%,X6S,CH622KMEB02':;

SECTION_NUMBER 1
 '@T6G_MB_LIB.T6G(SCH_1):PAGE69_I165@PURE_QUANTA.Q_CAP(CHIPS)':
 C_PATH='@t6g_mb_lib.t6g(sch_1):page69_i165@pure_quanta.q_cap(chips)',
 P_PATH='@t6g_mb_lib.t6g(sch_1):page70_i165@pure_quanta.q_cap(chips)',
 PATH='I165',
 DRAWING='@T6G_MB_LIB.T6G(SCH_1):PAGE69',
 TOLERANCE='20%',
 MATERIAL='X6S',
 PHYS_PAGE='70',
 XY='(-2275,5900)',
 ROT='0',
 VER='1',
 PACK_TYPE='C0402',
 LOCATION='C2631',
 CDS_LIB='pure_quanta',
 CDS_PART_NAME='Q_CAP_C0402-22UF,4V,20%,X6S,CH622KMEB02',
 VOLTAGE='4V',
 PART_NUMBER='CH622KMEB02',
 VALUE='22UF',
 PRIM_FILE='./archive_libs/logical/q_cap/chips/chips.prt';

PART_NAME
 C2632 'Q_CAP_C0402-22UF,4V,20%,X6S,CH622KMEB02':;

SECTION_NUMBER 1
 '@T6G_MB_LIB.T6G(SCH_1):PAGE69_I163@PURE_QUANTA.Q_CAP(CHIPS)':
 C_PATH='@t6g_mb_lib.t6g(sch_1):page69_i163@pure_quanta.q_cap(chips)',
 P_PATH='@t6g_mb_lib.t6g(sch_1):page70_i163@pure_quanta.q_cap(chips)',
 PATH='I163',
 DRAWING='@T6G_MB_LIB.T6G(SCH_1):PAGE69',
 TOLERANCE='20%',
 MATERIAL='X6S',
 PHYS_PAGE='70',
 XY='(-2275,5100)',
 ROT='0',
 VER='1',
 PACK_TYPE='C0402',
 LOCATION='C2632',
 CDS_LIB='pure_quanta',
 CDS_PART_NAME='Q_CAP_C0402-22UF,4V,20%,X6S,CH622KMEB02',
 VOLTAGE='4V',
 PART_NUMBER='CH622KMEB02',
 VALUE='22UF',
 PRIM_FILE='./archive_libs/logical/q_cap/chips/chips.prt';

PART_NAME
 C2633 'Q_CAP_C0402-22UF,4V,20%,X6S,CH622KMEB02':;

SECTION_NUMBER 1
 '@T6G_MB_LIB.T6G(SCH_1):PAGE69_I132@PURE_QUANTA.Q_CAP(CHIPS)':
 C_PATH='@t6g_mb_lib.t6g(sch_1):page69_i132@pure_quanta.q_cap(chips)',
 P_PATH='@t6g_mb_lib.t6g(sch_1):page70_i132@pure_quanta.q_cap(chips)',
 PATH='I132',
 DRAWING='@T6G_MB_LIB.T6G(SCH_1):PAGE69',
 TOLERANCE='20%',
 MATERIAL='X6S',
 PHYS_PAGE='70',
 XY='(-2250,3275)',
 ROT='0',
 VER='1',
 PACK_TYPE='C0402',
 LOCATION='C2633',
 CDS_LIB='pure_quanta',
 CDS_PART_NAME='Q_CAP_C0402-22UF,4V,20%,X6S,CH622KMEB02',
 VOLTAGE='4V',
 PART_NUMBER='CH622KMEB02',
 VALUE='22UF',
 PRIM_FILE='./archive_libs/logical/q_cap/chips/chips.prt';

PART_NAME
 C2634 'Q_CAP_C0402-22UF,4V,20%,X6S,CH622KMEB02':;

SECTION_NUMBER 1
 '@T6G_MB_LIB.T6G(SCH_1):PAGE69_I130@PURE_QUANTA.Q_CAP(CHIPS)':
 C_PATH='@t6g_mb_lib.t6g(sch_1):page69_i130@pure_quanta.q_cap(chips)',
 P_PATH='@t6g_mb_lib.t6g(sch_1):page70_i130@pure_quanta.q_cap(chips)',
 PATH='I130',
 DRAWING='@T6G_MB_LIB.T6G(SCH_1):PAGE69',
 TOLERANCE='20%',
 MATERIAL='X6S',
 PHYS_PAGE='70',
 XY='(-2250,2625)',
 ROT='0',
 VER='1',
 PACK_TYPE='C0402',
 LOCATION='C2634',
 CDS_LIB='pure_quanta',
 CDS_PART_NAME='Q_CAP_C0402-22UF,4V,20%,X6S,CH622KMEB02',
 VOLTAGE='4V',
 PART_NUMBER='CH622KMEB02',
 VALUE='22UF',
 PRIM_FILE='./archive_libs/logical/q_cap/chips/chips.prt';

PART_NAME
 C2635 'Q_CAP_C0402-22UF,4V,20%,X6S,CH622KMEB02':;

SECTION_NUMBER 1
 '@T6G_MB_LIB.T6G(SCH_1):PAGE69_I121@PURE_QUANTA.Q_CAP(CHIPS)':
 C_PATH='@t6g_mb_lib.t6g(sch_1):page69_i121@pure_quanta.q_cap(chips)',
 P_PATH='@t6g_mb_lib.t6g(sch_1):page70_i121@pure_quanta.q_cap(chips)',
 PATH='I121',
 DRAWING='@T6G_MB_LIB.T6G(SCH_1):PAGE69',
 TOLERANCE='20%',
 MATERIAL='X6S',
 PHYS_PAGE='70',
 XY='(-2250,2000)',
 ROT='0',
 VER='1',
 PACK_TYPE='C0402',
 LOCATION='C2635',
 CDS_LIB='pure_quanta',
 CDS_PART_NAME='Q_CAP_C0402-22UF,4V,20%,X6S,CH622KMEB02',
 VOLTAGE='4V',
 PART_NUMBER='CH622KMEB02',
 VALUE='22UF',
 PRIM_FILE='./archive_libs/logical/q_cap/chips/chips.prt';

PART_NAME
 C2636 'Q_CAP_C0402-22UF,4V,20%,X6S,CH622KMEB02':;

SECTION_NUMBER 1
 '@T6G_MB_LIB.T6G(SCH_1):PAGE69_I120@PURE_QUANTA.Q_CAP(CHIPS)':
 C_PATH='@t6g_mb_lib.t6g(sch_1):page69_i120@pure_quanta.q_cap(chips)',
 P_PATH='@t6g_mb_lib.t6g(sch_1):page70_i120@pure_quanta.q_cap(chips)',
 PATH='I120',
 DRAWING='@T6G_MB_LIB.T6G(SCH_1):PAGE69',
 TOLERANCE='20%',
 MATERIAL='X6S',
 PHYS_PAGE='70',
 XY='(-2250,1400)',
 ROT='0',
 VER='1',
 PACK_TYPE='C0402',
 LOCATION='C2636',
 CDS_LIB='pure_quanta',
 CDS_PART_NAME='Q_CAP_C0402-22UF,4V,20%,X6S,CH622KMEB02',
 VOLTAGE='4V',
 PART_NUMBER='CH622KMEB02',
 VALUE='22UF',
 PRIM_FILE='./archive_libs/logical/q_cap/chips/chips.prt';

PART_NAME
 C2637 'Q_CAP_C0402-22UF,4V,20%,X6S,CH622KMEB02':;

SECTION_NUMBER 1
 '@T6G_MB_LIB.T6G(SCH_1):PAGE69_I168@PURE_QUANTA.Q_CAP(CHIPS)':
 C_PATH='@t6g_mb_lib.t6g(sch_1):page69_i168@pure_quanta.q_cap(chips)',
 P_PATH='@t6g_mb_lib.t6g(sch_1):page70_i168@pure_quanta.q_cap(chips)',
 PATH='I168',
 DRAWING='@T6G_MB_LIB.T6G(SCH_1):PAGE69',
 TOLERANCE='20%',
 MATERIAL='X6S',
 PHYS_PAGE='70',
 XY='(-1825,5900)',
 ROT='0',
 VER='1',
 PACK_TYPE='C0402',
 LOCATION='C2637',
 CDS_LIB='pure_quanta',
 CDS_PART_NAME='Q_CAP_C0402-22UF,4V,20%,X6S,CH622KMEB02',
 VOLTAGE='4V',
 PART_NUMBER='CH622KMEB02',
 VALUE='22UF',
 PRIM_FILE='./archive_libs/logical/q_cap/chips/chips.prt';

PART_NAME
 C2638 'Q_CAP_C0402-22UF,4V,20%,X6S,CH622KMEB02':;

SECTION_NUMBER 1
 '@T6G_MB_LIB.T6G(SCH_1):PAGE69_I166@PURE_QUANTA.Q_CAP(CHIPS)':
 C_PATH='@t6g_mb_lib.t6g(sch_1):page69_i166@pure_quanta.q_cap(chips)',
 P_PATH='@t6g_mb_lib.t6g(sch_1):page70_i166@pure_quanta.q_cap(chips)',
 PATH='I166',
 DRAWING='@T6G_MB_LIB.T6G(SCH_1):PAGE69',
 TOLERANCE='20%',
 MATERIAL='X6S',
 PHYS_PAGE='70',
 XY='(-1825,5100)',
 ROT='0',
 VER='1',
 PACK_TYPE='C0402',
 LOCATION='C2638',
 CDS_LIB='pure_quanta',
 CDS_PART_NAME='Q_CAP_C0402-22UF,4V,20%,X6S,CH622KMEB02',
 VOLTAGE='4V',
 PART_NUMBER='CH622KMEB02',
 VALUE='22UF',
 PRIM_FILE='./archive_libs/logical/q_cap/chips/chips.prt';

PART_NAME
 C2639 'Q_CAP_C0402-22UF,4V,20%,X6S,CH622KMEB02':;

SECTION_NUMBER 1
 '@T6G_MB_LIB.T6G(SCH_1):PAGE69_I145@PURE_QUANTA.Q_CAP(CHIPS)':
 C_PATH='@t6g_mb_lib.t6g(sch_1):page69_i145@pure_quanta.q_cap(chips)',
 P_PATH='@t6g_mb_lib.t6g(sch_1):page70_i145@pure_quanta.q_cap(chips)',
 PATH='I145',
 DRAWING='@T6G_MB_LIB.T6G(SCH_1):PAGE69',
 TOLERANCE='20%',
 MATERIAL='X6S',
 PHYS_PAGE='70',
 XY='(-1800,3275)',
 ROT='0',
 VER='1',
 PACK_TYPE='C0402',
 LOCATION='C2639',
 CDS_LIB='pure_quanta',
 CDS_PART_NAME='Q_CAP_C0402-22UF,4V,20%,X6S,CH622KMEB02',
 VOLTAGE='4V',
 PART_NUMBER='CH622KMEB02',
 VALUE='22UF',
 PRIM_FILE='./archive_libs/logical/q_cap/chips/chips.prt';

PART_NAME
 C2640 'Q_CAP_C0402-22UF,4V,20%,X6S,CH622KMEB02':;

SECTION_NUMBER 1
 '@T6G_MB_LIB.T6G(SCH_1):PAGE69_I143@PURE_QUANTA.Q_CAP(CHIPS)':
 C_PATH='@t6g_mb_lib.t6g(sch_1):page69_i143@pure_quanta.q_cap(chips)',
 P_PATH='@t6g_mb_lib.t6g(sch_1):page70_i143@pure_quanta.q_cap(chips)',
 PATH='I143',
 DRAWING='@T6G_MB_LIB.T6G(SCH_1):PAGE69',
 TOLERANCE='20%',
 MATERIAL='X6S',
 PHYS_PAGE='70',
 XY='(-1800,2625)',
 ROT='0',
 VER='1',
 PACK_TYPE='C0402',
 LOCATION='C2640',
 CDS_LIB='pure_quanta',
 CDS_PART_NAME='Q_CAP_C0402-22UF,4V,20%,X6S,CH622KMEB02',
 VOLTAGE='4V',
 PART_NUMBER='CH622KMEB02',
 VALUE='22UF',
 PRIM_FILE='./archive_libs/logical/q_cap/chips/chips.prt';

PART_NAME
 C2641 'Q_CAP_C0402-22UF,4V,20%,X6S,CH622KMEB02':;

SECTION_NUMBER 1
 '@T6G_MB_LIB.T6G(SCH_1):PAGE69_I134@PURE_QUANTA.Q_CAP(CHIPS)':
 C_PATH='@t6g_mb_lib.t6g(sch_1):page69_i134@pure_quanta.q_cap(chips)',
 P_PATH='@t6g_mb_lib.t6g(sch_1):page70_i134@pure_quanta.q_cap(chips)',
 PATH='I134',
 DRAWING='@T6G_MB_LIB.T6G(SCH_1):PAGE69',
 TOLERANCE='20%',
 MATERIAL='X6S',
 PHYS_PAGE='70',
 XY='(-1800,2000)',
 ROT='0',
 VER='1',
 PACK_TYPE='C0402',
 LOCATION='C2641',
 CDS_LIB='pure_quanta',
 CDS_PART_NAME='Q_CAP_C0402-22UF,4V,20%,X6S,CH622KMEB02',
 VOLTAGE='4V',
 PART_NUMBER='CH622KMEB02',
 VALUE='22UF',
 PRIM_FILE='./archive_libs/logical/q_cap/chips/chips.prt';

PART_NAME
 C2642 'Q_CAP_C0402-22UF,4V,20%,X6S,CH622KMEB02':;

SECTION_NUMBER 1
 '@T6G_MB_LIB.T6G(SCH_1):PAGE69_I133@PURE_QUANTA.Q_CAP(CHIPS)':
 C_PATH='@t6g_mb_lib.t6g(sch_1):page69_i133@pure_quanta.q_cap(chips)',
 P_PATH='@t6g_mb_lib.t6g(sch_1):page70_i133@pure_quanta.q_cap(chips)',
 PATH='I133',
 DRAWING='@T6G_MB_LIB.T6G(SCH_1):PAGE69',
 TOLERANCE='20%',
 MATERIAL='X6S',
 PHYS_PAGE='70',
 XY='(-1800,1400)',
 ROT='0',
 VER='1',
 PACK_TYPE='C0402',
 LOCATION='C2642',
 CDS_LIB='pure_quanta',
 CDS_PART_NAME='Q_CAP_C0402-22UF,4V,20%,X6S,CH622KMEB02',
 VOLTAGE='4V',
 PART_NUMBER='CH622KMEB02',
 VALUE='22UF',
 PRIM_FILE='./archive_libs/logical/q_cap/chips/chips.prt';

PART_NAME
 C2643 'Q_CAP_C0402-22UF,4V,20%,X6S,CH622KMEB02':;

SECTION_NUMBER 1
 '@T6G_MB_LIB.T6G(SCH_1):PAGE69_I169@PURE_QUANTA.Q_CAP(CHIPS)':
 C_PATH='@t6g_mb_lib.t6g(sch_1):page69_i169@pure_quanta.q_cap(chips)',
 P_PATH='@t6g_mb_lib.t6g(sch_1):page70_i169@pure_quanta.q_cap(chips)',
 PATH='I169',
 DRAWING='@T6G_MB_LIB.T6G(SCH_1):PAGE69',
 TOLERANCE='20%',
 MATERIAL='X6S',
 PHYS_PAGE='70',
 XY='(-1375,5900)',
 ROT='0',
 VER='1',
 PACK_TYPE='C0402',
 LOCATION='C2643',
 CDS_LIB='pure_quanta',
 CDS_PART_NAME='Q_CAP_C0402-22UF,4V,20%,X6S,CH622KMEB02',
 VOLTAGE='4V',
 PART_NUMBER='CH622KMEB02',
 VALUE='22UF',
 PRIM_FILE='./archive_libs/logical/q_cap/chips/chips.prt';

PART_NAME
 C2644 'Q_CAP_C0402-22UF,4V,20%,X6S,CH622KMEB02':;

SECTION_NUMBER 1
 '@T6G_MB_LIB.T6G(SCH_1):PAGE69_I167@PURE_QUANTA.Q_CAP(CHIPS)':
 C_PATH='@t6g_mb_lib.t6g(sch_1):page69_i167@pure_quanta.q_cap(chips)',
 P_PATH='@t6g_mb_lib.t6g(sch_1):page70_i167@pure_quanta.q_cap(chips)',
 PATH='I167',
 DRAWING='@T6G_MB_LIB.T6G(SCH_1):PAGE69',
 TOLERANCE='20%',
 MATERIAL='X6S',
 PHYS_PAGE='70',
 XY='(-1375,5100)',
 ROT='0',
 VER='1',
 PACK_TYPE='C0402',
 LOCATION='C2644',
 CDS_LIB='pure_quanta',
 CDS_PART_NAME='Q_CAP_C0402-22UF,4V,20%,X6S,CH622KMEB02',
 VOLTAGE='4V',
 PART_NUMBER='CH622KMEB02',
 VALUE='22UF',
 PRIM_FILE='./archive_libs/logical/q_cap/chips/chips.prt';

PART_NAME
 C2645 'Q_CAP_C0402-22UF,4V,20%,X6S,CH622KMEB02':;

SECTION_NUMBER 1
 '@T6G_MB_LIB.T6G(SCH_1):PAGE69_I146@PURE_QUANTA.Q_CAP(CHIPS)':
 C_PATH='@t6g_mb_lib.t6g(sch_1):page69_i146@pure_quanta.q_cap(chips)',
 P_PATH='@t6g_mb_lib.t6g(sch_1):page70_i146@pure_quanta.q_cap(chips)',
 PATH='I146',
 DRAWING='@T6G_MB_LIB.T6G(SCH_1):PAGE69',
 TOLERANCE='20%',
 MATERIAL='X6S',
 PHYS_PAGE='70',
 XY='(-1350,3275)',
 ROT='0',
 VER='1',
 PACK_TYPE='C0402',
 LOCATION='C2645',
 CDS_LIB='pure_quanta',
 CDS_PART_NAME='Q_CAP_C0402-22UF,4V,20%,X6S,CH622KMEB02',
 VOLTAGE='4V',
 PART_NUMBER='CH622KMEB02',
 VALUE='22UF',
 PRIM_FILE='./archive_libs/logical/q_cap/chips/chips.prt';

PART_NAME
 C2646 'Q_CAP_C0402-22UF,4V,20%,X6S,CH622KMEB02':;

SECTION_NUMBER 1
 '@T6G_MB_LIB.T6G(SCH_1):PAGE69_I144@PURE_QUANTA.Q_CAP(CHIPS)':
 C_PATH='@t6g_mb_lib.t6g(sch_1):page69_i144@pure_quanta.q_cap(chips)',
 P_PATH='@t6g_mb_lib.t6g(sch_1):page70_i144@pure_quanta.q_cap(chips)',
 PATH='I144',
 DRAWING='@T6G_MB_LIB.T6G(SCH_1):PAGE69',
 TOLERANCE='20%',
 MATERIAL='X6S',
 PHYS_PAGE='70',
 XY='(-1350,2625)',
 ROT='0',
 VER='1',
 PACK_TYPE='C0402',
 LOCATION='C2646',
 CDS_LIB='pure_quanta',
 CDS_PART_NAME='Q_CAP_C0402-22UF,4V,20%,X6S,CH622KMEB02',
 VOLTAGE='4V',
 PART_NUMBER='CH622KMEB02',
 VALUE='22UF',
 PRIM_FILE='./archive_libs/logical/q_cap/chips/chips.prt';

PART_NAME
 C2647 'Q_CAP_C0402-22UF,4V,20%,X6S,CH622KMEB02':;

SECTION_NUMBER 1
 '@T6G_MB_LIB.T6G(SCH_1):PAGE69_I136@PURE_QUANTA.Q_CAP(CHIPS)':
 C_PATH='@t6g_mb_lib.t6g(sch_1):page69_i136@pure_quanta.q_cap(chips)',
 P_PATH='@t6g_mb_lib.t6g(sch_1):page70_i136@pure_quanta.q_cap(chips)',
 PATH='I136',
 DRAWING='@T6G_MB_LIB.T6G(SCH_1):PAGE69',
 TOLERANCE='20%',
 MATERIAL='X6S',
 PHYS_PAGE='70',
 XY='(-1350,2000)',
 ROT='0',
 VER='1',
 PACK_TYPE='C0402',
 LOCATION='C2647',
 CDS_LIB='pure_quanta',
 CDS_PART_NAME='Q_CAP_C0402-22UF,4V,20%,X6S,CH622KMEB02',
 VOLTAGE='4V',
 PART_NUMBER='CH622KMEB02',
 VALUE='22UF',
 PRIM_FILE='./archive_libs/logical/q_cap/chips/chips.prt';

PART_NAME
 C2648 'Q_CAP_C0402-22UF,4V,20%,X6S,CH622KMEB02':;

SECTION_NUMBER 1
 '@T6G_MB_LIB.T6G(SCH_1):PAGE69_I135@PURE_QUANTA.Q_CAP(CHIPS)':
 C_PATH='@t6g_mb_lib.t6g(sch_1):page69_i135@pure_quanta.q_cap(chips)',
 P_PATH='@t6g_mb_lib.t6g(sch_1):page70_i135@pure_quanta.q_cap(chips)',
 PATH='I135',
 DRAWING='@T6G_MB_LIB.T6G(SCH_1):PAGE69',
 TOLERANCE='20%',
 MATERIAL='X6S',
 PHYS_PAGE='70',
 XY='(-1350,1400)',
 ROT='0',
 VER='1',
 PACK_TYPE='C0402',
 LOCATION='C2648',
 CDS_LIB='pure_quanta',
 CDS_PART_NAME='Q_CAP_C0402-22UF,4V,20%,X6S,CH622KMEB02',
 VOLTAGE='4V',
 PART_NUMBER='CH622KMEB02',
 VALUE='22UF',
 PRIM_FILE='./archive_libs/logical/q_cap/chips/chips.prt';

PART_NAME
 C2649 'Q_CAP_C0402-22UF,4V,20%,X6S,CH622KMEB02':;

SECTION_NUMBER 1
 '@T6G_MB_LIB.T6G(SCH_1):PAGE69_I173@PURE_QUANTA.Q_CAP(CHIPS)':
 C_PATH='@t6g_mb_lib.t6g(sch_1):page69_i173@pure_quanta.q_cap(chips)',
 P_PATH='@t6g_mb_lib.t6g(sch_1):page70_i173@pure_quanta.q_cap(chips)',
 PATH='I173',
 DRAWING='@T6G_MB_LIB.T6G(SCH_1):PAGE69',
 TOLERANCE='20%',
 MATERIAL='X6S',
 PHYS_PAGE='70',
 XY='(-925,5900)',
 ROT='0',
 VER='1',
 PACK_TYPE='C0402',
 LOCATION='C2649',
 CDS_LIB='pure_quanta',
 CDS_PART_NAME='Q_CAP_C0402-22UF,4V,20%,X6S,CH622KMEB02',
 VOLTAGE='4V',
 PART_NUMBER='CH622KMEB02',
 VALUE='22UF',
 PRIM_FILE='./archive_libs/logical/q_cap/chips/chips.prt';

PART_NAME
 C2650 'Q_CAP_C0402-22UF,4V,20%,X6S,CH622KMEB02':;

SECTION_NUMBER 1
 '@T6G_MB_LIB.T6G(SCH_1):PAGE69_I170@PURE_QUANTA.Q_CAP(CHIPS)':
 C_PATH='@t6g_mb_lib.t6g(sch_1):page69_i170@pure_quanta.q_cap(chips)',
 P_PATH='@t6g_mb_lib.t6g(sch_1):page70_i170@pure_quanta.q_cap(chips)',
 PATH='I170',
 DRAWING='@T6G_MB_LIB.T6G(SCH_1):PAGE69',
 TOLERANCE='20%',
 MATERIAL='X6S',
 PHYS_PAGE='70',
 XY='(-925,5100)',
 ROT='0',
 VER='1',
 PACK_TYPE='C0402',
 LOCATION='C2650',
 CDS_LIB='pure_quanta',
 CDS_PART_NAME='Q_CAP_C0402-22UF,4V,20%,X6S,CH622KMEB02',
 VOLTAGE='4V',
 PART_NUMBER='CH622KMEB02',
 VALUE='22UF',
 PRIM_FILE='./archive_libs/logical/q_cap/chips/chips.prt';

PART_NAME
 C2651 'Q_CAP_C0402-22UF,4V,20%,X6S,CH622KMEB02':;

SECTION_NUMBER 1
 '@T6G_MB_LIB.T6G(SCH_1):PAGE69_I151@PURE_QUANTA.Q_CAP(CHIPS)':
 C_PATH='@t6g_mb_lib.t6g(sch_1):page69_i151@pure_quanta.q_cap(chips)',
 P_PATH='@t6g_mb_lib.t6g(sch_1):page70_i151@pure_quanta.q_cap(chips)',
 PATH='I151',
 DRAWING='@T6G_MB_LIB.T6G(SCH_1):PAGE69',
 TOLERANCE='20%',
 MATERIAL='X6S',
 PHYS_PAGE='70',
 XY='(-900,3275)',
 ROT='0',
 VER='1',
 PACK_TYPE='C0402',
 LOCATION='C2651',
 CDS_LIB='pure_quanta',
 CDS_PART_NAME='Q_CAP_C0402-22UF,4V,20%,X6S,CH622KMEB02',
 VOLTAGE='4V',
 PART_NUMBER='CH622KMEB02',
 VALUE='22UF',
 PRIM_FILE='./archive_libs/logical/q_cap/chips/chips.prt';

PART_NAME
 C2652 'Q_CAP_C0402-22UF,4V,20%,X6S,CH622KMEB02':;

SECTION_NUMBER 1
 '@T6G_MB_LIB.T6G(SCH_1):PAGE69_I147@PURE_QUANTA.Q_CAP(CHIPS)':
 C_PATH='@t6g_mb_lib.t6g(sch_1):page69_i147@pure_quanta.q_cap(chips)',
 P_PATH='@t6g_mb_lib.t6g(sch_1):page70_i147@pure_quanta.q_cap(chips)',
 PATH='I147',
 DRAWING='@T6G_MB_LIB.T6G(SCH_1):PAGE69',
 TOLERANCE='20%',
 MATERIAL='X6S',
 PHYS_PAGE='70',
 XY='(-900,2625)',
 ROT='0',
 VER='1',
 PACK_TYPE='C0402',
 LOCATION='C2652',
 CDS_LIB='pure_quanta',
 CDS_PART_NAME='Q_CAP_C0402-22UF,4V,20%,X6S,CH622KMEB02',
 VOLTAGE='4V',
 PART_NUMBER='CH622KMEB02',
 VALUE='22UF',
 PRIM_FILE='./archive_libs/logical/q_cap/chips/chips.prt';

PART_NAME
 C2653 'Q_CAP_C0402-22UF,4V,20%,X6S,CH622KMEB02':;

SECTION_NUMBER 1
 '@T6G_MB_LIB.T6G(SCH_1):PAGE69_I139@PURE_QUANTA.Q_CAP(CHIPS)':
 C_PATH='@t6g_mb_lib.t6g(sch_1):page69_i139@pure_quanta.q_cap(chips)',
 P_PATH='@t6g_mb_lib.t6g(sch_1):page70_i139@pure_quanta.q_cap(chips)',
 PATH='I139',
 DRAWING='@T6G_MB_LIB.T6G(SCH_1):PAGE69',
 TOLERANCE='20%',
 MATERIAL='X6S',
 PHYS_PAGE='70',
 XY='(-900,2000)',
 ROT='0',
 VER='1',
 PACK_TYPE='C0402',
 LOCATION='C2653',
 CDS_LIB='pure_quanta',
 CDS_PART_NAME='Q_CAP_C0402-22UF,4V,20%,X6S,CH622KMEB02',
 VOLTAGE='4V',
 PART_NUMBER='CH622KMEB02',
 VALUE='22UF',
 PRIM_FILE='./archive_libs/logical/q_cap/chips/chips.prt';

PART_NAME
 C2654 'Q_CAP_C0402-22UF,4V,20%,X6S,CH622KMEB02':;

SECTION_NUMBER 1
 '@T6G_MB_LIB.T6G(SCH_1):PAGE69_I175@PURE_QUANTA.Q_CAP(CHIPS)':
 C_PATH='@t6g_mb_lib.t6g(sch_1):page69_i175@pure_quanta.q_cap(chips)',
 P_PATH='@t6g_mb_lib.t6g(sch_1):page70_i175@pure_quanta.q_cap(chips)',
 PATH='I175',
 DRAWING='@T6G_MB_LIB.T6G(SCH_1):PAGE69',
 TOLERANCE='20%',
 MATERIAL='X6S',
 PHYS_PAGE='70',
 XY='(-525,5900)',
 ROT='0',
 VER='1',
 PACK_TYPE='C0402',
 LOCATION='C2654',
 CDS_LIB='pure_quanta',
 CDS_PART_NAME='Q_CAP_C0402-22UF,4V,20%,X6S,CH622KMEB02',
 VOLTAGE='4V',
 PART_NUMBER='CH622KMEB02',
 VALUE='22UF',
 PRIM_FILE='./archive_libs/logical/q_cap/chips/chips.prt';

PART_NAME
 C2655 'Q_CAP_C0402-22UF,4V,20%,X6S,CH622KMEB02':;

SECTION_NUMBER 1
 '@T6G_MB_LIB.T6G(SCH_1):PAGE69_I172@PURE_QUANTA.Q_CAP(CHIPS)':
 C_PATH='@t6g_mb_lib.t6g(sch_1):page69_i172@pure_quanta.q_cap(chips)',
 P_PATH='@t6g_mb_lib.t6g(sch_1):page70_i172@pure_quanta.q_cap(chips)',
 PATH='I172',
 DRAWING='@T6G_MB_LIB.T6G(SCH_1):PAGE69',
 TOLERANCE='20%',
 MATERIAL='X6S',
 PHYS_PAGE='70',
 XY='(-525,5100)',
 ROT='0',
 VER='1',
 PACK_TYPE='C0402',
 LOCATION='C2655',
 CDS_LIB='pure_quanta',
 CDS_PART_NAME='Q_CAP_C0402-22UF,4V,20%,X6S,CH622KMEB02',
 VOLTAGE='4V',
 PART_NUMBER='CH622KMEB02',
 VALUE='22UF',
 PRIM_FILE='./archive_libs/logical/q_cap/chips/chips.prt';

PART_NAME
 C2656 'Q_CAP_C0402-22UF,4V,20%,X6S,CH622KMEB02':;

SECTION_NUMBER 1
 '@T6G_MB_LIB.T6G(SCH_1):PAGE69_I152@PURE_QUANTA.Q_CAP(CHIPS)':
 C_PATH='@t6g_mb_lib.t6g(sch_1):page69_i152@pure_quanta.q_cap(chips)',
 P_PATH='@t6g_mb_lib.t6g(sch_1):page70_i152@pure_quanta.q_cap(chips)',
 PATH='I152',
 DRAWING='@T6G_MB_LIB.T6G(SCH_1):PAGE69',
 TOLERANCE='20%',
 MATERIAL='X6S',
 PHYS_PAGE='70',
 XY='(-500,3275)',
 ROT='0',
 VER='1',
 PACK_TYPE='C0402',
 LOCATION='C2656',
 CDS_LIB='pure_quanta',
 CDS_PART_NAME='Q_CAP_C0402-22UF,4V,20%,X6S,CH622KMEB02',
 VOLTAGE='4V',
 PART_NUMBER='CH622KMEB02',
 VALUE='22UF',
 PRIM_FILE='./archive_libs/logical/q_cap/chips/chips.prt';

PART_NAME
 C2657 'Q_CAP_C0402-22UF,4V,20%,X6S,CH622KMEB02':;

SECTION_NUMBER 1
 '@T6G_MB_LIB.T6G(SCH_1):PAGE69_I149@PURE_QUANTA.Q_CAP(CHIPS)':
 C_PATH='@t6g_mb_lib.t6g(sch_1):page69_i149@pure_quanta.q_cap(chips)',
 P_PATH='@t6g_mb_lib.t6g(sch_1):page70_i149@pure_quanta.q_cap(chips)',
 PATH='I149',
 DRAWING='@T6G_MB_LIB.T6G(SCH_1):PAGE69',
 TOLERANCE='20%',
 MATERIAL='X6S',
 PHYS_PAGE='70',
 XY='(-500,2625)',
 ROT='0',
 VER='1',
 PACK_TYPE='C0402',
 LOCATION='C2657',
 CDS_LIB='pure_quanta',
 CDS_PART_NAME='Q_CAP_C0402-22UF,4V,20%,X6S,CH622KMEB02',
 VOLTAGE='4V',
 PART_NUMBER='CH622KMEB02',
 VALUE='22UF',
 PRIM_FILE='./archive_libs/logical/q_cap/chips/chips.prt';

PART_NAME
 C2658 'Q_CAP_C0402-22UF,4V,20%,X6S,CH622KMEB02':;

SECTION_NUMBER 1
 '@T6G_MB_LIB.T6G(SCH_1):PAGE69_I142@PURE_QUANTA.Q_CAP(CHIPS)':
 C_PATH='@t6g_mb_lib.t6g(sch_1):page69_i142@pure_quanta.q_cap(chips)',
 P_PATH='@t6g_mb_lib.t6g(sch_1):page70_i142@pure_quanta.q_cap(chips)',
 PATH='I142',
 DRAWING='@T6G_MB_LIB.T6G(SCH_1):PAGE69',
 TOLERANCE='20%',
 MATERIAL='X6S',
 PHYS_PAGE='70',
 XY='(-500,2000)',
 ROT='0',
 VER='1',
 PACK_TYPE='C0402',
 LOCATION='C2658',
 CDS_LIB='pure_quanta',
 CDS_PART_NAME='Q_CAP_C0402-22UF,4V,20%,X6S,CH622KMEB02',
 VOLTAGE='4V',
 PART_NUMBER='CH622KMEB02',
 VALUE='22UF',
 PRIM_FILE='./archive_libs/logical/q_cap/chips/chips.prt';

PART_NAME
 C2659 'Q_CAP_C0402-10UF,6.3V,20%,X6S,CH6101MEB01':;

SECTION_NUMBER 1
 '@T6G_MB_LIB.T6G(SCH_1):PAGE74_I26@PURE_QUANTA.Q_CAP(CHIPS)':
 C_PATH='@t6g_mb_lib.t6g(sch_1):page74_i26@pure_quanta.q_cap(chips)',
 P_PATH='@t6g_mb_lib.t6g(sch_1):page75_i26@pure_quanta.q_cap(chips)',
 PATH='I26',
 DRAWING='@T6G_MB_LIB.T6G(SCH_1):PAGE74',
 TOLERANCE='20%',
 MATERIAL='X6S',
 PHYS_PAGE='75',
 XY='(-8475,5400)',
 ROT='0',
 VER='1',
 PACK_TYPE='C0402',
 LOCATION='C2659',
 CDS_LIB='pure_quanta',
 CDS_PART_NAME='Q_CAP_C0402-10UF,6.3V,20%,X6S,CH6101MEB01',
 VOLTAGE='6.3V',
 PART_NUMBER='CH6101MEB01',
 VALUE='10UF',
 PRIM_FILE='./archive_libs/logical/q_cap/chips/chips.prt';

PART_NAME
 C2660 'Q_CAP_C0402-22UF,4V,20%,X6S,CH622KMEB02':;

SECTION_NUMBER 1
 '@T6G_MB_LIB.T6G(SCH_1):PAGE74_I3@PURE_QUANTA.Q_CAP(CHIPS)':
 C_PATH='@t6g_mb_lib.t6g(sch_1):page74_i3@pure_quanta.q_cap(chips)',
 P_PATH='@t6g_mb_lib.t6g(sch_1):page75_i3@pure_quanta.q_cap(chips)',
 PATH='I3',
 DRAWING='@T6G_MB_LIB.T6G(SCH_1):PAGE74',
 TOLERANCE='20%',
 MATERIAL='X6S',
 PHYS_PAGE='75',
 XY='(-8550,3775)',
 ROT='0',
 VER='1',
 PACK_TYPE='C0402',
 LOCATION='C2660',
 CDS_LIB='pure_quanta',
 CDS_PART_NAME='Q_CAP_C0402-22UF,4V,20%,X6S,CH622KMEB02',
 VOLTAGE='4V',
 PART_NUMBER='CH622KMEB02',
 VALUE='22UF',
 PRIM_FILE='./archive_libs/logical/q_cap/chips/chips.prt';

PART_NAME
 C2661 'Q_CAP_C0402-22UF,4V,20%,X6S,CH622KMEB02':;

SECTION_NUMBER 1
 '@T6G_MB_LIB.T6G(SCH_1):PAGE74_I1@PURE_QUANTA.Q_CAP(CHIPS)':
 C_PATH='@t6g_mb_lib.t6g(sch_1):page74_i1@pure_quanta.q_cap(chips)',
 P_PATH='@t6g_mb_lib.t6g(sch_1):page75_i1@pure_quanta.q_cap(chips)',
 PATH='I1',
 DRAWING='@T6G_MB_LIB.T6G(SCH_1):PAGE74',
 TOLERANCE='20%',
 MATERIAL='X6S',
 PHYS_PAGE='75',
 XY='(-8550,3000)',
 ROT='0',
 VER='1',
 PACK_TYPE='C0402',
 LOCATION='C2661',
 CDS_LIB='pure_quanta',
 CDS_PART_NAME='Q_CAP_C0402-22UF,4V,20%,X6S,CH622KMEB02',
 VOLTAGE='4V',
 PART_NUMBER='CH622KMEB02',
 VALUE='22UF',
 PRIM_FILE='./archive_libs/logical/q_cap/chips/chips.prt';

PART_NAME
 C2662 'Q_CAP_C0402-10UF,6.3V,20%,X6S,CH6101MEB01':;

SECTION_NUMBER 1
 '@T6G_MB_LIB.T6G(SCH_1):PAGE74_I25@PURE_QUANTA.Q_CAP(CHIPS)':
 C_PATH='@t6g_mb_lib.t6g(sch_1):page74_i25@pure_quanta.q_cap(chips)',
 P_PATH='@t6g_mb_lib.t6g(sch_1):page75_i25@pure_quanta.q_cap(chips)',
 PATH='I25',
 DRAWING='@T6G_MB_LIB.T6G(SCH_1):PAGE74',
 TOLERANCE='20%',
 MATERIAL='X6S',
 PHYS_PAGE='75',
 XY='(-8025,5400)',
 ROT='0',
 VER='1',
 PACK_TYPE='C0402',
 LOCATION='C2662',
 CDS_LIB='pure_quanta',
 CDS_PART_NAME='Q_CAP_C0402-10UF,6.3V,20%,X6S,CH6101MEB01',
 VOLTAGE='6.3V',
 PART_NUMBER='CH6101MEB01',
 VALUE='10UF',
 PRIM_FILE='./archive_libs/logical/q_cap/chips/chips.prt';

PART_NAME
 C2663 'Q_CAP_C0402-22UF,4V,20%,X6S,CH622KMEB02':;

SECTION_NUMBER 1
 '@T6G_MB_LIB.T6G(SCH_1):PAGE74_I9@PURE_QUANTA.Q_CAP(CHIPS)':
 C_PATH='@t6g_mb_lib.t6g(sch_1):page74_i9@pure_quanta.q_cap(chips)',
 P_PATH='@t6g_mb_lib.t6g(sch_1):page75_i9@pure_quanta.q_cap(chips)',
 PATH='I9',
 DRAWING='@T6G_MB_LIB.T6G(SCH_1):PAGE74',
 TOLERANCE='20%',
 MATERIAL='X6S',
 PHYS_PAGE='75',
 XY='(-8100,3775)',
 ROT='0',
 VER='1',
 PACK_TYPE='C0402',
 LOCATION='C2663',
 CDS_LIB='pure_quanta',
 CDS_PART_NAME='Q_CAP_C0402-22UF,4V,20%,X6S,CH622KMEB02',
 VOLTAGE='4V',
 PART_NUMBER='CH622KMEB02',
 VALUE='22UF',
 PRIM_FILE='./archive_libs/logical/q_cap/chips/chips.prt';

PART_NAME
 C2664 'Q_CAP_C0402-22UF,4V,20%,X6S,CH622KMEB02':;

SECTION_NUMBER 1
 '@T6G_MB_LIB.T6G(SCH_1):PAGE74_I8@PURE_QUANTA.Q_CAP(CHIPS)':
 C_PATH='@t6g_mb_lib.t6g(sch_1):page74_i8@pure_quanta.q_cap(chips)',
 P_PATH='@t6g_mb_lib.t6g(sch_1):page75_i8@pure_quanta.q_cap(chips)',
 PATH='I8',
 DRAWING='@T6G_MB_LIB.T6G(SCH_1):PAGE74',
 TOLERANCE='20%',
 MATERIAL='X6S',
 PHYS_PAGE='75',
 XY='(-8100,3000)',
 ROT='0',
 VER='1',
 PACK_TYPE='C0402',
 LOCATION='C2664',
 CDS_LIB='pure_quanta',
 CDS_PART_NAME='Q_CAP_C0402-22UF,4V,20%,X6S,CH622KMEB02',
 VOLTAGE='4V',
 PART_NUMBER='CH622KMEB02',
 VALUE='22UF',
 PRIM_FILE='./archive_libs/logical/q_cap/chips/chips.prt';

PART_NAME
 C2665 'Q_CAP_C0402-22UF,4V,20%,X6S,CH622KMEB02':;

SECTION_NUMBER 1
 '@T6G_MB_LIB.T6G(SCH_1):PAGE74_I10@PURE_QUANTA.Q_CAP(CHIPS)':
 C_PATH='@t6g_mb_lib.t6g(sch_1):page74_i10@pure_quanta.q_cap(chips)',
 P_PATH='@t6g_mb_lib.t6g(sch_1):page75_i10@pure_quanta.q_cap(chips)',
 PATH='I10',
 DRAWING='@T6G_MB_LIB.T6G(SCH_1):PAGE74',
 TOLERANCE='20%',
 MATERIAL='X6S',
 PHYS_PAGE='75',
 XY='(-7650,3775)',
 ROT='0',
 VER='1',
 PACK_TYPE='C0402',
 LOCATION='C2665',
 CDS_LIB='pure_quanta',
 CDS_PART_NAME='Q_CAP_C0402-22UF,4V,20%,X6S,CH622KMEB02',
 VOLTAGE='4V',
 PART_NUMBER='CH622KMEB02',
 VALUE='22UF',
 PRIM_FILE='./archive_libs/logical/q_cap/chips/chips.prt';

PART_NAME
 C2667 'Q_CAP_C0402-22UF,4V,20%,X6S,CH622KMEB02':;

SECTION_NUMBER 1
 '@T6G_MB_LIB.T6G(SCH_1):PAGE74_I11@PURE_QUANTA.Q_CAP(CHIPS)':
 C_PATH='@t6g_mb_lib.t6g(sch_1):page74_i11@pure_quanta.q_cap(chips)',
 P_PATH='@t6g_mb_lib.t6g(sch_1):page75_i11@pure_quanta.q_cap(chips)',
 PATH='I11',
 DRAWING='@T6G_MB_LIB.T6G(SCH_1):PAGE74',
 TOLERANCE='20%',
 MATERIAL='X6S',
 PHYS_PAGE='75',
 XY='(-7200,3775)',
 ROT='0',
 VER='1',
 PACK_TYPE='C0402',
 LOCATION='C2667',
 CDS_LIB='pure_quanta',
 CDS_PART_NAME='Q_CAP_C0402-22UF,4V,20%,X6S,CH622KMEB02',
 VOLTAGE='4V',
 PART_NUMBER='CH622KMEB02',
 VALUE='22UF',
 PRIM_FILE='./archive_libs/logical/q_cap/chips/chips.prt';

PART_NAME
 C2668 'Q_CAP_C0402-22UF,4V,20%,X6S,CH622KMEB02':;

SECTION_NUMBER 1
 '@T6G_MB_LIB.T6G(SCH_1):PAGE74_I12@PURE_QUANTA.Q_CAP(CHIPS)':
 C_PATH='@t6g_mb_lib.t6g(sch_1):page74_i12@pure_quanta.q_cap(chips)',
 P_PATH='@t6g_mb_lib.t6g(sch_1):page75_i12@pure_quanta.q_cap(chips)',
 PATH='I12',
 DRAWING='@T6G_MB_LIB.T6G(SCH_1):PAGE74',
 TOLERANCE='20%',
 MATERIAL='X6S',
 PHYS_PAGE='75',
 XY='(-6750,3775)',
 ROT='0',
 VER='1',
 PACK_TYPE='C0402',
 LOCATION='C2668',
 CDS_LIB='pure_quanta',
 CDS_PART_NAME='Q_CAP_C0402-22UF,4V,20%,X6S,CH622KMEB02',
 VOLTAGE='4V',
 PART_NUMBER='CH622KMEB02',
 VALUE='22UF',
 PRIM_FILE='./archive_libs/logical/q_cap/chips/chips.prt';

PART_NAME
 C2669 'Q_CAP_C0402-22UF,4V,20%,X6S,CH622KMEB02':;

SECTION_NUMBER 1
 '@T6G_MB_LIB.T6G(SCH_1):PAGE74_I13@PURE_QUANTA.Q_CAP(CHIPS)':
 C_PATH='@t6g_mb_lib.t6g(sch_1):page74_i13@pure_quanta.q_cap(chips)',
 P_PATH='@t6g_mb_lib.t6g(sch_1):page75_i13@pure_quanta.q_cap(chips)',
 PATH='I13',
 DRAWING='@T6G_MB_LIB.T6G(SCH_1):PAGE74',
 TOLERANCE='20%',
 MATERIAL='X6S',
 PHYS_PAGE='75',
 XY='(-6300,3775)',
 ROT='0',
 VER='1',
 PACK_TYPE='C0402',
 LOCATION='C2669',
 CDS_LIB='pure_quanta',
 CDS_PART_NAME='Q_CAP_C0402-22UF,4V,20%,X6S,CH622KMEB02',
 VOLTAGE='4V',
 PART_NUMBER='CH622KMEB02',
 VALUE='22UF',
 PRIM_FILE='./archive_libs/logical/q_cap/chips/chips.prt';

PART_NAME
 C2670 'Q_CAP_C0402-22UF,4V,20%,X6S,CH622KMEB02':;

SECTION_NUMBER 1
 '@T6G_MB_LIB.T6G(SCH_1):PAGE74_I14@PURE_QUANTA.Q_CAP(CHIPS)':
 C_PATH='@t6g_mb_lib.t6g(sch_1):page74_i14@pure_quanta.q_cap(chips)',
 P_PATH='@t6g_mb_lib.t6g(sch_1):page75_i14@pure_quanta.q_cap(chips)',
 PATH='I14',
 DRAWING='@T6G_MB_LIB.T6G(SCH_1):PAGE74',
 TOLERANCE='20%',
 MATERIAL='X6S',
 PHYS_PAGE='75',
 XY='(-5850,3775)',
 ROT='0',
 VER='1',
 PACK_TYPE='C0402',
 LOCATION='C2670',
 CDS_LIB='pure_quanta',
 CDS_PART_NAME='Q_CAP_C0402-22UF,4V,20%,X6S,CH622KMEB02',
 VOLTAGE='4V',
 PART_NUMBER='CH622KMEB02',
 VALUE='22UF',
 PRIM_FILE='./archive_libs/logical/q_cap/chips/chips.prt';

PART_NAME
 C2671 'Q_CAP_C0402-22UF,4V,20%,X6S,CH622KMEB02':;

SECTION_NUMBER 1
 '@T6G_MB_LIB.T6G(SCH_1):PAGE74_I15@PURE_QUANTA.Q_CAP(CHIPS)':
 C_PATH='@t6g_mb_lib.t6g(sch_1):page74_i15@pure_quanta.q_cap(chips)',
 P_PATH='@t6g_mb_lib.t6g(sch_1):page75_i15@pure_quanta.q_cap(chips)',
 PATH='I15',
 DRAWING='@T6G_MB_LIB.T6G(SCH_1):PAGE74',
 TOLERANCE='20%',
 MATERIAL='X6S',
 PHYS_PAGE='75',
 XY='(-5400,3775)',
 ROT='0',
 VER='1',
 PACK_TYPE='C0402',
 LOCATION='C2671',
 CDS_LIB='pure_quanta',
 CDS_PART_NAME='Q_CAP_C0402-22UF,4V,20%,X6S,CH622KMEB02',
 VOLTAGE='4V',
 PART_NUMBER='CH622KMEB02',
 VALUE='22UF',
 PRIM_FILE='./archive_libs/logical/q_cap/chips/chips.prt';

PART_NAME
 C2672 'Q_CAP_C0402-22UF,4V,20%,X6S,CH622KMEB02':;

SECTION_NUMBER 1
 '@T6G_MB_LIB.T6G(SCH_1):PAGE74_I16@PURE_QUANTA.Q_CAP(CHIPS)':
 C_PATH='@t6g_mb_lib.t6g(sch_1):page74_i16@pure_quanta.q_cap(chips)',
 P_PATH='@t6g_mb_lib.t6g(sch_1):page75_i16@pure_quanta.q_cap(chips)',
 PATH='I16',
 DRAWING='@T6G_MB_LIB.T6G(SCH_1):PAGE74',
 TOLERANCE='20%',
 MATERIAL='X6S',
 PHYS_PAGE='75',
 XY='(-4950,3775)',
 ROT='0',
 VER='1',
 PACK_TYPE='C0402',
 LOCATION='C2672',
 CDS_LIB='pure_quanta',
 CDS_PART_NAME='Q_CAP_C0402-22UF,4V,20%,X6S,CH622KMEB02',
 VOLTAGE='4V',
 PART_NUMBER='CH622KMEB02',
 VALUE='22UF',
 PRIM_FILE='./archive_libs/logical/q_cap/chips/chips.prt';

PART_NAME
 C2673 'Q_CAP_C0402-22UF,4V,20%,X6S,CH622KMEB02':;

SECTION_NUMBER 1
 '@T6G_MB_LIB.T6G(SCH_1):PAGE74_I18@PURE_QUANTA.Q_CAP(CHIPS)':
 C_PATH='@t6g_mb_lib.t6g(sch_1):page74_i18@pure_quanta.q_cap(chips)',
 P_PATH='@t6g_mb_lib.t6g(sch_1):page75_i18@pure_quanta.q_cap(chips)',
 PATH='I18',
 DRAWING='@T6G_MB_LIB.T6G(SCH_1):PAGE74',
 TOLERANCE='20%',
 MATERIAL='X6S',
 PHYS_PAGE='75',
 XY='(-4550,3775)',
 ROT='0',
 VER='1',
 PACK_TYPE='C0402',
 LOCATION='C2673',
 CDS_LIB='pure_quanta',
 CDS_PART_NAME='Q_CAP_C0402-22UF,4V,20%,X6S,CH622KMEB02',
 VOLTAGE='4V',
 PART_NUMBER='CH622KMEB02',
 VALUE='22UF',
 PRIM_FILE='./archive_libs/logical/q_cap/chips/chips.prt';

PART_NAME
 C3888 'Q_CAP_C0402-22UF,4V,20%,X6S,CH622KMEB02':;

SECTION_NUMBER 1
 '@T6G_MB_LIB.T6G(SCH_1):PAGE67_I83@PURE_QUANTA.Q_CAP(CHIPS)':
 C_PATH='@t6g_mb_lib.t6g(sch_1):page67_i83@pure_quanta.q_cap(chips)',
 P_PATH='@t6g_mb_lib.t6g(sch_1):page68_i83@pure_quanta.q_cap(chips)',
 PATH='I83',
 DRAWING='@T6G_MB_LIB.T6G(SCH_1):PAGE67',
 TOLERANCE='20%',
 MATERIAL='X6S',
 PHYS_PAGE='68',
 XY='(-13100,4275)',
 ROT='0',
 VER='1',
 PACK_TYPE='C0402',
 LOCATION='C3888',
 CDS_LIB='pure_quanta',
 CDS_PART_NAME='Q_CAP_C0402-22UF,4V,20%,X6S,CH622KMEB02',
 VOLTAGE='4V',
 PART_NUMBER='CH622KMEB02',
 VALUE='22UF',
 PRIM_FILE='./archive_libs/logical/q_cap/chips/chips.prt';

PART_NAME
 C3889 'Q_CAP_C0402-22UF,4V,20%,X6S,CH622KMEB02':;

SECTION_NUMBER 1
 '@T6G_MB_LIB.T6G(SCH_1):PAGE67_I86@PURE_QUANTA.Q_CAP(CHIPS)':
 C_PATH='@t6g_mb_lib.t6g(sch_1):page67_i86@pure_quanta.q_cap(chips)',
 P_PATH='@t6g_mb_lib.t6g(sch_1):page68_i86@pure_quanta.q_cap(chips)',
 PATH='I86',
 DRAWING='@T6G_MB_LIB.T6G(SCH_1):PAGE67',
 TOLERANCE='20%',
 MATERIAL='X6S',
 PHYS_PAGE='68',
 XY='(-12700,4275)',
 ROT='0',
 VER='1',
 PACK_TYPE='C0402',
 LOCATION='C3889',
 CDS_LIB='pure_quanta',
 CDS_PART_NAME='Q_CAP_C0402-22UF,4V,20%,X6S,CH622KMEB02',
 VOLTAGE='4V',
 PART_NUMBER='CH622KMEB02',
 VALUE='22UF',
 PRIM_FILE='./archive_libs/logical/q_cap/chips/chips.prt';

PART_NAME
 C3890 'Q_CAP_C0402-22UF,4V,20%,X6S,CH622KMEB02':;

SECTION_NUMBER 1
 '@T6G_MB_LIB.T6G(SCH_1):PAGE67_I116@PURE_QUANTA.Q_CAP(CHIPS)':
 C_PATH='@t6g_mb_lib.t6g(sch_1):page67_i116@pure_quanta.q_cap(chips)',
 P_PATH='@t6g_mb_lib.t6g(sch_1):page68_i116@pure_quanta.q_cap(chips)',
 PATH='I116',
 DRAWING='@T6G_MB_LIB.T6G(SCH_1):PAGE67',
 TOLERANCE='20%',
 MATERIAL='X6S',
 PHYS_PAGE='68',
 XY='(-12225,1600)',
 ROT='0',
 VER='1',
 PACK_TYPE='C0402',
 LOCATION='C3890',
 CDS_LIB='pure_quanta',
 CDS_PART_NAME='Q_CAP_C0402-22UF,4V,20%,X6S,CH622KMEB02',
 VOLTAGE='4V',
 PART_NUMBER='CH622KMEB02',
 VALUE='22UF',
 PRIM_FILE='./archive_libs/logical/q_cap/chips/chips.prt';

PART_NAME
 C3891 'Q_CAP_C0402-22UF,4V,20%,X6S,CH622KMEB02':;

SECTION_NUMBER 1
 '@T6G_MB_LIB.T6G(SCH_1):PAGE67_I117@PURE_QUANTA.Q_CAP(CHIPS)':
 C_PATH='@t6g_mb_lib.t6g(sch_1):page67_i117@pure_quanta.q_cap(chips)',
 P_PATH='@t6g_mb_lib.t6g(sch_1):page68_i117@pure_quanta.q_cap(chips)',
 PATH='I117',
 DRAWING='@T6G_MB_LIB.T6G(SCH_1):PAGE67',
 TOLERANCE='20%',
 MATERIAL='X6S',
 PHYS_PAGE='68',
 XY='(-11775,1600)',
 ROT='0',
 VER='1',
 PACK_TYPE='C0402',
 LOCATION='C3891',
 CDS_LIB='pure_quanta',
 CDS_PART_NAME='Q_CAP_C0402-22UF,4V,20%,X6S,CH622KMEB02',
 VOLTAGE='4V',
 PART_NUMBER='CH622KMEB02',
 VALUE='22UF',
 PRIM_FILE='./archive_libs/logical/q_cap/chips/chips.prt';

PART_NAME
 C3892 'Q_CAP_C0402-22UF,4V,20%,X6S,CH622KMEB02':;

SECTION_NUMBER 1
 '@T6G_MB_LIB.T6G(SCH_1):PAGE67_I118@PURE_QUANTA.Q_CAP(CHIPS)':
 C_PATH='@t6g_mb_lib.t6g(sch_1):page67_i118@pure_quanta.q_cap(chips)',
 P_PATH='@t6g_mb_lib.t6g(sch_1):page68_i118@pure_quanta.q_cap(chips)',
 PATH='I118',
 DRAWING='@T6G_MB_LIB.T6G(SCH_1):PAGE67',
 TOLERANCE='20%',
 MATERIAL='X6S',
 PHYS_PAGE='68',
 XY='(-11325,1600)',
 ROT='0',
 VER='1',
 PACK_TYPE='C0402',
 LOCATION='C3892',
 CDS_LIB='pure_quanta',
 CDS_PART_NAME='Q_CAP_C0402-22UF,4V,20%,X6S,CH622KMEB02',
 VOLTAGE='4V',
 PART_NUMBER='CH622KMEB02',
 VALUE='22UF',
 PRIM_FILE='./archive_libs/logical/q_cap/chips/chips.prt';

PART_NAME
 C3893 'Q_CAP_C0402-22UF,4V,20%,X6S,CH622KMEB02':;

SECTION_NUMBER 1
 '@T6G_MB_LIB.T6G(SCH_1):PAGE67_I120@PURE_QUANTA.Q_CAP(CHIPS)':
 C_PATH='@t6g_mb_lib.t6g(sch_1):page67_i120@pure_quanta.q_cap(chips)',
 P_PATH='@t6g_mb_lib.t6g(sch_1):page68_i120@pure_quanta.q_cap(chips)',
 PATH='I120',
 DRAWING='@T6G_MB_LIB.T6G(SCH_1):PAGE67',
 TOLERANCE='20%',
 MATERIAL='X6S',
 PHYS_PAGE='68',
 XY='(-10875,1600)',
 ROT='0',
 VER='1',
 PACK_TYPE='C0402',
 LOCATION='C3893',
 CDS_LIB='pure_quanta',
 CDS_PART_NAME='Q_CAP_C0402-22UF,4V,20%,X6S,CH622KMEB02',
 VOLTAGE='4V',
 PART_NUMBER='CH622KMEB02',
 VALUE='22UF',
 PRIM_FILE='./archive_libs/logical/q_cap/chips/chips.prt';

PART_NAME
 C3894 'Q_CAP_C0402-22UF,4V,20%,X6S,CH622KMEB02':;

SECTION_NUMBER 1
 '@T6G_MB_LIB.T6G(SCH_1):PAGE67_I101@PURE_QUANTA.Q_CAP(CHIPS)':
 C_PATH='@t6g_mb_lib.t6g(sch_1):page67_i101@pure_quanta.q_cap(chips)',
 P_PATH='@t6g_mb_lib.t6g(sch_1):page68_i101@pure_quanta.q_cap(chips)',
 PATH='I101',
 DRAWING='@T6G_MB_LIB.T6G(SCH_1):PAGE67',
 TOLERANCE='20%',
 MATERIAL='X6S',
 PHYS_PAGE='68',
 XY='(-9975,5050)',
 ROT='0',
 VER='1',
 PACK_TYPE='C0402',
 LOCATION='C3894',
 CDS_LIB='pure_quanta',
 CDS_PART_NAME='Q_CAP_C0402-22UF,4V,20%,X6S,CH622KMEB02',
 VOLTAGE='4V',
 PART_NUMBER='CH622KMEB02',
 VALUE='22UF',
 PRIM_FILE='./archive_libs/logical/q_cap/chips/chips.prt';

PART_NAME
 C3895 'Q_CAP_C0402-22UF,4V,20%,X6S,CH622KMEB02':;

SECTION_NUMBER 1
 '@T6G_MB_LIB.T6G(SCH_1):PAGE67_I102@PURE_QUANTA.Q_CAP(CHIPS)':
 C_PATH='@t6g_mb_lib.t6g(sch_1):page67_i102@pure_quanta.q_cap(chips)',
 P_PATH='@t6g_mb_lib.t6g(sch_1):page68_i102@pure_quanta.q_cap(chips)',
 PATH='I102',
 DRAWING='@T6G_MB_LIB.T6G(SCH_1):PAGE67',
 TOLERANCE='20%',
 MATERIAL='X6S',
 PHYS_PAGE='68',
 XY='(-9525,5050)',
 ROT='0',
 VER='1',
 PACK_TYPE='C0402',
 LOCATION='C3895',
 CDS_LIB='pure_quanta',
 CDS_PART_NAME='Q_CAP_C0402-22UF,4V,20%,X6S,CH622KMEB02',
 VOLTAGE='4V',
 PART_NUMBER='CH622KMEB02',
 VALUE='22UF',
 PRIM_FILE='./archive_libs/logical/q_cap/chips/chips.prt';

PART_NAME
 C3896 'Q_CAP_C0402-22UF,4V,20%,X6S,CH622KMEB02':;

SECTION_NUMBER 1
 '@T6G_MB_LIB.T6G(SCH_1):PAGE67_I106@PURE_QUANTA.Q_CAP(CHIPS)':
 C_PATH='@t6g_mb_lib.t6g(sch_1):page67_i106@pure_quanta.q_cap(chips)',
 P_PATH='@t6g_mb_lib.t6g(sch_1):page68_i106@pure_quanta.q_cap(chips)',
 PATH='I106',
 DRAWING='@T6G_MB_LIB.T6G(SCH_1):PAGE67',
 TOLERANCE='20%',
 MATERIAL='X6S',
 PHYS_PAGE='68',
 XY='(-9125,5050)',
 ROT='0',
 VER='1',
 PACK_TYPE='C0402',
 LOCATION='C3896',
 CDS_LIB='pure_quanta',
 CDS_PART_NAME='Q_CAP_C0402-22UF,4V,20%,X6S,CH622KMEB02',
 VOLTAGE='4V',
 PART_NUMBER='CH622KMEB02',
 VALUE='22UF',
 PRIM_FILE='./archive_libs/logical/q_cap/chips/chips.prt';

PART_NAME
 C3897 'Q_CAP_C0402-22UF,4V,20%,X6S,CH622KMEB02':;

SECTION_NUMBER 1
 '@T6G_MB_LIB.T6G(SCH_1):PAGE67_I134@PURE_QUANTA.Q_CAP(CHIPS)':
 C_PATH='@t6g_mb_lib.t6g(sch_1):page67_i134@pure_quanta.q_cap(chips)',
 P_PATH='@t6g_mb_lib.t6g(sch_1):page68_i134@pure_quanta.q_cap(chips)',
 PATH='I134',
 DRAWING='@T6G_MB_LIB.T6G(SCH_1):PAGE67',
 TOLERANCE='20%',
 MATERIAL='X6S',
 PHYS_PAGE='68',
 XY='(-7250,4200)',
 ROT='0',
 VER='1',
 PACK_TYPE='C0402',
 LOCATION='C3897',
 CDS_LIB='pure_quanta',
 CDS_PART_NAME='Q_CAP_C0402-22UF,4V,20%,X6S,CH622KMEB02',
 VOLTAGE='4V',
 PART_NUMBER='CH622KMEB02',
 VALUE='22UF',
 PRIM_FILE='./archive_libs/logical/q_cap/chips/chips.prt';

PART_NAME
 C3898 'Q_CAP_C0402-22UF,4V,20%,X6S,CH622KMEB02':;

SECTION_NUMBER 1
 '@T6G_MB_LIB.T6G(SCH_1):PAGE67_I141@PURE_QUANTA.Q_CAP(CHIPS)':
 C_PATH='@t6g_mb_lib.t6g(sch_1):page67_i141@pure_quanta.q_cap(chips)',
 P_PATH='@t6g_mb_lib.t6g(sch_1):page68_i141@pure_quanta.q_cap(chips)',
 PATH='I141',
 DRAWING='@T6G_MB_LIB.T6G(SCH_1):PAGE67',
 TOLERANCE='20%',
 MATERIAL='X6S',
 PHYS_PAGE='68',
 XY='(-5950,5950)',
 ROT='0',
 VER='1',
 PACK_TYPE='C0402',
 LOCATION='C3898',
 CDS_LIB='pure_quanta',
 CDS_PART_NAME='Q_CAP_C0402-22UF,4V,20%,X6S,CH622KMEB02',
 VOLTAGE='4V',
 PART_NUMBER='CH622KMEB02',
 VALUE='22UF',
 PRIM_FILE='./archive_libs/logical/q_cap/chips/chips.prt';

PART_NAME
 C3899 'Q_CAP_C0402-22UF,4V,20%,X6S,CH622KMEB02':;

SECTION_NUMBER 1
 '@T6G_MB_LIB.T6G(SCH_1):PAGE67_I143@PURE_QUANTA.Q_CAP(CHIPS)':
 C_PATH='@t6g_mb_lib.t6g(sch_1):page67_i143@pure_quanta.q_cap(chips)',
 P_PATH='@t6g_mb_lib.t6g(sch_1):page68_i143@pure_quanta.q_cap(chips)',
 PATH='I143',
 DRAWING='@T6G_MB_LIB.T6G(SCH_1):PAGE67',
 TOLERANCE='20%',
 MATERIAL='X6S',
 PHYS_PAGE='68',
 XY='(-5500,5950)',
 ROT='0',
 VER='1',
 PACK_TYPE='C0402',
 LOCATION='C3899',
 CDS_LIB='pure_quanta',
 CDS_PART_NAME='Q_CAP_C0402-22UF,4V,20%,X6S,CH622KMEB02',
 VOLTAGE='4V',
 PART_NUMBER='CH622KMEB02',
 VALUE='22UF',
 PRIM_FILE='./archive_libs/logical/q_cap/chips/chips.prt';

PART_NAME
 C3900 'Q_CAP_C0402-22UF,4V,20%,X6S,CH622KMEB02':;

SECTION_NUMBER 1
 '@T6G_MB_LIB.T6G(SCH_1):PAGE71_I5@PURE_QUANTA.Q_CAP(CHIPS)':
 C_PATH='@t6g_mb_lib.t6g(sch_1):page71_i5@pure_quanta.q_cap(chips)',
 P_PATH='@t6g_mb_lib.t6g(sch_1):page72_i5@pure_quanta.q_cap(chips)',
 PATH='I5',
 DRAWING='@T6G_MB_LIB.T6G(SCH_1):PAGE71',
 TOLERANCE='20%',
 MATERIAL='X6S',
 PHYS_PAGE='72',
 XY='(-8525,3375)',
 ROT='0',
 VER='1',
 PACK_TYPE='C0402',
 LOCATION='C3900',
 CDS_LIB='pure_quanta',
 CDS_PART_NAME='Q_CAP_C0402-22UF,4V,20%,X6S,CH622KMEB02',
 VOLTAGE='4V',
 PART_NUMBER='CH622KMEB02',
 VALUE='22UF',
 PRIM_FILE='./archive_libs/logical/q_cap/chips/chips.prt';

PART_NAME
 C3901 'Q_CAP_C0402-22UF,4V,20%,X6S,CH622KMEB02':;

SECTION_NUMBER 1
 '@T6G_MB_LIB.T6G(SCH_1):PAGE71_I23@PURE_QUANTA.Q_CAP(CHIPS)':
 C_PATH='@t6g_mb_lib.t6g(sch_1):page71_i23@pure_quanta.q_cap(chips)',
 P_PATH='@t6g_mb_lib.t6g(sch_1):page72_i23@pure_quanta.q_cap(chips)',
 PATH='I23',
 DRAWING='@T6G_MB_LIB.T6G(SCH_1):PAGE71',
 TOLERANCE='20%',
 MATERIAL='X6S',
 PHYS_PAGE='72',
 XY='(-8075,3375)',
 ROT='0',
 VER='1',
 PACK_TYPE='C0402',
 LOCATION='C3901',
 CDS_LIB='pure_quanta',
 CDS_PART_NAME='Q_CAP_C0402-22UF,4V,20%,X6S,CH622KMEB02',
 VOLTAGE='4V',
 PART_NUMBER='CH622KMEB02',
 VALUE='22UF',
 PRIM_FILE='./archive_libs/logical/q_cap/chips/chips.prt';

PART_NAME
 C3902 'Q_CAP_C0402-22UF,4V,20%,X6S,CH622KMEB02':;

SECTION_NUMBER 1
 '@T6G_MB_LIB.T6G(SCH_1):PAGE71_I12@PURE_QUANTA.Q_CAP(CHIPS)':
 C_PATH='@t6g_mb_lib.t6g(sch_1):page71_i12@pure_quanta.q_cap(chips)',
 P_PATH='@t6g_mb_lib.t6g(sch_1):page72_i12@pure_quanta.q_cap(chips)',
 PATH='I12',
 DRAWING='@T6G_MB_LIB.T6G(SCH_1):PAGE71',
 TOLERANCE='20%',
 MATERIAL='X6S',
 PHYS_PAGE='72',
 XY='(-7600,825)',
 ROT='0',
 VER='1',
 PACK_TYPE='C0402',
 LOCATION='C3902',
 CDS_LIB='pure_quanta',
 CDS_PART_NAME='Q_CAP_C0402-22UF,4V,20%,X6S,CH622KMEB02',
 VOLTAGE='4V',
 PART_NUMBER='CH622KMEB02',
 VALUE='22UF',
 PRIM_FILE='./archive_libs/logical/q_cap/chips/chips.prt';

PART_NAME
 C3903 'Q_CAP_C0402-22UF,4V,20%,X6S,CH622KMEB02':;

SECTION_NUMBER 1
 '@T6G_MB_LIB.T6G(SCH_1):PAGE71_I15@PURE_QUANTA.Q_CAP(CHIPS)':
 C_PATH='@t6g_mb_lib.t6g(sch_1):page71_i15@pure_quanta.q_cap(chips)',
 P_PATH='@t6g_mb_lib.t6g(sch_1):page72_i15@pure_quanta.q_cap(chips)',
 PATH='I15',
 DRAWING='@T6G_MB_LIB.T6G(SCH_1):PAGE71',
 TOLERANCE='20%',
 MATERIAL='X6S',
 PHYS_PAGE='72',
 XY='(-7150,825)',
 ROT='0',
 VER='1',
 PACK_TYPE='C0402',
 LOCATION='C3903',
 CDS_LIB='pure_quanta',
 CDS_PART_NAME='Q_CAP_C0402-22UF,4V,20%,X6S,CH622KMEB02',
 VOLTAGE='4V',
 PART_NUMBER='CH622KMEB02',
 VALUE='22UF',
 PRIM_FILE='./archive_libs/logical/q_cap/chips/chips.prt';

PART_NAME
 C3904 'Q_CAP_C0402-22UF,4V,20%,X6S,CH622KMEB02':;

SECTION_NUMBER 1
 '@T6G_MB_LIB.T6G(SCH_1):PAGE71_I16@PURE_QUANTA.Q_CAP(CHIPS)':
 C_PATH='@t6g_mb_lib.t6g(sch_1):page71_i16@pure_quanta.q_cap(chips)',
 P_PATH='@t6g_mb_lib.t6g(sch_1):page72_i16@pure_quanta.q_cap(chips)',
 PATH='I16',
 DRAWING='@T6G_MB_LIB.T6G(SCH_1):PAGE71',
 TOLERANCE='20%',
 MATERIAL='X6S',
 PHYS_PAGE='72',
 XY='(-6700,825)',
 ROT='0',
 VER='1',
 PACK_TYPE='C0402',
 LOCATION='C3904',
 CDS_LIB='pure_quanta',
 CDS_PART_NAME='Q_CAP_C0402-22UF,4V,20%,X6S,CH622KMEB02',
 VOLTAGE='4V',
 PART_NUMBER='CH622KMEB02',
 VALUE='22UF',
 PRIM_FILE='./archive_libs/logical/q_cap/chips/chips.prt';

PART_NAME
 C3905 'Q_CAP_C0402-22UF,4V,20%,X6S,CH622KMEB02':;

SECTION_NUMBER 1
 '@T6G_MB_LIB.T6G(SCH_1):PAGE71_I18@PURE_QUANTA.Q_CAP(CHIPS)':
 C_PATH='@t6g_mb_lib.t6g(sch_1):page71_i18@pure_quanta.q_cap(chips)',
 P_PATH='@t6g_mb_lib.t6g(sch_1):page72_i18@pure_quanta.q_cap(chips)',
 PATH='I18',
 DRAWING='@T6G_MB_LIB.T6G(SCH_1):PAGE71',
 TOLERANCE='20%',
 MATERIAL='X6S',
 PHYS_PAGE='72',
 XY='(-6250,825)',
 ROT='0',
 VER='1',
 PACK_TYPE='C0402',
 LOCATION='C3905',
 CDS_LIB='pure_quanta',
 CDS_PART_NAME='Q_CAP_C0402-22UF,4V,20%,X6S,CH622KMEB02',
 VOLTAGE='4V',
 PART_NUMBER='CH622KMEB02',
 VALUE='22UF',
 PRIM_FILE='./archive_libs/logical/q_cap/chips/chips.prt';

PART_NAME
 C3906 'Q_CAP_C0402-22UF,4V,20%,X6S,CH622KMEB02':;

SECTION_NUMBER 1
 '@T6G_MB_LIB.T6G(SCH_1):PAGE71_I41@PURE_QUANTA.Q_CAP(CHIPS)':
 C_PATH='@t6g_mb_lib.t6g(sch_1):page71_i41@pure_quanta.q_cap(chips)',
 P_PATH='@t6g_mb_lib.t6g(sch_1):page72_i41@pure_quanta.q_cap(chips)',
 PATH='I41',
 DRAWING='@T6G_MB_LIB.T6G(SCH_1):PAGE71',
 TOLERANCE='20%',
 MATERIAL='X6S',
 PHYS_PAGE='72',
 XY='(-5375,4100)',
 ROT='0',
 VER='1',
 PACK_TYPE='C0402',
 LOCATION='C3906',
 CDS_LIB='pure_quanta',
 CDS_PART_NAME='Q_CAP_C0402-22UF,4V,20%,X6S,CH622KMEB02',
 VOLTAGE='4V',
 PART_NUMBER='CH622KMEB02',
 VALUE='22UF',
 PRIM_FILE='./archive_libs/logical/q_cap/chips/chips.prt';

PART_NAME
 C3907 'Q_CAP_C0402-22UF,4V,20%,X6S,CH622KMEB02':;

SECTION_NUMBER 1
 '@T6G_MB_LIB.T6G(SCH_1):PAGE71_I43@PURE_QUANTA.Q_CAP(CHIPS)':
 C_PATH='@t6g_mb_lib.t6g(sch_1):page71_i43@pure_quanta.q_cap(chips)',
 P_PATH='@t6g_mb_lib.t6g(sch_1):page72_i43@pure_quanta.q_cap(chips)',
 PATH='I43',
 DRAWING='@T6G_MB_LIB.T6G(SCH_1):PAGE71',
 TOLERANCE='20%',
 MATERIAL='X6S',
 PHYS_PAGE='72',
 XY='(-4925,4100)',
 ROT='0',
 VER='1',
 PACK_TYPE='C0402',
 LOCATION='C3907',
 CDS_LIB='pure_quanta',
 CDS_PART_NAME='Q_CAP_C0402-22UF,4V,20%,X6S,CH622KMEB02',
 VOLTAGE='4V',
 PART_NUMBER='CH622KMEB02',
 VALUE='22UF',
 PRIM_FILE='./archive_libs/logical/q_cap/chips/chips.prt';

PART_NAME
 C3908 'Q_CAP_C0402-22UF,4V,20%,X6S,CH622KMEB02':;

SECTION_NUMBER 1
 '@T6G_MB_LIB.T6G(SCH_1):PAGE71_I45@PURE_QUANTA.Q_CAP(CHIPS)':
 C_PATH='@t6g_mb_lib.t6g(sch_1):page71_i45@pure_quanta.q_cap(chips)',
 P_PATH='@t6g_mb_lib.t6g(sch_1):page72_i45@pure_quanta.q_cap(chips)',
 PATH='I45',
 DRAWING='@T6G_MB_LIB.T6G(SCH_1):PAGE71',
 TOLERANCE='20%',
 MATERIAL='X6S',
 PHYS_PAGE='72',
 XY='(-4525,4100)',
 ROT='0',
 VER='1',
 PACK_TYPE='C0402',
 LOCATION='C3908',
 CDS_LIB='pure_quanta',
 CDS_PART_NAME='Q_CAP_C0402-22UF,4V,20%,X6S,CH622KMEB02',
 VOLTAGE='4V',
 PART_NUMBER='CH622KMEB02',
 VALUE='22UF',
 PRIM_FILE='./archive_libs/logical/q_cap/chips/chips.prt';

PART_NAME
 C3909 'Q_CAP_C0402-22UF,4V,20%,X6S,CH622KMEB02':;

SECTION_NUMBER 1
 '@T6G_MB_LIB.T6G(SCH_1):PAGE71_I52@PURE_QUANTA.Q_CAP(CHIPS)':
 C_PATH='@t6g_mb_lib.t6g(sch_1):page71_i52@pure_quanta.q_cap(chips)',
 P_PATH='@t6g_mb_lib.t6g(sch_1):page72_i52@pure_quanta.q_cap(chips)',
 PATH='I52',
 DRAWING='@T6G_MB_LIB.T6G(SCH_1):PAGE71',
 TOLERANCE='20%',
 MATERIAL='X6S',
 PHYS_PAGE='72',
 XY='(-2700,3375)',
 ROT='0',
 VER='1',
 PACK_TYPE='C0402',
 LOCATION='C3909',
 CDS_LIB='pure_quanta',
 CDS_PART_NAME='Q_CAP_C0402-22UF,4V,20%,X6S,CH622KMEB02',
 VOLTAGE='4V',
 PART_NUMBER='CH622KMEB02',
 VALUE='22UF',
 PRIM_FILE='./archive_libs/logical/q_cap/chips/chips.prt';

PART_NAME
 C3910 'Q_CAP_C0402-22UF,4V,20%,X6S,CH622KMEB02':;

SECTION_NUMBER 1
 '@T6G_MB_LIB.T6G(SCH_1):PAGE71_I59@PURE_QUANTA.Q_CAP(CHIPS)':
 C_PATH='@t6g_mb_lib.t6g(sch_1):page71_i59@pure_quanta.q_cap(chips)',
 P_PATH='@t6g_mb_lib.t6g(sch_1):page72_i59@pure_quanta.q_cap(chips)',
 PATH='I59',
 DRAWING='@T6G_MB_LIB.T6G(SCH_1):PAGE71',
 TOLERANCE='20%',
 MATERIAL='X6S',
 PHYS_PAGE='72',
 XY='(-1350,4975)',
 ROT='0',
 VER='1',
 PACK_TYPE='C0402',
 LOCATION='C3910',
 CDS_LIB='pure_quanta',
 CDS_PART_NAME='Q_CAP_C0402-22UF,4V,20%,X6S,CH622KMEB02',
 VOLTAGE='4V',
 PART_NUMBER='CH622KMEB02',
 VALUE='22UF',
 PRIM_FILE='./archive_libs/logical/q_cap/chips/chips.prt';

PART_NAME
 C3911 'Q_CAP_C0402-22UF,4V,20%,X6S,CH622KMEB02':;

SECTION_NUMBER 1
 '@T6G_MB_LIB.T6G(SCH_1):PAGE71_I61@PURE_QUANTA.Q_CAP(CHIPS)':
 C_PATH='@t6g_mb_lib.t6g(sch_1):page71_i61@pure_quanta.q_cap(chips)',
 P_PATH='@t6g_mb_lib.t6g(sch_1):page72_i61@pure_quanta.q_cap(chips)',
 PATH='I61',
 DRAWING='@T6G_MB_LIB.T6G(SCH_1):PAGE71',
 TOLERANCE='20%',
 MATERIAL='X6S',
 PHYS_PAGE='72',
 XY='(-900,4975)',
 ROT='0',
 VER='1',
 PACK_TYPE='C0402',
 LOCATION='C3911',
 CDS_LIB='pure_quanta',
 CDS_PART_NAME='Q_CAP_C0402-22UF,4V,20%,X6S,CH622KMEB02',
 VOLTAGE='4V',
 PART_NUMBER='CH622KMEB02',
 VALUE='22UF',
 PRIM_FILE='./archive_libs/logical/q_cap/chips/chips.prt';

PART_NAME
 C3912 'Q_CAP_C0402-22UF,4V,20%,X6S,CH622KMEB02':;

SECTION_NUMBER 1
 '@T6G_MB_LIB.T6G(SCH_1):PAGE73_I1@PURE_QUANTA.Q_CAP(CHIPS)':
 C_PATH='@t6g_mb_lib.t6g(sch_1):page73_i1@pure_quanta.q_cap(chips)',
 P_PATH='@t6g_mb_lib.t6g(sch_1):page74_i1@pure_quanta.q_cap(chips)',
 PATH='I1',
 DRAWING='@T6G_MB_LIB.T6G(SCH_1):PAGE73',
 TOLERANCE='20%',
 MATERIAL='X6S',
 PHYS_PAGE='74',
 XY='(400,1075)',
 ROT='0',
 VER='1',
 PACK_TYPE='C0402',
 LOCATION='C3912',
 CDS_LIB='pure_quanta',
 CDS_PART_NAME='Q_CAP_C0402-22UF,4V,20%,X6S,CH622KMEB02',
 VOLTAGE='4V',
 PART_NUMBER='CH622KMEB02',
 VALUE='22UF',
 PRIM_FILE='./archive_libs/logical/q_cap/chips/chips.prt';

PART_NAME
 C3913 'Q_CAP_C0402-22UF,4V,20%,X6S,CH622KMEB02':;

SECTION_NUMBER 1
 '@T6G_MB_LIB.T6G(SCH_1):PAGE73_I4@PURE_QUANTA.Q_CAP(CHIPS)':
 C_PATH='@t6g_mb_lib.t6g(sch_1):page73_i4@pure_quanta.q_cap(chips)',
 P_PATH='@t6g_mb_lib.t6g(sch_1):page74_i4@pure_quanta.q_cap(chips)',
 PATH='I4',
 DRAWING='@T6G_MB_LIB.T6G(SCH_1):PAGE73',
 TOLERANCE='20%',
 MATERIAL='X6S',
 PHYS_PAGE='74',
 XY='(850,1075)',
 ROT='0',
 VER='1',
 PACK_TYPE='C0402',
 LOCATION='C3913',
 CDS_LIB='pure_quanta',
 CDS_PART_NAME='Q_CAP_C0402-22UF,4V,20%,X6S,CH622KMEB02',
 VOLTAGE='4V',
 PART_NUMBER='CH622KMEB02',
 VALUE='22UF',
 PRIM_FILE='./archive_libs/logical/q_cap/chips/chips.prt';

PART_NAME
 C3914 'Q_CAP_C0402-22UF,4V,20%,X6S,CH622KMEB02':;

SECTION_NUMBER 1
 '@T6G_MB_LIB.T6G(SCH_1):PAGE73_I6@PURE_QUANTA.Q_CAP(CHIPS)':
 C_PATH='@t6g_mb_lib.t6g(sch_1):page73_i6@pure_quanta.q_cap(chips)',
 P_PATH='@t6g_mb_lib.t6g(sch_1):page74_i6@pure_quanta.q_cap(chips)',
 PATH='I6',
 DRAWING='@T6G_MB_LIB.T6G(SCH_1):PAGE73',
 TOLERANCE='20%',
 MATERIAL='X6S',
 PHYS_PAGE='74',
 XY='(1300,1075)',
 ROT='0',
 VER='1',
 PACK_TYPE='C0402',
 LOCATION='C3914',
 CDS_LIB='pure_quanta',
 CDS_PART_NAME='Q_CAP_C0402-22UF,4V,20%,X6S,CH622KMEB02',
 VOLTAGE='4V',
 PART_NUMBER='CH622KMEB02',
 VALUE='22UF',
 PRIM_FILE='./archive_libs/logical/q_cap/chips/chips.prt';

PART_NAME
 C3915 'Q_CAP_C0402-22UF,4V,20%,X6S,CH622KMEB02':;

SECTION_NUMBER 1
 '@T6G_MB_LIB.T6G(SCH_1):PAGE73_I8@PURE_QUANTA.Q_CAP(CHIPS)':
 C_PATH='@t6g_mb_lib.t6g(sch_1):page73_i8@pure_quanta.q_cap(chips)',
 P_PATH='@t6g_mb_lib.t6g(sch_1):page74_i8@pure_quanta.q_cap(chips)',
 PATH='I8',
 DRAWING='@T6G_MB_LIB.T6G(SCH_1):PAGE73',
 TOLERANCE='20%',
 MATERIAL='X6S',
 PHYS_PAGE='74',
 XY='(1750,1075)',
 ROT='0',
 VER='1',
 PACK_TYPE='C0402',
 LOCATION='C3915',
 CDS_LIB='pure_quanta',
 CDS_PART_NAME='Q_CAP_C0402-22UF,4V,20%,X6S,CH622KMEB02',
 VOLTAGE='4V',
 PART_NUMBER='CH622KMEB02',
 VALUE='22UF',
 PRIM_FILE='./archive_libs/logical/q_cap/chips/chips.prt';

PART_NAME
 C3916 'Q_CAP_C0402-22UF,4V,20%,X6S,CH622KMEB02':;

SECTION_NUMBER 1
 '@T6G_MB_LIB.T6G(SCH_1):PAGE73_I25@PURE_QUANTA.Q_CAP(CHIPS)':
 C_PATH='@t6g_mb_lib.t6g(sch_1):page73_i25@pure_quanta.q_cap(chips)',
 P_PATH='@t6g_mb_lib.t6g(sch_1):page74_i25@pure_quanta.q_cap(chips)',
 PATH='I25',
 DRAWING='@T6G_MB_LIB.T6G(SCH_1):PAGE73',
 TOLERANCE='20%',
 MATERIAL='X6S',
 PHYS_PAGE='74',
 XY='(2200,1075)',
 ROT='0',
 VER='1',
 PACK_TYPE='C0402',
 LOCATION='C3916',
 CDS_LIB='pure_quanta',
 CDS_PART_NAME='Q_CAP_C0402-22UF,4V,20%,X6S,CH622KMEB02',
 VOLTAGE='4V',
 PART_NUMBER='CH622KMEB02',
 VALUE='22UF',
 PRIM_FILE='./archive_libs/logical/q_cap/chips/chips.prt';

PART_NAME
 C3917 'Q_CAP_C0402-22UF,4V,20%,X6S,CH622KMEB02':;

SECTION_NUMBER 1
 '@T6G_MB_LIB.T6G(SCH_1):PAGE73_I27@PURE_QUANTA.Q_CAP(CHIPS)':
 C_PATH='@t6g_mb_lib.t6g(sch_1):page73_i27@pure_quanta.q_cap(chips)',
 P_PATH='@t6g_mb_lib.t6g(sch_1):page74_i27@pure_quanta.q_cap(chips)',
 PATH='I27',
 DRAWING='@T6G_MB_LIB.T6G(SCH_1):PAGE73',
 TOLERANCE='20%',
 MATERIAL='X6S',
 PHYS_PAGE='74',
 XY='(2650,1075)',
 ROT='0',
 VER='1',
 PACK_TYPE='C0402',
 LOCATION='C3917',
 CDS_LIB='pure_quanta',
 CDS_PART_NAME='Q_CAP_C0402-22UF,4V,20%,X6S,CH622KMEB02',
 VOLTAGE='4V',
 PART_NUMBER='CH622KMEB02',
 VALUE='22UF',
 PRIM_FILE='./archive_libs/logical/q_cap/chips/chips.prt';

PART_NAME
 C3918 'Q_CAP_C0402-22UF,4V,20%,X6S,CH622KMEB02':;

SECTION_NUMBER 1
 '@T6G_MB_LIB.T6G(SCH_1):PAGE73_I30@PURE_QUANTA.Q_CAP(CHIPS)':
 C_PATH='@t6g_mb_lib.t6g(sch_1):page73_i30@pure_quanta.q_cap(chips)',
 P_PATH='@t6g_mb_lib.t6g(sch_1):page74_i30@pure_quanta.q_cap(chips)',
 PATH='I30',
 DRAWING='@T6G_MB_LIB.T6G(SCH_1):PAGE73',
 TOLERANCE='20%',
 MATERIAL='X6S',
 PHYS_PAGE='74',
 XY='(3100,1075)',
 ROT='0',
 VER='1',
 PACK_TYPE='C0402',
 LOCATION='C3918',
 CDS_LIB='pure_quanta',
 CDS_PART_NAME='Q_CAP_C0402-22UF,4V,20%,X6S,CH622KMEB02',
 VOLTAGE='4V',
 PART_NUMBER='CH622KMEB02',
 VALUE='22UF',
 PRIM_FILE='./archive_libs/logical/q_cap/chips/chips.prt';

PART_NAME
 C3919 'Q_CAP_C0402-22UF,4V,20%,X6S,CH622KMEB02':;

SECTION_NUMBER 1
 '@T6G_MB_LIB.T6G(SCH_1):PAGE73_I77@PURE_QUANTA.Q_CAP(CHIPS)':
 C_PATH='@t6g_mb_lib.t6g(sch_1):page73_i77@pure_quanta.q_cap(chips)',
 P_PATH='@t6g_mb_lib.t6g(sch_1):page74_i77@pure_quanta.q_cap(chips)',
 PATH='I77',
 DRAWING='@T6G_MB_LIB.T6G(SCH_1):PAGE73',
 TOLERANCE='20%',
 MATERIAL='X6S',
 PHYS_PAGE='74',
 XY='(5000,775)',
 ROT='0',
 VER='1',
 PACK_TYPE='C0402',
 LOCATION='C3919',
 CDS_LIB='pure_quanta',
 CDS_PART_NAME='Q_CAP_C0402-22UF,4V,20%,X6S,CH622KMEB02',
 VOLTAGE='4V',
 PART_NUMBER='CH622KMEB02',
 VALUE='22UF',
 PRIM_FILE='./archive_libs/logical/q_cap/chips/chips.prt';

PART_NAME
 C3920 'Q_CAP_C0402-22UF,4V,20%,X6S,CH622KMEB02':;

SECTION_NUMBER 1
 '@T6G_MB_LIB.T6G(SCH_1):PAGE73_I84@PURE_QUANTA.Q_CAP(CHIPS)':
 C_PATH='@t6g_mb_lib.t6g(sch_1):page73_i84@pure_quanta.q_cap(chips)',
 P_PATH='@t6g_mb_lib.t6g(sch_1):page74_i84@pure_quanta.q_cap(chips)',
 PATH='I84',
 DRAWING='@T6G_MB_LIB.T6G(SCH_1):PAGE73',
 TOLERANCE='20%',
 MATERIAL='X6S',
 PHYS_PAGE='74',
 XY='(5450,775)',
 ROT='0',
 VER='1',
 PACK_TYPE='C0402',
 LOCATION='C3920',
 CDS_LIB='pure_quanta',
 CDS_PART_NAME='Q_CAP_C0402-22UF,4V,20%,X6S,CH622KMEB02',
 VOLTAGE='4V',
 PART_NUMBER='CH622KMEB02',
 VALUE='22UF',
 PRIM_FILE='./archive_libs/logical/q_cap/chips/chips.prt';

PART_NAME
 C3921 'Q_CAP_C0402-22UF,4V,20%,X6S,CH622KMEB02':;

SECTION_NUMBER 1
 '@T6G_MB_LIB.T6G(SCH_1):PAGE73_I155@PURE_QUANTA.Q_CAP(CHIPS)':
 C_PATH='@t6g_mb_lib.t6g(sch_1):page73_i155@pure_quanta.q_cap(chips)',
 P_PATH='@t6g_mb_lib.t6g(sch_1):page74_i155@pure_quanta.q_cap(chips)',
 PATH='I155',
 DRAWING='@T6G_MB_LIB.T6G(SCH_1):PAGE73',
 TOLERANCE='20%',
 MATERIAL='X6S',
 PHYS_PAGE='74',
 XY='(8600,1375)',
 ROT='0',
 VER='1',
 PACK_TYPE='C0402',
 LOCATION='C3921',
 CDS_LIB='pure_quanta',
 CDS_PART_NAME='Q_CAP_C0402-22UF,4V,20%,X6S,CH622KMEB02',
 VOLTAGE='4V',
 PART_NUMBER='CH622KMEB02',
 VALUE='22UF',
 PRIM_FILE='./archive_libs/logical/q_cap/chips/chips.prt';

PART_NAME
 C3922 'Q_CAP_C0402-22UF,4V,20%,X6S,CH622KMEB02':;

SECTION_NUMBER 1
 '@T6G_MB_LIB.T6G(SCH_1):PAGE73_I157@PURE_QUANTA.Q_CAP(CHIPS)':
 C_PATH='@t6g_mb_lib.t6g(sch_1):page73_i157@pure_quanta.q_cap(chips)',
 P_PATH='@t6g_mb_lib.t6g(sch_1):page74_i157@pure_quanta.q_cap(chips)',
 PATH='I157',
 DRAWING='@T6G_MB_LIB.T6G(SCH_1):PAGE73',
 TOLERANCE='20%',
 MATERIAL='X6S',
 PHYS_PAGE='74',
 XY='(9000,1375)',
 ROT='0',
 VER='1',
 PACK_TYPE='C0402',
 LOCATION='C3922',
 CDS_LIB='pure_quanta',
 CDS_PART_NAME='Q_CAP_C0402-22UF,4V,20%,X6S,CH622KMEB02',
 VOLTAGE='4V',
 PART_NUMBER='CH622KMEB02',
 VALUE='22UF',
 PRIM_FILE='./archive_libs/logical/q_cap/chips/chips.prt';

PART_NAME
 C3925 'Q_CAP_C0402-22UF,4V,20%,X6S,CH622KMEB02':;

SECTION_NUMBER 1
 '@T6G_MB_LIB.T6G(SCH_1):PAGE69_I1@PURE_QUANTA.Q_CAP(CHIPS)':
 C_PATH='@t6g_mb_lib.t6g(sch_1):page69_i1@pure_quanta.q_cap(chips)',
 P_PATH='@t6g_mb_lib.t6g(sch_1):page70_i1@pure_quanta.q_cap(chips)',
 PATH='I1',
 DRAWING='@T6G_MB_LIB.T6G(SCH_1):PAGE69',
 TOLERANCE='20%',
 MATERIAL='X6S',
 PHYS_PAGE='70',
 XY='(-9075,875)',
 ROT='0',
 VER='1',
 PACK_TYPE='C0402',
 LOCATION='C3925',
 CDS_LIB='pure_quanta',
 CDS_PART_NAME='Q_CAP_C0402-22UF,4V,20%,X6S,CH622KMEB02',
 VOLTAGE='4V',
 PART_NUMBER='CH622KMEB02',
 VALUE='22UF',
 PRIM_FILE='./archive_libs/logical/q_cap/chips/chips.prt';

PART_NAME
 C3926 'Q_CAP_C0402-22UF,4V,20%,X6S,CH622KMEB02':;

SECTION_NUMBER 1
 '@T6G_MB_LIB.T6G(SCH_1):PAGE69_I3@PURE_QUANTA.Q_CAP(CHIPS)':
 C_PATH='@t6g_mb_lib.t6g(sch_1):page69_i3@pure_quanta.q_cap(chips)',
 P_PATH='@t6g_mb_lib.t6g(sch_1):page70_i3@pure_quanta.q_cap(chips)',
 PATH='I3',
 DRAWING='@T6G_MB_LIB.T6G(SCH_1):PAGE69',
 TOLERANCE='20%',
 MATERIAL='X6S',
 PHYS_PAGE='70',
 XY='(-8625,875)',
 ROT='0',
 VER='1',
 PACK_TYPE='C0402',
 LOCATION='C3926',
 CDS_LIB='pure_quanta',
 CDS_PART_NAME='Q_CAP_C0402-22UF,4V,20%,X6S,CH622KMEB02',
 VOLTAGE='4V',
 PART_NUMBER='CH622KMEB02',
 VALUE='22UF',
 PRIM_FILE='./archive_libs/logical/q_cap/chips/chips.prt';

PART_NAME
 C3927 'Q_CAP_C0402-22UF,4V,20%,X6S,CH622KMEB02':;

SECTION_NUMBER 1
 '@T6G_MB_LIB.T6G(SCH_1):PAGE69_I25@PURE_QUANTA.Q_CAP(CHIPS)':
 C_PATH='@t6g_mb_lib.t6g(sch_1):page69_i25@pure_quanta.q_cap(chips)',
 P_PATH='@t6g_mb_lib.t6g(sch_1):page70_i25@pure_quanta.q_cap(chips)',
 PATH='I25',
 DRAWING='@T6G_MB_LIB.T6G(SCH_1):PAGE69',
 TOLERANCE='20%',
 MATERIAL='X6S',
 PHYS_PAGE='70',
 XY='(-8175,875)',
 ROT='0',
 VER='1',
 PACK_TYPE='C0402',
 LOCATION='C3927',
 CDS_LIB='pure_quanta',
 CDS_PART_NAME='Q_CAP_C0402-22UF,4V,20%,X6S,CH622KMEB02',
 VOLTAGE='4V',
 PART_NUMBER='CH622KMEB02',
 VALUE='22UF',
 PRIM_FILE='./archive_libs/logical/q_cap/chips/chips.prt';

PART_NAME
 C3928 'Q_CAP_C0402-22UF,4V,20%,X6S,CH622KMEB02':;

SECTION_NUMBER 1
 '@T6G_MB_LIB.T6G(SCH_1):PAGE69_I26@PURE_QUANTA.Q_CAP(CHIPS)':
 C_PATH='@t6g_mb_lib.t6g(sch_1):page69_i26@pure_quanta.q_cap(chips)',
 P_PATH='@t6g_mb_lib.t6g(sch_1):page70_i26@pure_quanta.q_cap(chips)',
 PATH='I26',
 DRAWING='@T6G_MB_LIB.T6G(SCH_1):PAGE69',
 TOLERANCE='20%',
 MATERIAL='X6S',
 PHYS_PAGE='70',
 XY='(-7725,875)',
 ROT='0',
 VER='1',
 PACK_TYPE='C0402',
 LOCATION='C3928',
 CDS_LIB='pure_quanta',
 CDS_PART_NAME='Q_CAP_C0402-22UF,4V,20%,X6S,CH622KMEB02',
 VOLTAGE='4V',
 PART_NUMBER='CH622KMEB02',
 VALUE='22UF',
 PRIM_FILE='./archive_libs/logical/q_cap/chips/chips.prt';

PART_NAME
 C3929 'Q_CAP_C0402-22UF,4V,20%,X6S,CH622KMEB02':;

SECTION_NUMBER 1
 '@T6G_MB_LIB.T6G(SCH_1):PAGE69_I27@PURE_QUANTA.Q_CAP(CHIPS)':
 C_PATH='@t6g_mb_lib.t6g(sch_1):page69_i27@pure_quanta.q_cap(chips)',
 P_PATH='@t6g_mb_lib.t6g(sch_1):page70_i27@pure_quanta.q_cap(chips)',
 PATH='I27',
 DRAWING='@T6G_MB_LIB.T6G(SCH_1):PAGE69',
 TOLERANCE='20%',
 MATERIAL='X6S',
 PHYS_PAGE='70',
 XY='(-7275,875)',
 ROT='0',
 VER='1',
 PACK_TYPE='C0402',
 LOCATION='C3929',
 CDS_LIB='pure_quanta',
 CDS_PART_NAME='Q_CAP_C0402-22UF,4V,20%,X6S,CH622KMEB02',
 VOLTAGE='4V',
 PART_NUMBER='CH622KMEB02',
 VALUE='22UF',
 PRIM_FILE='./archive_libs/logical/q_cap/chips/chips.prt';

PART_NAME
 C3930 'Q_CAP_C0402-22UF,4V,20%,X6S,CH622KMEB02':;

SECTION_NUMBER 1
 '@T6G_MB_LIB.T6G(SCH_1):PAGE69_I31@PURE_QUANTA.Q_CAP(CHIPS)':
 C_PATH='@t6g_mb_lib.t6g(sch_1):page69_i31@pure_quanta.q_cap(chips)',
 P_PATH='@t6g_mb_lib.t6g(sch_1):page70_i31@pure_quanta.q_cap(chips)',
 PATH='I31',
 DRAWING='@T6G_MB_LIB.T6G(SCH_1):PAGE69',
 TOLERANCE='20%',
 MATERIAL='X6S',
 PHYS_PAGE='70',
 XY='(-6825,875)',
 ROT='0',
 VER='1',
 PACK_TYPE='C0402',
 LOCATION='C3930',
 CDS_LIB='pure_quanta',
 CDS_PART_NAME='Q_CAP_C0402-22UF,4V,20%,X6S,CH622KMEB02',
 VOLTAGE='4V',
 PART_NUMBER='CH622KMEB02',
 VALUE='22UF',
 PRIM_FILE='./archive_libs/logical/q_cap/chips/chips.prt';

PART_NAME
 C3931 'Q_CAP_C0402-22UF,4V,20%,X6S,CH622KMEB02':;

SECTION_NUMBER 1
 '@T6G_MB_LIB.T6G(SCH_1):PAGE69_I33@PURE_QUANTA.Q_CAP(CHIPS)':
 C_PATH='@t6g_mb_lib.t6g(sch_1):page69_i33@pure_quanta.q_cap(chips)',
 P_PATH='@t6g_mb_lib.t6g(sch_1):page70_i33@pure_quanta.q_cap(chips)',
 PATH='I33',
 DRAWING='@T6G_MB_LIB.T6G(SCH_1):PAGE69',
 TOLERANCE='20%',
 MATERIAL='X6S',
 PHYS_PAGE='70',
 XY='(-6375,875)',
 ROT='0',
 VER='1',
 PACK_TYPE='C0402',
 LOCATION='C3931',
 CDS_LIB='pure_quanta',
 CDS_PART_NAME='Q_CAP_C0402-22UF,4V,20%,X6S,CH622KMEB02',
 VOLTAGE='4V',
 PART_NUMBER='CH622KMEB02',
 VALUE='22UF',
 PRIM_FILE='./archive_libs/logical/q_cap/chips/chips.prt';

PART_NAME
 C3932 'Q_CAP_C0402-22UF,4V,20%,X6S,CH622KMEB02':;

SECTION_NUMBER 1
 '@T6G_MB_LIB.T6G(SCH_1):PAGE69_I53@PURE_QUANTA.Q_CAP(CHIPS)':
 C_PATH='@t6g_mb_lib.t6g(sch_1):page69_i53@pure_quanta.q_cap(chips)',
 P_PATH='@t6g_mb_lib.t6g(sch_1):page70_i53@pure_quanta.q_cap(chips)',
 PATH='I53',
 DRAWING='@T6G_MB_LIB.T6G(SCH_1):PAGE69',
 TOLERANCE='20%',
 MATERIAL='X6S',
 PHYS_PAGE='70',
 XY='(-4500,800)',
 ROT='0',
 VER='1',
 PACK_TYPE='C0402',
 LOCATION='C3932',
 CDS_LIB='pure_quanta',
 CDS_PART_NAME='Q_CAP_C0402-22UF,4V,20%,X6S,CH622KMEB02',
 VOLTAGE='4V',
 PART_NUMBER='CH622KMEB02',
 VALUE='22UF',
 PRIM_FILE='./archive_libs/logical/q_cap/chips/chips.prt';

PART_NAME
 C3933 'Q_CAP_C0402-22UF,4V,20%,X6S,CH622KMEB02':;

SECTION_NUMBER 1
 '@T6G_MB_LIB.T6G(SCH_1):PAGE69_I111@PURE_QUANTA.Q_CAP(CHIPS)':
 C_PATH='@t6g_mb_lib.t6g(sch_1):page69_i111@pure_quanta.q_cap(chips)',
 P_PATH='@t6g_mb_lib.t6g(sch_1):page70_i111@pure_quanta.q_cap(chips)',
 PATH='I111',
 DRAWING='@T6G_MB_LIB.T6G(SCH_1):PAGE69',
 TOLERANCE='20%',
 MATERIAL='X6S',
 PHYS_PAGE='70',
 XY='(-4050,800)',
 ROT='0',
 VER='1',
 PACK_TYPE='C0402',
 LOCATION='C3933',
 CDS_LIB='pure_quanta',
 CDS_PART_NAME='Q_CAP_C0402-22UF,4V,20%,X6S,CH622KMEB02',
 VOLTAGE='4V',
 PART_NUMBER='CH622KMEB02',
 VALUE='22UF',
 PRIM_FILE='./archive_libs/logical/q_cap/chips/chips.prt';

PART_NAME
 C3934 'Q_CAP_C0402-22UF,4V,20%,X6S,CH622KMEB02':;

SECTION_NUMBER 1
 '@T6G_MB_LIB.T6G(SCH_1):PAGE69_I138@PURE_QUANTA.Q_CAP(CHIPS)':
 C_PATH='@t6g_mb_lib.t6g(sch_1):page69_i138@pure_quanta.q_cap(chips)',
 P_PATH='@t6g_mb_lib.t6g(sch_1):page70_i138@pure_quanta.q_cap(chips)',
 PATH='I138',
 DRAWING='@T6G_MB_LIB.T6G(SCH_1):PAGE69',
 TOLERANCE='20%',
 MATERIAL='X6S',
 PHYS_PAGE='70',
 XY='(-900,1400)',
 ROT='0',
 VER='1',
 PACK_TYPE='C0402',
 LOCATION='C3934',
 CDS_LIB='pure_quanta',
 CDS_PART_NAME='Q_CAP_C0402-22UF,4V,20%,X6S,CH622KMEB02',
 VOLTAGE='4V',
 PART_NUMBER='CH622KMEB02',
 VALUE='22UF',
 PRIM_FILE='./archive_libs/logical/q_cap/chips/chips.prt';

PART_NAME
 C3935 'Q_CAP_C0402-22UF,4V,20%,X6S,CH622KMEB02':;

SECTION_NUMBER 1
 '@T6G_MB_LIB.T6G(SCH_1):PAGE69_I140@PURE_QUANTA.Q_CAP(CHIPS)':
 C_PATH='@t6g_mb_lib.t6g(sch_1):page69_i140@pure_quanta.q_cap(chips)',
 P_PATH='@t6g_mb_lib.t6g(sch_1):page70_i140@pure_quanta.q_cap(chips)',
 PATH='I140',
 DRAWING='@T6G_MB_LIB.T6G(SCH_1):PAGE69',
 TOLERANCE='20%',
 MATERIAL='X6S',
 PHYS_PAGE='70',
 XY='(-500,1400)',
 ROT='0',
 VER='1',
 PACK_TYPE='C0402',
 LOCATION='C3935',
 CDS_LIB='pure_quanta',
 CDS_PART_NAME='Q_CAP_C0402-22UF,4V,20%,X6S,CH622KMEB02',
 VOLTAGE='4V',
 PART_NUMBER='CH622KMEB02',
 VALUE='22UF',
 PRIM_FILE='./archive_libs/logical/q_cap/chips/chips.prt';

PART_NAME
 C4178 'Q_CAP_C0402-22UF,4V,20%,X6S,CH622KMEB02':;

SECTION_NUMBER 1
 '@T6G_MB_LIB.T6G(SCH_1):PAGE68_I47@PURE_QUANTA.Q_CAP(CHIPS)':
 C_PATH='@t6g_mb_lib.t6g(sch_1):page68_i47@pure_quanta.q_cap(chips)',
 P_PATH='@t6g_mb_lib.t6g(sch_1):page69_i47@pure_quanta.q_cap(chips)',
 PATH='I47',
 DRAWING='@T6G_MB_LIB.T6G(SCH_1):PAGE68',
 TOLERANCE='20%',
 MATERIAL='X6S',
 PHYS_PAGE='69',
 XY='(-8100,5250)',
 ROT='0',
 VER='1',
 PACK_TYPE='C0402',
 LOCATION='C4178',
 CDS_LIB='pure_quanta',
 CDS_PART_NAME='Q_CAP_C0402-22UF,4V,20%,X6S,CH622KMEB02',
 VOLTAGE='4V',
 PART_NUMBER='CH622KMEB02',
 VALUE='22UF',
 PRIM_FILE='./archive_libs/logical/q_cap/chips/chips.prt';

PART_NAME
 C4179 'Q_CAP_C0402-22UF,4V,20%,X6S,CH622KMEB02':;

SECTION_NUMBER 1
 '@T6G_MB_LIB.T6G(SCH_1):PAGE68_I48@PURE_QUANTA.Q_CAP(CHIPS)':
 C_PATH='@t6g_mb_lib.t6g(sch_1):page68_i48@pure_quanta.q_cap(chips)',
 P_PATH='@t6g_mb_lib.t6g(sch_1):page69_i48@pure_quanta.q_cap(chips)',
 PATH='I48',
 DRAWING='@T6G_MB_LIB.T6G(SCH_1):PAGE68',
 TOLERANCE='20%',
 MATERIAL='X6S',
 PHYS_PAGE='69',
 XY='(-7650,5250)',
 ROT='0',
 VER='1',
 PACK_TYPE='C0402',
 LOCATION='C4179',
 CDS_LIB='pure_quanta',
 CDS_PART_NAME='Q_CAP_C0402-22UF,4V,20%,X6S,CH622KMEB02',
 VOLTAGE='4V',
 PART_NUMBER='CH622KMEB02',
 VALUE='22UF',
 PRIM_FILE='./archive_libs/logical/q_cap/chips/chips.prt';

PART_NAME
 C5000 'Q_CAP_0402-1000PF,50V,5%,X7R,TMP_QCH21006JB10':;

SECTION_NUMBER 1
 '@T6G_MB_LIB.T6G(SCH_1):PAGE34_I124@PURE_QUANTA.Q_CAP(CHIPS)':
 C_PATH='@t6g_mb_lib.t6g(sch_1):page34_i124@pure_quanta.q_cap(chips)',
 P_PATH='@t6g_mb_lib.t6g(sch_1):page34_i124@pure_quanta.q_cap(chips)',
 PATH='I124',
 DRAWING='@T6G_MB_LIB.T6G(SCH_1):PAGE34',
 TOLERANCE='5%',
 MATERIAL='X7R',
 PHYS_PAGE='34',
 XY='(-4600,2450)',
 ROT='0',
 VER='1',
 PACK_TYPE='0402',
 LOCATION='C5000',
 CDS_LIB='pure_quanta',
 CDS_PART_NAME='Q_CAP_0402-1000PF,50V,5%,X7R,TMP_QCH21006JB10',
 VOLTAGE='50V',
 PART_NUMBER='TMP_QCH21006JB10',
 VALUE='1000PF',
 PRIM_FILE='./archive_libs/logical/q_cap/chips/chips.prt';

PART_NAME
 C5001 'Q_CAP_0402-1000PF,50V,5%,X7R,TMP_QCH21006JB10':;

SECTION_NUMBER 1
 '@T6G_MB_LIB.T6G(SCH_1):PAGE184_I56@PURE_QUANTA.Q_CAP(CHIPS)':
 C_PATH='@t6g_mb_lib.t6g(sch_1):page184_i56@pure_quanta.q_cap(chips)',
 P_PATH='@t6g_mb_lib.t6g(sch_1):page209_i56@pure_quanta.q_cap(chips)',
 PATH='I56',
 DRAWING='@T6G_MB_LIB.T6G(SCH_1):PAGE184',
 TOLERANCE='5%',
 MATERIAL='X7R',
 PHYS_PAGE='209',
 XY='(-2850,3925)',
 ROT='0',
 VER='1',
 PACK_TYPE='0402',
 LOCATION='C5001',
 CDS_LIB='pure_quanta',
 CDS_PART_NAME='Q_CAP_0402-1000PF,50V,5%,X7R,TMP_QCH21006JB10',
 VOLTAGE='50V',
 PART_NUMBER='TMP_QCH21006JB10',
 VALUE='1000PF',
 PRIM_FILE='./archive_libs/logical/q_cap/chips/chips.prt';

PART_NAME
 C5002 'Q_CAP_0402-1000PF,50V,5%,X7R,TMP_QCH21006JB10':;

SECTION_NUMBER 1
 '@T6G_MB_LIB.T6G(SCH_1):PAGE167_I43@PURE_QUANTA.Q_CAP(CHIPS)':
 C_PATH='@t6g_mb_lib.t6g(sch_1):page167_i43@pure_quanta.q_cap(chips)',
 P_PATH='@t6g_mb_lib.t6g(sch_1):page192_i43@pure_quanta.q_cap(chips)',
 PATH='I43',
 DRAWING='@T6G_MB_LIB.T6G(SCH_1):PAGE167',
 TOLERANCE='5%',
 MATERIAL='X7R',
 PHYS_PAGE='192',
 XY='(-4850,3950)',
 ROT='0',
 VER='1',
 PACK_TYPE='0402',
 LOCATION='C5002',
 CDS_LIB='pure_quanta',
 CDS_PART_NAME='Q_CAP_0402-1000PF,50V,5%,X7R,TMP_QCH21006JB10',
 VOLTAGE='50V',
 PART_NUMBER='TMP_QCH21006JB10',
 VALUE='1000PF',
 PRIM_FILE='./archive_libs/logical/q_cap/chips/chips.prt';

PART_NAME
 C5003 'Q_CAP_0402-1000PF,50V,5%,X7R,TMP_QCH21006JB10':;

SECTION_NUMBER 1
 '@T6G_MB_LIB.T6G(SCH_1):PAGE185_I141@PURE_QUANTA.Q_CAP(CHIPS)':
 C_PATH='@t6g_mb_lib.t6g(sch_1):page185_i141@pure_quanta.q_cap(chips)',
 P_PATH='@t6g_mb_lib.t6g(sch_1):page210_i141@pure_quanta.q_cap(chips)',
 PATH='I141',
 DRAWING='@T6G_MB_LIB.T6G(SCH_1):PAGE185',
 TOLERANCE='5%',
 MATERIAL='X7R',
 PHYS_PAGE='210',
 XY='(-3600,7950)',
 ROT='0',
 VER='2',
 PACK_TYPE='0402',
 LOCATION='C5003',
 CDS_LIB='pure_quanta',
 CDS_PART_NAME='Q_CAP_0402-1000PF,50V,5%,X7R,TMP_QCH21006JB10',
 VOLTAGE='50V',
 PART_NUMBER='TMP_QCH21006JB10',
 VALUE='1000PF',
 PRIM_FILE='./archive_libs/logical/q_cap/chips/chips.prt';

PART_NAME
 C5004 'Q_CAP_0402-1000PF,50V,5%,X7R,TMP_QCH21006JB10':;

SECTION_NUMBER 1
 '@T6G_MB_LIB.T6G(SCH_1):PAGE175_I135@PURE_QUANTA.Q_CAP(CHIPS)':
 C_PATH='@t6g_mb_lib.t6g(sch_1):page175_i135@pure_quanta.q_cap(chips)',
 P_PATH='@t6g_mb_lib.t6g(sch_1):page200_i135@pure_quanta.q_cap(chips)',
 PATH='I135',
 DRAWING='@T6G_MB_LIB.T6G(SCH_1):PAGE175',
 TOLERANCE='5%',
 MATERIAL='X7R',
 PHYS_PAGE='200',
 XY='(-7250,6375)',
 ROT='0',
 VER='2',
 PACK_TYPE='0402',
 LOCATION='C5004',
 CDS_LIB='pure_quanta',
 CDS_PART_NAME='Q_CAP_0402-1000PF,50V,5%,X7R,TMP_QCH21006JB10',
 VOLTAGE='50V',
 PART_NUMBER='TMP_QCH21006JB10',
 VALUE='1000PF',
 PRIM_FILE='./archive_libs/logical/q_cap/chips/chips.prt';

PART_NAME
 C5005 'Q_CAP_0402-1000PF,50V,5%,X7R,TMP_QCH21006JB10':;

SECTION_NUMBER 1
 '@T6G_MB_LIB.T6G(SCH_1):PAGE175_I133@PURE_QUANTA.Q_CAP(CHIPS)':
 C_PATH='@t6g_mb_lib.t6g(sch_1):page175_i133@pure_quanta.q_cap(chips)',
 P_PATH='@t6g_mb_lib.t6g(sch_1):page200_i133@pure_quanta.q_cap(chips)',
 PATH='I133',
 DRAWING='@T6G_MB_LIB.T6G(SCH_1):PAGE175',
 TOLERANCE='5%',
 MATERIAL='X7R',
 PHYS_PAGE='200',
 XY='(-7275,1175)',
 ROT='0',
 VER='2',
 PACK_TYPE='0402',
 LOCATION='C5005',
 CDS_LIB='pure_quanta',
 CDS_PART_NAME='Q_CAP_0402-1000PF,50V,5%,X7R,TMP_QCH21006JB10',
 VOLTAGE='50V',
 PART_NUMBER='TMP_QCH21006JB10',
 VALUE='1000PF',
 PRIM_FILE='./archive_libs/logical/q_cap/chips/chips.prt';

PART_NAME
 C5006 'Q_CAP_0402-1000PF,50V,5%,X7R,TMP_QCH21006JB10':;

SECTION_NUMBER 1
 '@T6G_MB_LIB.T6G(SCH_1):PAGE192_I136@PURE_QUANTA.Q_CAP(CHIPS)':
 C_PATH='@t6g_mb_lib.t6g(sch_1):page192_i136@pure_quanta.q_cap(chips)',
 P_PATH='@t6g_mb_lib.t6g(sch_1):page217_i136@pure_quanta.q_cap(chips)',
 PATH='I136',
 DRAWING='@T6G_MB_LIB.T6G(SCH_1):PAGE192',
 TOLERANCE='5%',
 MATERIAL='X7R',
 PHYS_PAGE='217',
 XY='(-3625,2100)',
 ROT='0',
 VER='2',
 PACK_TYPE='0402',
 LOCATION='C5006',
 CDS_LIB='pure_quanta',
 CDS_PART_NAME='Q_CAP_0402-1000PF,50V,5%,X7R,TMP_QCH21006JB10',
 VOLTAGE='50V',
 PART_NUMBER='TMP_QCH21006JB10',
 VALUE='1000PF',
 PRIM_FILE='./archive_libs/logical/q_cap/chips/chips.prt';

PART_NAME
 C5009 'Q_CAP_0402-1000PF,50V,5%,X7R,TMP_QCH21006JB10':;

SECTION_NUMBER 1
 '@T6G_MB_LIB.T6G(SCH_1):PAGE182_I88@PURE_QUANTA.Q_CAP(CHIPS)':
 C_PATH='@t6g_mb_lib.t6g(sch_1):page182_i88@pure_quanta.q_cap(chips)',
 P_PATH='@t6g_mb_lib.t6g(sch_1):page207_i88@pure_quanta.q_cap(chips)',
 PATH='I88',
 DRAWING='@T6G_MB_LIB.T6G(SCH_1):PAGE182',
 TOLERANCE='5%',
 MATERIAL='X7R',
 PHYS_PAGE='207',
 XY='(-6500,4500)',
 ROT='0',
 VER='1',
 PACK_TYPE='0402',
 LOCATION='C5009',
 CDS_LIB='pure_quanta',
 CDS_PART_NAME='Q_CAP_0402-1000PF,50V,5%,X7R,TMP_QCH21006JB10',
 VOLTAGE='50V',
 PART_NUMBER='TMP_QCH21006JB10',
 VALUE='1000PF',
 PRIM_FILE='./archive_libs/logical/q_cap/chips/chips.prt';

PART_NAME
 C5010 'Q_CAP_0402-1000PF,50V,5%,X7R,TMP_QCH21006JB10':;

SECTION_NUMBER 1
 '@T6G_MB_LIB.T6G(SCH_1):PAGE199_I88@PURE_QUANTA.Q_CAP(CHIPS)':
 C_PATH='@t6g_mb_lib.t6g(sch_1):page199_i88@pure_quanta.q_cap(chips)',
 P_PATH='@t6g_mb_lib.t6g(sch_1):page224_i88@pure_quanta.q_cap(chips)',
 PATH='I88',
 DRAWING='@T6G_MB_LIB.T6G(SCH_1):PAGE199',
 TOLERANCE='5%',
 MATERIAL='X7R',
 PHYS_PAGE='224',
 XY='(-6375,4500)',
 ROT='0',
 VER='1',
 PACK_TYPE='0402',
 LOCATION='C5010',
 CDS_LIB='pure_quanta',
 CDS_PART_NAME='Q_CAP_0402-1000PF,50V,5%,X7R,TMP_QCH21006JB10',
 VOLTAGE='50V',
 PART_NUMBER='TMP_QCH21006JB10',
 VALUE='1000PF',
 PRIM_FILE='./archive_libs/logical/q_cap/chips/chips.prt';

PART_NAME
 C5011 'Q_CAP_0402-1000PF,50V,5%,X7R,TMP_QCH21006JB10':;

SECTION_NUMBER 1
 '@T6G_MB_LIB.T6G(SCH_1):PAGE168_I142@PURE_QUANTA.Q_CAP(CHIPS)':
 C_PATH='@t6g_mb_lib.t6g(sch_1):page168_i142@pure_quanta.q_cap(chips)',
 P_PATH='@t6g_mb_lib.t6g(sch_1):page193_i142@pure_quanta.q_cap(chips)',
 PATH='I142',
 DRAWING='@T6G_MB_LIB.T6G(SCH_1):PAGE168',
 TOLERANCE='5%',
 MATERIAL='X7R',
 PHYS_PAGE='193',
 XY='(-5225,4775)',
 ROT='0',
 VER='1',
 PACK_TYPE='0402',
 LOCATION='C5011',
 CDS_LIB='pure_quanta',
 CDS_PART_NAME='Q_CAP_0402-1000PF,50V,5%,X7R,TMP_QCH21006JB10',
 VOLTAGE='50V',
 PART_NUMBER='TMP_QCH21006JB10',
 VALUE='1000PF',
 PRIM_FILE='./archive_libs/logical/q_cap/chips/chips.prt';

PART_NAME
 C5012 'Q_CAP_0402-1000PF,50V,5%,X7R,TMP_QCH21006JB10':;

SECTION_NUMBER 1
 '@T6G_MB_LIB.T6G(SCH_1):PAGE185_I139@PURE_QUANTA.Q_CAP(CHIPS)':
 C_PATH='@t6g_mb_lib.t6g(sch_1):page185_i139@pure_quanta.q_cap(chips)',
 P_PATH='@t6g_mb_lib.t6g(sch_1):page210_i139@pure_quanta.q_cap(chips)',
 PATH='I139',
 DRAWING='@T6G_MB_LIB.T6G(SCH_1):PAGE185',
 TOLERANCE='5%',
 MATERIAL='X7R',
 PHYS_PAGE='210',
 XY='(-3125,6250)',
 ROT='0',
 VER='1',
 PACK_TYPE='0402',
 LOCATION='C5012',
 CDS_LIB='pure_quanta',
 CDS_PART_NAME='Q_CAP_0402-1000PF,50V,5%,X7R,TMP_QCH21006JB10',
 VOLTAGE='50V',
 PART_NUMBER='TMP_QCH21006JB10',
 VALUE='1000PF',
 PRIM_FILE='./archive_libs/logical/q_cap/chips/chips.prt';

PART_NAME
 C5013 'Q_CAP_0402-1000PF,50V,5%,X7R,TMP_QCH21006JB10':;

SECTION_NUMBER 1
 '@T6G_MB_LIB.T6G(SCH_1):PAGE175_I130@PURE_QUANTA.Q_CAP(CHIPS)':
 C_PATH='@t6g_mb_lib.t6g(sch_1):page175_i130@pure_quanta.q_cap(chips)',
 P_PATH='@t6g_mb_lib.t6g(sch_1):page200_i130@pure_quanta.q_cap(chips)',
 PATH='I130',
 DRAWING='@T6G_MB_LIB.T6G(SCH_1):PAGE175',
 TOLERANCE='5%',
 MATERIAL='X7R',
 PHYS_PAGE='200',
 XY='(-6100,4675)',
 ROT='0',
 VER='1',
 PACK_TYPE='0402',
 LOCATION='C5013',
 CDS_LIB='pure_quanta',
 CDS_PART_NAME='Q_CAP_0402-1000PF,50V,5%,X7R,TMP_QCH21006JB10',
 VOLTAGE='50V',
 PART_NUMBER='TMP_QCH21006JB10',
 VALUE='1000PF',
 PRIM_FILE='./archive_libs/logical/q_cap/chips/chips.prt';

PART_NAME
 C5014 'Q_CAP_0402-1000PF,50V,5%,X7R,TMP_QCH21006JB10':;

SECTION_NUMBER 1
 '@T6G_MB_LIB.T6G(SCH_1):PAGE264_I49@PURE_QUANTA.Q_CAP(CHIPS)':
 C_PATH='@t6g_mb_lib.t6g(sch_1):page264_i49@pure_quanta.q_cap(chips)',
 P_PATH='@t6g_mb_lib.t6g(sch_1):page259_i49@pure_quanta.q_cap(chips)',
 PATH='I49',
 DRAWING='@T6G_MB_LIB.T6G(SCH_1):PAGE264',
 TOLERANCE='5%',
 MATERIAL='X7R',
 PHYS_PAGE='259',
 XY='(-3225,1775)',
 ROT='0',
 VER='1',
 PACK_TYPE='0402',
 LOCATION='C5014',
 CDS_LIB='pure_quanta',
 CDS_PART_NAME='Q_CAP_0402-1000PF,50V,5%,X7R,TMP_QCH21006JB10',
 VOLTAGE='50V',
 PART_NUMBER='TMP_QCH21006JB10',
 VALUE='1000PF',
 PRIM_FILE='./archive_libs/logical/q_cap/chips/chips.prt';

PART_NAME
 C5015 'Q_CAP_0402-1000PF,50V,5%,EMPTY,TMP_QCH21006JB10':;

SECTION_NUMBER 1
 '@T6G_MB_LIB.T6G(SCH_1):PAGE245_I68@PURE_QUANTA.Q_CAP(CHIPS)':
 C_PATH='@t6g_mb_lib.t6g(sch_1):page245_i68@pure_quanta.q_cap(chips)',
 P_PATH='@t6g_mb_lib.t6g(sch_1):page190_i68@pure_quanta.q_cap(chips)',
 PATH='I68',
 DRAWING='@T6G_MB_LIB.T6G(SCH_1):PAGE245',
 TOLERANCE='5%',
 MATERIAL='EMPTY',
 PHYS_PAGE='190',
 XY='(2625,-75)',
 ROT='0',
 VER='1',
 PACK_TYPE='0402',
 LOCATION='C5015',
 CDS_LIB='pure_quanta',
 CDS_PART_NAME='Q_CAP_0402-1000PF,50V,5%,EMPTY,TMP_QCH21006JB10',
 VOLTAGE='50V',
 PART_NUMBER='TMP_QCH21006JB10',
 VALUE='1000PF',
 PRIM_FILE='./archive_libs/logical/q_cap/chips/chips.prt';

PART_NAME
 C5016 'Q_CAP_0402-1000PF,50V,5%,X7R,TMP_QCH21006JB10':;

SECTION_NUMBER 1
 '@T6G_MB_LIB.T6G(SCH_1):PAGE201_I55@PURE_QUANTA.Q_CAP(CHIPS)':
 C_PATH='@t6g_mb_lib.t6g(sch_1):page201_i55@pure_quanta.q_cap(chips)',
 P_PATH='@t6g_mb_lib.t6g(sch_1):page226_i55@pure_quanta.q_cap(chips)',
 PATH='I55',
 DRAWING='@T6G_MB_LIB.T6G(SCH_1):PAGE201',
 TOLERANCE='5%',
 MATERIAL='X7R',
 PHYS_PAGE='226',
 XY='(-2375,4350)',
 ROT='0',
 VER='1',
 PACK_TYPE='0402',
 LOCATION='C5016',
 CDS_LIB='pure_quanta',
 CDS_PART_NAME='Q_CAP_0402-1000PF,50V,5%,X7R,TMP_QCH21006JB10',
 VOLTAGE='50V',
 PART_NUMBER='TMP_QCH21006JB10',
 VALUE='1000PF',
 PRIM_FILE='./archive_libs/logical/q_cap/chips/chips.prt';

PART_NAME
 C5017 'Q_CAP_0402-1000PF,50V,5%,X7R,TMP_QCH21006JB10':;

SECTION_NUMBER 1
 '@T6G_MB_LIB.T6G(SCH_1):PAGE168_I139@PURE_QUANTA.Q_CAP(CHIPS)':
 C_PATH='@t6g_mb_lib.t6g(sch_1):page168_i139@pure_quanta.q_cap(chips)',
 P_PATH='@t6g_mb_lib.t6g(sch_1):page193_i139@pure_quanta.q_cap(chips)',
 PATH='I139',
 DRAWING='@T6G_MB_LIB.T6G(SCH_1):PAGE168',
 TOLERANCE='5%',
 MATERIAL='X7R',
 PHYS_PAGE='193',
 XY='(-6450,6625)',
 ROT='0',
 VER='2',
 PACK_TYPE='0402',
 LOCATION='C5017',
 CDS_LIB='pure_quanta',
 CDS_PART_NAME='Q_CAP_0402-1000PF,50V,5%,X7R,TMP_QCH21006JB10',
 VOLTAGE='50V',
 PART_NUMBER='TMP_QCH21006JB10',
 VALUE='1000PF',
 PRIM_FILE='./archive_libs/logical/q_cap/chips/chips.prt';

PART_NAME
 C5018 'Q_CAP_0402-1000PF,50V,5%,X7R,TMP_QCH21006JB10':;

SECTION_NUMBER 1
 '@T6G_MB_LIB.T6G(SCH_1):PAGE168_I138@PURE_QUANTA.Q_CAP(CHIPS)':
 C_PATH='@t6g_mb_lib.t6g(sch_1):page168_i138@pure_quanta.q_cap(chips)',
 P_PATH='@t6g_mb_lib.t6g(sch_1):page193_i138@pure_quanta.q_cap(chips)',
 PATH='I138',
 DRAWING='@T6G_MB_LIB.T6G(SCH_1):PAGE168',
 TOLERANCE='5%',
 MATERIAL='X7R',
 PHYS_PAGE='193',
 XY='(-6750,1525)',
 ROT='0',
 VER='2',
 PACK_TYPE='0402',
 LOCATION='C5018',
 CDS_LIB='pure_quanta',
 CDS_PART_NAME='Q_CAP_0402-1000PF,50V,5%,X7R,TMP_QCH21006JB10',
 VOLTAGE='50V',
 PART_NUMBER='TMP_QCH21006JB10',
 VALUE='1000PF',
 PRIM_FILE='./archive_libs/logical/q_cap/chips/chips.prt';

PART_NAME
 C5019 'Q_CAP_0402-1000PF,50V,5%,X7R,TMP_QCH21006JB10':;

SECTION_NUMBER 1
 '@T6G_MB_LIB.T6G(SCH_1):PAGE185_I137@PURE_QUANTA.Q_CAP(CHIPS)':
 C_PATH='@t6g_mb_lib.t6g(sch_1):page185_i137@pure_quanta.q_cap(chips)',
 P_PATH='@t6g_mb_lib.t6g(sch_1):page210_i137@pure_quanta.q_cap(chips)',
 PATH='I137',
 DRAWING='@T6G_MB_LIB.T6G(SCH_1):PAGE185',
 TOLERANCE='5%',
 MATERIAL='X7R',
 PHYS_PAGE='210',
 XY='(-3900,2900)',
 ROT='0',
 VER='2',
 PACK_TYPE='0402',
 LOCATION='C5019',
 CDS_LIB='pure_quanta',
 CDS_PART_NAME='Q_CAP_0402-1000PF,50V,5%,X7R,TMP_QCH21006JB10',
 VOLTAGE='50V',
 PART_NUMBER='TMP_QCH21006JB10',
 VALUE='1000PF',
 PRIM_FILE='./archive_libs/logical/q_cap/chips/chips.prt';

PART_NAME
 C5020 'Q_CAP_0402-1000PF,50V,5%,X7R,TMP_QCH21006JB10':;

SECTION_NUMBER 1
 '@T6G_MB_LIB.T6G(SCH_1):PAGE192_I133@PURE_QUANTA.Q_CAP(CHIPS)':
 C_PATH='@t6g_mb_lib.t6g(sch_1):page192_i133@pure_quanta.q_cap(chips)',
 P_PATH='@t6g_mb_lib.t6g(sch_1):page217_i133@pure_quanta.q_cap(chips)',
 PATH='I133',
 DRAWING='@T6G_MB_LIB.T6G(SCH_1):PAGE192',
 TOLERANCE='5%',
 MATERIAL='X7R',
 PHYS_PAGE='217',
 XY='(-3450,5550)',
 ROT='0',
 VER='2',
 PACK_TYPE='0402',
 LOCATION='C5020',
 CDS_LIB='pure_quanta',
 CDS_PART_NAME='Q_CAP_0402-1000PF,50V,5%,X7R,TMP_QCH21006JB10',
 VOLTAGE='50V',
 PART_NUMBER='TMP_QCH21006JB10',
 VALUE='1000PF',
 PRIM_FILE='./archive_libs/logical/q_cap/chips/chips.prt';

PART_NAME
 C5022 'Q_CAP_0402-1000PF,50V,5%,X7R,TMP_QCH21006JB10':;

SECTION_NUMBER 1
 '@T6G_MB_LIB.T6G(SCH_1):PAGE192_I131@PURE_QUANTA.Q_CAP(CHIPS)':
 C_PATH='@t6g_mb_lib.t6g(sch_1):page192_i131@pure_quanta.q_cap(chips)',
 P_PATH='@t6g_mb_lib.t6g(sch_1):page217_i131@pure_quanta.q_cap(chips)',
 PATH='I131',
 DRAWING='@T6G_MB_LIB.T6G(SCH_1):PAGE192',
 TOLERANCE='5%',
 MATERIAL='X7R',
 PHYS_PAGE='217',
 XY='(-3600,7350)',
 ROT='0',
 VER='2',
 PACK_TYPE='0402',
 LOCATION='C5022',
 CDS_LIB='pure_quanta',
 CDS_PART_NAME='Q_CAP_0402-1000PF,50V,5%,X7R,TMP_QCH21006JB10',
 VOLTAGE='50V',
 PART_NUMBER='TMP_QCH21006JB10',
 VALUE='1000PF',
 PRIM_FILE='./archive_libs/logical/q_cap/chips/chips.prt';

PART_NAME
 C5023 'Q_CAP_0402-1000PF,50V,5%,X7R,TMP_QCH21006JB10':;

SECTION_NUMBER 1
 '@T6G_MB_LIB.T6G(SCH_1):PAGE28_I194@PURE_QUANTA.Q_CAP(CHIPS)':
 C_PATH='@t6g_mb_lib.t6g(sch_1):page28_i194@pure_quanta.q_cap(chips)',
 P_PATH='@t6g_mb_lib.t6g(sch_1):page28_i194@pure_quanta.q_cap(chips)',
 PATH='I194',
 DRAWING='@T6G_MB_LIB.T6G(SCH_1):PAGE28',
 TOLERANCE='5%',
 MATERIAL='X7R',
 PHYS_PAGE='28',
 XY='(-7125,12250)',
 ROT='0',
 VER='1',
 PACK_TYPE='0402',
 LOCATION='C5023',
 CDS_LIB='pure_quanta',
 CDS_PART_NAME='Q_CAP_0402-1000PF,50V,5%,X7R,TMP_QCH21006JB10',
 VOLTAGE='50V',
 PART_NUMBER='TMP_QCH21006JB10',
 VALUE='1000PF',
 PRIM_FILE='./archive_libs/logical/q_cap/chips/chips.prt';

PART_NAME
 C5024 'Q_CAP_0402-1000PF,50V,5%,X7R,TMP_QCH21006JB10':;

SECTION_NUMBER 1
 '@T6G_MB_LIB.T6G(SCH_1):PAGE55_I388@PURE_QUANTA.Q_CAP(CHIPS)':
 C_PATH='@t6g_mb_lib.t6g(sch_1):page55_i388@pure_quanta.q_cap(chips)',
 P_PATH='@t6g_mb_lib.t6g(sch_1):page55_i388@pure_quanta.q_cap(chips)',
 PATH='I388',
 DRAWING='@T6G_MB_LIB.T6G(SCH_1):PAGE55',
 TOLERANCE='5%',
 MATERIAL='X7R',
 PHYS_PAGE='55',
 XY='(-7400,5350)',
 ROT='0',
 VER='1',
 PACK_TYPE='0402',
 LOCATION='C5024',
 CDS_LIB='pure_quanta',
 CDS_PART_NAME='Q_CAP_0402-1000PF,50V,5%,X7R,TMP_QCH21006JB10',
 VOLTAGE='50V',
 PART_NUMBER='TMP_QCH21006JB10',
 VALUE='1000PF',
 PRIM_FILE='./archive_libs/logical/q_cap/chips/chips.prt';

PART_NAME
 C5032 'Q_CAP_C0805-10UF,25V,10%,X6S,CH6104KEA00':;

SECTION_NUMBER 1
 '@T6G_MB_LIB.T6G(SCH_1):PAGE156_I126@PURE_QUANTA.Q_CAP(CHIPS)':
 C_PATH='@t6g_mb_lib.t6g(sch_1):page156_i126@pure_quanta.q_cap(chips)',
 P_PATH='@t6g_mb_lib.t6g(sch_1):page187_i126@pure_quanta.q_cap(chips)',
 PATH='I126',
 DRAWING='@T6G_MB_LIB.T6G(SCH_1):PAGE156',
 TOLERANCE='10%',
 MATERIAL='X6S',
 PHYS_PAGE='187',
 XY='(-1650,6275)',
 ROT='0',
 VER='1',
 PACK_TYPE='C0805',
 LOCATION='C5032',
 CDS_LIB='pure_quanta',
 CDS_PART_NAME='Q_CAP_C0805-10UF,25V,10%,X6S,CH6104KEA00',
 VOLTAGE='25V',
 PART_NUMBER='CH6104KEA00',
 VALUE='10UF',
 PRIM_FILE='./archive_libs/logical/q_cap/chips/chips.prt';

PART_NAME
 C5229 'Q_CAP_C0402-1UF,25V,10%,EMPTY,CH5104KEB02':
 ROOM='USB2 BOM2';

SECTION_NUMBER 1
 '@T6G_MB_LIB.T6G(SCH_1):PAGE358_I88@PURE_QUANTA.Q_CAP(CHIPS)':
 C_PATH='@t6g_mb_lib.t6g(sch_1):page358_i88@pure_quanta.q_cap(chips)',
 P_PATH='@t6g_mb_lib.t6g(sch_1):page234_i88@pure_quanta.q_cap(chips)',
 PATH='I88',
 DRAWING='@T6G_MB_LIB.T6G(SCH_1):PAGE358',
 TOLERANCE='10%',
 MATERIAL='EMPTY',
 PHYS_PAGE='234',
 XY='(75,700)',
 ROT='0',
 VER='1',
 PACK_TYPE='C0402',
 LOCATION='C5229',
 CDS_LIB='pure_quanta',
 CDS_PART_NAME='Q_CAP_C0402-1UF,25V,10%,EMPTY,CH5104KEB02',
 VOLTAGE='25V',
 ROOM='USB2 BOM2',
 PART_NUMBER='CH5104KEB02',
 VALUE='1UF',
 PRIM_FILE='./archive_libs/logical/q_cap/chips/chips.prt';

PART_NAME
 C5232 'Q_CAP_C0402-0.1UF,25V,10%,EMPTY,CH4104KEB00':
 ROOM='USB2 BOM2';

SECTION_NUMBER 1
 '@T6G_MB_LIB.T6G(SCH_1):PAGE358_I81@PURE_QUANTA.Q_CAP(CHIPS)':
 C_PATH='@t6g_mb_lib.t6g(sch_1):page358_i81@pure_quanta.q_cap(chips)',
 P_PATH='@t6g_mb_lib.t6g(sch_1):page234_i81@pure_quanta.q_cap(chips)',
 PATH='I81',
 DRAWING='@T6G_MB_LIB.T6G(SCH_1):PAGE358',
 TOLERANCE='10%',
 MATERIAL='EMPTY',
 PHYS_PAGE='234',
 XY='(-1150,-225)',
 ROT='0',
 VER='1',
 PACK_TYPE='C0402',
 LOCATION='C5232',
 CDS_LIB='pure_quanta',
 CDS_PART_NAME='Q_CAP_C0402-0.1UF,25V,10%,EMPTY,CH4104KEB00',
 VOLTAGE='25V',
 ROOM='USB2 BOM2',
 PART_NUMBER='CH4104KEB00',
 VALUE='0.1UF',
 PRIM_FILE='./archive_libs/logical/q_cap/chips/chips.prt';

PART_NAME
 C5234 'Q_CAP_C0402-0.1UF,25V,10%,EMPTY,CH4104KEB00':
 ROOM='USB2 BOM2';

SECTION_NUMBER 1
 '@T6G_MB_LIB.T6G(SCH_1):PAGE358_I92@PURE_QUANTA.Q_CAP(CHIPS)':
 C_PATH='@t6g_mb_lib.t6g(sch_1):page358_i92@pure_quanta.q_cap(chips)',
 P_PATH='@t6g_mb_lib.t6g(sch_1):page234_i92@pure_quanta.q_cap(chips)',
 PATH='I92',
 DRAWING='@T6G_MB_LIB.T6G(SCH_1):PAGE358',
 TOLERANCE='10%',
 MATERIAL='EMPTY',
 PHYS_PAGE='234',
 XY='(575,675)',
 ROT='0',
 VER='1',
 PACK_TYPE='C0402',
 LOCATION='C5234',
 CDS_LIB='pure_quanta',
 CDS_PART_NAME='Q_CAP_C0402-0.1UF,25V,10%,EMPTY,CH4104KEB00',
 VOLTAGE='25V',
 ROOM='USB2 BOM2',
 PART_NUMBER='CH4104KEB00',
 VALUE='0.1UF',
 PRIM_FILE='./archive_libs/logical/q_cap/chips/chips.prt';

PART_NAME
 C5236 'Q_CAP_C0402-0.1UF,25V,10%,EMPTY,CH4104KEB00':
 ROOM='USB2 BOM2';

SECTION_NUMBER 1
 '@T6G_MB_LIB.T6G(SCH_1):PAGE358_I87@PURE_QUANTA.Q_CAP(CHIPS)':
 C_PATH='@t6g_mb_lib.t6g(sch_1):page358_i87@pure_quanta.q_cap(chips)',
 P_PATH='@t6g_mb_lib.t6g(sch_1):page234_i87@pure_quanta.q_cap(chips)',
 PATH='I87',
 DRAWING='@T6G_MB_LIB.T6G(SCH_1):PAGE358',
 TOLERANCE='10%',
 MATERIAL='EMPTY',
 PHYS_PAGE='234',
 XY='(1475,-200)',
 ROT='0',
 VER='1',
 PACK_TYPE='C0402',
 LOCATION='C5236',
 CDS_LIB='pure_quanta',
 CDS_PART_NAME='Q_CAP_C0402-0.1UF,25V,10%,EMPTY,CH4104KEB00',
 VOLTAGE='25V',
 ROOM='USB2 BOM2',
 PART_NUMBER='CH4104KEB00',
 VALUE='0.1UF',
 PRIM_FILE='./archive_libs/logical/q_cap/chips/chips.prt';

PART_NAME
 C6000 'Q_CAP_0402-0.1UF,25V,10%,X7R,CH4104K1B00':;

SECTION_NUMBER 1
 '@T6G_MB_LIB.T6G(SCH_1):PAGE348_I219@PURE_QUANTA.Q_CAP(CHIPS)':
 C_PATH='@t6g_mb_lib.t6g(sch_1):page348_i219@pure_quanta.q_cap(chips)',
 P_PATH='@t6g_mb_lib.t6g(sch_1):page150_i219@pure_quanta.q_cap(chips)',
 PATH='I219',
 DRAWING='@T6G_MB_LIB.T6G(SCH_1):PAGE348',
 TOLERANCE='10%',
 MATERIAL='X7R',
 PHYS_PAGE='150',
 XY='(-8500,6675)',
 ROT='0',
 VER='1',
 PACK_TYPE='0402',
 LOCATION='C6000',
 CDS_LIB='pure_quanta',
 CDS_PART_NAME='Q_CAP_0402-0.1UF,25V,10%,X7R,CH4104K1B00',
 VOLTAGE='25V',
 PART_NUMBER='CH4104K1B00',
 VALUE='0.1UF',
 PRIM_FILE='./archive_libs/logical/q_cap/chips/chips.prt';

PART_NAME
 C6003 'Q_CAP_0402-0.1UF,25V,10%,X7R,CH4104K1B00':
 ROOM='USB3_HUB1';

SECTION_NUMBER 1
 '@T6G_MB_LIB.T6G(SCH_1):PAGE158_I144@PURE_QUANTA.Q_CAP(CHIPS)':
 C_PATH='@t6g_mb_lib.t6g(sch_1):page158_i144@pure_quanta.q_cap(chips)',
 P_PATH='@t6g_mb_lib.t6g(sch_1):page180_i144@pure_quanta.q_cap(chips)',
 PATH='I144',
 DRAWING='@T6G_MB_LIB.T6G(SCH_1):PAGE158',
 TOLERANCE='10%',
 MATERIAL='X7R',
 PHYS_PAGE='180',
 XY='(-7575,4800)',
 ROT='0',
 VER='2',
 PACK_TYPE='0402',
 LOCATION='C6003',
 CDS_LIB='pure_quanta',
 CDS_PART_NAME='Q_CAP_0402-0.1UF,25V,10%,X7R,CH4104K1B00',
 VOLTAGE='25V',
 ROOM='USB3_HUB1',
 PART_NUMBER='CH4104K1B00',
 VALUE='0.1UF',
 PRIM_FILE='./archive_libs/logical/q_cap/chips/chips.prt';

PART_NAME
 C6004 'Q_CAP_0402-0.1UF,25V,10%,X7R,CH4104K1B00':
 ROOM='USB3_HUB1';

SECTION_NUMBER 1
 '@T6G_MB_LIB.T6G(SCH_1):PAGE158_I143@PURE_QUANTA.Q_CAP(CHIPS)':
 C_PATH='@t6g_mb_lib.t6g(sch_1):page158_i143@pure_quanta.q_cap(chips)',
 P_PATH='@t6g_mb_lib.t6g(sch_1):page180_i143@pure_quanta.q_cap(chips)',
 PATH='I143',
 DRAWING='@T6G_MB_LIB.T6G(SCH_1):PAGE158',
 TOLERANCE='10%',
 MATERIAL='X7R',
 PHYS_PAGE='180',
 XY='(-7575,4750)',
 ROT='0',
 VER='2',
 PACK_TYPE='0402',
 LOCATION='C6004',
 CDS_LIB='pure_quanta',
 CDS_PART_NAME='Q_CAP_0402-0.1UF,25V,10%,X7R,CH4104K1B00',
 VOLTAGE='25V',
 ROOM='USB3_HUB1',
 PART_NUMBER='CH4104K1B00',
 VALUE='0.1UF',
 PRIM_FILE='./archive_libs/logical/q_cap/chips/chips.prt';

PART_NAME
 C6005 'Q_CAP_0402-0.1UF,25V,10%,X7R,CH4104K1B00':
 ROOM='PCIE REDRIVER BOM2';

SECTION_NUMBER 1
 '@T6G_MB_LIB.T6G(SCH_1):PAGE112_I36@PURE_QUANTA.Q_CAP(CHIPS)':
 C_PATH='@t6g_mb_lib.t6g(sch_1):page112_i36@pure_quanta.q_cap(chips)',
 P_PATH='@t6g_mb_lib.t6g(sch_1):page113_i36@pure_quanta.q_cap(chips)',
 PATH='I36',
 DRAWING='@T6G_MB_LIB.T6G(SCH_1):PAGE112',
 TOLERANCE='10%',
 MATERIAL='X7R',
 PHYS_PAGE='113',
 XY='(-2650,4900)',
 ROT='0',
 VER='2',
 PACK_TYPE='0402',
 LOCATION='C6005',
 CDS_LIB='pure_quanta',
 CDS_PART_NAME='Q_CAP_0402-0.1UF,25V,10%,X7R,CH4104K1B00',
 VOLTAGE='25V',
 ROOM='PCIE REDRIVER BOM2',
 PART_NUMBER='CH4104K1B00',
 VALUE='0.1UF',
 PRIM_FILE='./archive_libs/logical/q_cap/chips/chips.prt';

PART_NAME
 C6006 'Q_CAP_0402-0.1UF,25V,10%,X7R,CH4104K1B00':
 ROOM='PCIE REDRIVER BOM2';

SECTION_NUMBER 1
 '@T6G_MB_LIB.T6G(SCH_1):PAGE112_I35@PURE_QUANTA.Q_CAP(CHIPS)':
 C_PATH='@t6g_mb_lib.t6g(sch_1):page112_i35@pure_quanta.q_cap(chips)',
 P_PATH='@t6g_mb_lib.t6g(sch_1):page113_i35@pure_quanta.q_cap(chips)',
 PATH='I35',
 DRAWING='@T6G_MB_LIB.T6G(SCH_1):PAGE112',
 TOLERANCE='10%',
 MATERIAL='X7R',
 PHYS_PAGE='113',
 XY='(-2650,4850)',
 ROT='0',
 VER='2',
 PACK_TYPE='0402',
 LOCATION='C6006',
 CDS_LIB='pure_quanta',
 CDS_PART_NAME='Q_CAP_0402-0.1UF,25V,10%,X7R,CH4104K1B00',
 VOLTAGE='25V',
 ROOM='PCIE REDRIVER BOM2',
 PART_NUMBER='CH4104K1B00',
 VALUE='0.1UF',
 PRIM_FILE='./archive_libs/logical/q_cap/chips/chips.prt';

PART_NAME
 C6007 'Q_CAP_0402-0.1UF,25V,10%,X7R,CH4104K1B00':
 ROOM='PCIE REDRIVER BOM2';

SECTION_NUMBER 1
 '@T6G_MB_LIB.T6G(SCH_1):PAGE112_I43@PURE_QUANTA.Q_CAP(CHIPS)':
 C_PATH='@t6g_mb_lib.t6g(sch_1):page112_i43@pure_quanta.q_cap(chips)',
 P_PATH='@t6g_mb_lib.t6g(sch_1):page113_i43@pure_quanta.q_cap(chips)',
 PATH='I43',
 DRAWING='@T6G_MB_LIB.T6G(SCH_1):PAGE112',
 TOLERANCE='10%',
 MATERIAL='X7R',
 PHYS_PAGE='113',
 XY='(-2550,3925)',
 ROT='0',
 VER='2',
 PACK_TYPE='0402',
 LOCATION='C6007',
 CDS_LIB='pure_quanta',
 CDS_PART_NAME='Q_CAP_0402-0.1UF,25V,10%,X7R,CH4104K1B00',
 VOLTAGE='25V',
 ROOM='PCIE REDRIVER BOM2',
 PART_NUMBER='CH4104K1B00',
 VALUE='0.1UF',
 PRIM_FILE='./archive_libs/logical/q_cap/chips/chips.prt';

PART_NAME
 C6008 'Q_CAP_0402-0.1UF,25V,10%,X7R,CH4104K1B00':
 ROOM='PCIE REDRIVER BOM2';

SECTION_NUMBER 1
 '@T6G_MB_LIB.T6G(SCH_1):PAGE112_I44@PURE_QUANTA.Q_CAP(CHIPS)':
 C_PATH='@t6g_mb_lib.t6g(sch_1):page112_i44@pure_quanta.q_cap(chips)',
 P_PATH='@t6g_mb_lib.t6g(sch_1):page113_i44@pure_quanta.q_cap(chips)',
 PATH='I44',
 DRAWING='@T6G_MB_LIB.T6G(SCH_1):PAGE112',
 TOLERANCE='10%',
 MATERIAL='X7R',
 PHYS_PAGE='113',
 XY='(-2550,3875)',
 ROT='0',
 VER='2',
 PACK_TYPE='0402',
 LOCATION='C6008',
 CDS_LIB='pure_quanta',
 CDS_PART_NAME='Q_CAP_0402-0.1UF,25V,10%,X7R,CH4104K1B00',
 VOLTAGE='25V',
 ROOM='PCIE REDRIVER BOM2',
 PART_NUMBER='CH4104K1B00',
 VALUE='0.1UF',
 PRIM_FILE='./archive_libs/logical/q_cap/chips/chips.prt';

PART_NAME
 C6009 'Q_CAP_C0402-1UF,25V,10%,X6S,CH5104KEB02':
 ROOM='PCIE REDRIVER BOM2';

SECTION_NUMBER 1
 '@T6G_MB_LIB.T6G(SCH_1):PAGE111_I3@PURE_QUANTA.Q_CAP(CHIPS)':
 C_PATH='@t6g_mb_lib.t6g(sch_1):page111_i3@pure_quanta.q_cap(chips)',
 P_PATH='@t6g_mb_lib.t6g(sch_1):page112_i3@pure_quanta.q_cap(chips)',
 PATH='I3',
 DRAWING='@T6G_MB_LIB.T6G(SCH_1):PAGE111',
 TOLERANCE='10%',
 MATERIAL='X6S',
 PHYS_PAGE='112',
 XY='(-7725,6075)',
 ROT='0',
 VER='1',
 PACK_TYPE='C0402',
 LOCATION='C6009',
 CDS_LIB='pure_quanta',
 CDS_PART_NAME='Q_CAP_C0402-1UF,25V,10%,X6S,CH5104KEB02',
 VOLTAGE='25V',
 ROOM='PCIE REDRIVER BOM2',
 PART_NUMBER='CH5104KEB02',
 VALUE='1UF',
 PRIM_FILE='./archive_libs/logical/q_cap/chips/chips.prt';

PART_NAME
 C6010 'Q_CAP_C0805-10UF,16V,10%,X6S,CH6103KEA00':
 ROOM='PCIE REDRIVER BOM2';

SECTION_NUMBER 1
 '@T6G_MB_LIB.T6G(SCH_1):PAGE111_I5@PURE_QUANTA.Q_CAP(CHIPS)':
 C_PATH='@t6g_mb_lib.t6g(sch_1):page111_i5@pure_quanta.q_cap(chips)',
 P_PATH='@t6g_mb_lib.t6g(sch_1):page112_i5@pure_quanta.q_cap(chips)',
 PATH='I5',
 DRAWING='@T6G_MB_LIB.T6G(SCH_1):PAGE111',
 TOLERANCE='10%',
 MATERIAL='X6S',
 PHYS_PAGE='112',
 XY='(-7150,6075)',
 ROT='0',
 VER='1',
 PACK_TYPE='C0805',
 LOCATION='C6010',
 CDS_LIB='pure_quanta',
 CDS_PART_NAME='Q_CAP_C0805-10UF,16V,10%,X6S,CH6103KEA00',
 VOLTAGE='16V',
 ROOM='PCIE REDRIVER BOM2',
 PART_NUMBER='CH6103KEA00',
 VALUE='10UF',
 PRIM_FILE='./archive_libs/logical/q_cap/chips/chips.prt';

PART_NAME
 C6011 'Q_CAP_0402-0.1UF,25V,10%,X7R,CH4104K1B00':
 ROOM='PCIE REDRIVER BOM2';

SECTION_NUMBER 1
 '@T6G_MB_LIB.T6G(SCH_1):PAGE111_I6@PURE_QUANTA.Q_CAP(CHIPS)':
 C_PATH='@t6g_mb_lib.t6g(sch_1):page111_i6@pure_quanta.q_cap(chips)',
 P_PATH='@t6g_mb_lib.t6g(sch_1):page112_i6@pure_quanta.q_cap(chips)',
 PATH='I6',
 DRAWING='@T6G_MB_LIB.T6G(SCH_1):PAGE111',
 TOLERANCE='10%',
 MATERIAL='X7R',
 PHYS_PAGE='112',
 XY='(-6575,6025)',
 ROT='0',
 VER='1',
 PACK_TYPE='0402',
 LOCATION='C6011',
 CDS_LIB='pure_quanta',
 CDS_PART_NAME='Q_CAP_0402-0.1UF,25V,10%,X7R,CH4104K1B00',
 VOLTAGE='25V',
 ROOM='PCIE REDRIVER BOM2',
 PART_NUMBER='CH4104K1B00',
 VALUE='0.1UF',
 PRIM_FILE='./archive_libs/logical/q_cap/chips/chips.prt';

PART_NAME
 C6012 'Q_CAP_0402-0.1UF,25V,10%,X7R,CH4104K1B00':
 ROOM='PCIE REDRIVER BOM2';

SECTION_NUMBER 1
 '@T6G_MB_LIB.T6G(SCH_1):PAGE111_I7@PURE_QUANTA.Q_CAP(CHIPS)':
 C_PATH='@t6g_mb_lib.t6g(sch_1):page111_i7@pure_quanta.q_cap(chips)',
 P_PATH='@t6g_mb_lib.t6g(sch_1):page112_i7@pure_quanta.q_cap(chips)',
 PATH='I7',
 DRAWING='@T6G_MB_LIB.T6G(SCH_1):PAGE111',
 TOLERANCE='10%',
 MATERIAL='X7R',
 PHYS_PAGE='112',
 XY='(-6025,6025)',
 ROT='0',
 VER='1',
 PACK_TYPE='0402',
 LOCATION='C6012',
 CDS_LIB='pure_quanta',
 CDS_PART_NAME='Q_CAP_0402-0.1UF,25V,10%,X7R,CH4104K1B00',
 VOLTAGE='25V',
 ROOM='PCIE REDRIVER BOM2',
 PART_NUMBER='CH4104K1B00',
 VALUE='0.1UF',
 PRIM_FILE='./archive_libs/logical/q_cap/chips/chips.prt';

PART_NAME
 C6013 'Q_CAP_0402-0.1UF,25V,10%,X7R,CH4104K1B00':
 ROOM='USB3_HUB2';

SECTION_NUMBER 1
 '@T6G_MB_LIB.T6G(SCH_1):PAGE158_I142@PURE_QUANTA.Q_CAP(CHIPS)':
 C_PATH='@t6g_mb_lib.t6g(sch_1):page158_i142@pure_quanta.q_cap(chips)',
 P_PATH='@t6g_mb_lib.t6g(sch_1):page180_i142@pure_quanta.q_cap(chips)',
 PATH='I142',
 DRAWING='@T6G_MB_LIB.T6G(SCH_1):PAGE158',
 TOLERANCE='10%',
 MATERIAL='X7R',
 PHYS_PAGE='180',
 XY='(-7575,4450)',
 ROT='0',
 VER='2',
 PACK_TYPE='0402',
 LOCATION='C6013',
 CDS_LIB='pure_quanta',
 CDS_PART_NAME='Q_CAP_0402-0.1UF,25V,10%,X7R,CH4104K1B00',
 VOLTAGE='25V',
 ROOM='USB3_HUB2',
 PART_NUMBER='CH4104K1B00',
 VALUE='0.1UF',
 PRIM_FILE='./archive_libs/logical/q_cap/chips/chips.prt';

PART_NAME
 C6014 'Q_CAP_0402-0.1UF,25V,10%,X7R,CH4104K1B00':
 ROOM='USB3_HUB2';

SECTION_NUMBER 1
 '@T6G_MB_LIB.T6G(SCH_1):PAGE158_I141@PURE_QUANTA.Q_CAP(CHIPS)':
 C_PATH='@t6g_mb_lib.t6g(sch_1):page158_i141@pure_quanta.q_cap(chips)',
 P_PATH='@t6g_mb_lib.t6g(sch_1):page180_i141@pure_quanta.q_cap(chips)',
 PATH='I141',
 DRAWING='@T6G_MB_LIB.T6G(SCH_1):PAGE158',
 TOLERANCE='10%',
 MATERIAL='X7R',
 PHYS_PAGE='180',
 XY='(-7575,4400)',
 ROT='0',
 VER='2',
 PACK_TYPE='0402',
 LOCATION='C6014',
 CDS_LIB='pure_quanta',
 CDS_PART_NAME='Q_CAP_0402-0.1UF,25V,10%,X7R,CH4104K1B00',
 VOLTAGE='25V',
 ROOM='USB3_HUB2',
 PART_NUMBER='CH4104K1B00',
 VALUE='0.1UF',
 PRIM_FILE='./archive_libs/logical/q_cap/chips/chips.prt';

PART_NAME
 C6015 'Q_CAP_DIFFBUS_C0402-DIFF BUS_0.33UF,6.3V,10%,X6S,SA':
 ROOM='USB3_HUB1';

SECTION_NUMBER 1
 '@T6G_MB_LIB.T6G(SCH_1):PAGE158_I49@PURE_QUANTA.Q_CAP_DIFFBUS(CHIPS)':
 C_PATH='@t6g_mb_lib.t6g(sch_1):page158_i49@pure_quanta.q_cap_diffbus(chips)',
 P_PATH='@t6g_mb_lib.t6g(sch_1):page180_i49@pure_quanta.q_cap_diffbus(chips)',
 PATH='I49',
 DRAWING='@T6G_MB_LIB.T6G(SCH_1):PAGE158',
 PIN_NAMES_ROTATE='True',
 TOLERANCE='10%',
 MATERIAL='X6S',
 PHYS_PAGE='180',
 XY='(-3175,2725)',
 ROT='0',
 VER='2',
 PACK_TYPE='C0402',
 LOCATION='C6015',
 CDS_LIB='pure_quanta',
 CDS_PART_NAME='Q_CAP_DIFFBUS_C0402-DIFF BUS_0.33UF,6.3V,10%,X6S,SA',
 VOLTAGE='6.3V',
 ROOM='USB3_HUB1',
 PART_NUMBER='SP_CH4331KEB01',
 VALUE='DIFF BUS_0.33UF',
 PRIM_FILE='./archive_libs/logical/q_cap_diffbus/chips/chips.prt';

PART_NAME
 C6016 'Q_CAP_DIFFBUS_C0402-DIFF BUS_0.33UF,6.3V,10%,X6S,SA':
 ROOM='USB3_HUB1';

SECTION_NUMBER 1
 '@T6G_MB_LIB.T6G(SCH_1):PAGE158_I50@PURE_QUANTA.Q_CAP_DIFFBUS(CHIPS)':
 C_PATH='@t6g_mb_lib.t6g(sch_1):page158_i50@pure_quanta.q_cap_diffbus(chips)',
 P_PATH='@t6g_mb_lib.t6g(sch_1):page180_i50@pure_quanta.q_cap_diffbus(chips)',
 PATH='I50',
 DRAWING='@T6G_MB_LIB.T6G(SCH_1):PAGE158',
 PIN_NAMES_ROTATE='True',
 TOLERANCE='10%',
 MATERIAL='X6S',
 PHYS_PAGE='180',
 XY='(-3175,2675)',
 ROT='0',
 VER='2',
 PACK_TYPE='C0402',
 LOCATION='C6016',
 CDS_LIB='pure_quanta',
 CDS_PART_NAME='Q_CAP_DIFFBUS_C0402-DIFF BUS_0.33UF,6.3V,10%,X6S,SA',
 VOLTAGE='6.3V',
 ROOM='USB3_HUB1',
 PART_NUMBER='SP_CH4331KEB01',
 VALUE='DIFF BUS_0.33UF',
 PRIM_FILE='./archive_libs/logical/q_cap_diffbus/chips/chips.prt';

PART_NAME
 C6017 'Q_CAP_0402-0.1UF,25V,10%,X7R,CH4104K1B00':
 ROOM='USB3_HUB2';

SECTION_NUMBER 1
 '@T6G_MB_LIB.T6G(SCH_1):PAGE158_I148@PURE_QUANTA.Q_CAP(CHIPS)':
 C_PATH='@t6g_mb_lib.t6g(sch_1):page158_i148@pure_quanta.q_cap(chips)',
 P_PATH='@t6g_mb_lib.t6g(sch_1):page180_i148@pure_quanta.q_cap(chips)',
 PATH='I148',
 DRAWING='@T6G_MB_LIB.T6G(SCH_1):PAGE158',
 TOLERANCE='10%',
 MATERIAL='X7R',
 PHYS_PAGE='180',
 XY='(-3125,2150)',
 ROT='0',
 VER='2',
 PACK_TYPE='0402',
 LOCATION='C6017',
 CDS_LIB='pure_quanta',
 CDS_PART_NAME='Q_CAP_0402-0.1UF,25V,10%,X7R,CH4104K1B00',
 VOLTAGE='25V',
 ROOM='USB3_HUB2',
 PART_NUMBER='CH4104K1B00',
 VALUE='0.1UF',
 PRIM_FILE='./archive_libs/logical/q_cap/chips/chips.prt';

PART_NAME
 C6018 'Q_CAP_0402-0.1UF,25V,10%,X7R,CH4104K1B00':
 ROOM='USB3_HUB2';

SECTION_NUMBER 1
 '@T6G_MB_LIB.T6G(SCH_1):PAGE158_I147@PURE_QUANTA.Q_CAP(CHIPS)':
 C_PATH='@t6g_mb_lib.t6g(sch_1):page158_i147@pure_quanta.q_cap(chips)',
 P_PATH='@t6g_mb_lib.t6g(sch_1):page180_i147@pure_quanta.q_cap(chips)',
 PATH='I147',
 DRAWING='@T6G_MB_LIB.T6G(SCH_1):PAGE158',
 TOLERANCE='10%',
 MATERIAL='X7R',
 PHYS_PAGE='180',
 XY='(-3125,2100)',
 ROT='0',
 VER='2',
 PACK_TYPE='0402',
 LOCATION='C6018',
 CDS_LIB='pure_quanta',
 CDS_PART_NAME='Q_CAP_0402-0.1UF,25V,10%,X7R,CH4104K1B00',
 VOLTAGE='25V',
 ROOM='USB3_HUB2',
 PART_NUMBER='CH4104K1B00',
 VALUE='0.1UF',
 PRIM_FILE='./archive_libs/logical/q_cap/chips/chips.prt';

PART_NAME
 C6019 'Q_CAP_DIFFBUS_C0402-DIFF BUS_0.33UF,6.3V,10%,X6S,SA':
 ROOM='USB3_HUB1';

SECTION_NUMBER 1
 '@T6G_MB_LIB.T6G(SCH_1):PAGE158_I85@PURE_QUANTA.Q_CAP_DIFFBUS(CHIPS)':
 C_PATH='@t6g_mb_lib.t6g(sch_1):page158_i85@pure_quanta.q_cap_diffbus(chips)',
 P_PATH='@t6g_mb_lib.t6g(sch_1):page180_i85@pure_quanta.q_cap_diffbus(chips)',
 PATH='I85',
 DRAWING='@T6G_MB_LIB.T6G(SCH_1):PAGE158',
 PIN_NAMES_ROTATE='True',
 TOLERANCE='10%',
 MATERIAL='X6S',
 PHYS_PAGE='180',
 XY='(-7300,2650)',
 ROT='0',
 VER='2',
 PACK_TYPE='C0402',
 LOCATION='C6019',
 CDS_LIB='pure_quanta',
 CDS_PART_NAME='Q_CAP_DIFFBUS_C0402-DIFF BUS_0.33UF,6.3V,10%,X6S,SA',
 VOLTAGE='6.3V',
 ROOM='USB3_HUB1',
 PART_NUMBER='SP_CH4331KEB01',
 VALUE='DIFF BUS_0.33UF',
 PRIM_FILE='./archive_libs/logical/q_cap_diffbus/chips/chips.prt';

PART_NAME
 C6020 'Q_CAP_DIFFBUS_C0402-DIFF BUS_0.33UF,6.3V,10%,X6S,SA':
 ROOM='USB3_HUB1';

SECTION_NUMBER 1
 '@T6G_MB_LIB.T6G(SCH_1):PAGE158_I86@PURE_QUANTA.Q_CAP_DIFFBUS(CHIPS)':
 C_PATH='@t6g_mb_lib.t6g(sch_1):page158_i86@pure_quanta.q_cap_diffbus(chips)',
 P_PATH='@t6g_mb_lib.t6g(sch_1):page180_i86@pure_quanta.q_cap_diffbus(chips)',
 PATH='I86',
 DRAWING='@T6G_MB_LIB.T6G(SCH_1):PAGE158',
 PIN_NAMES_ROTATE='True',
 TOLERANCE='10%',
 MATERIAL='X6S',
 PHYS_PAGE='180',
 XY='(-7300,2600)',
 ROT='0',
 VER='2',
 PACK_TYPE='C0402',
 LOCATION='C6020',
 CDS_LIB='pure_quanta',
 CDS_PART_NAME='Q_CAP_DIFFBUS_C0402-DIFF BUS_0.33UF,6.3V,10%,X6S,SA',
 VOLTAGE='6.3V',
 ROOM='USB3_HUB1',
 PART_NUMBER='SP_CH4331KEB01',
 VALUE='DIFF BUS_0.33UF',
 PRIM_FILE='./archive_libs/logical/q_cap_diffbus/chips/chips.prt';

PART_NAME
 C6021 'Q_CAP_DIFFBUS_C0402-DIFF BUS_0.33UF,6.3V,10%,X6S,SA':
 ROOM='USB3_HUB2';

SECTION_NUMBER 1
 '@T6G_MB_LIB.T6G(SCH_1):PAGE158_I87@PURE_QUANTA.Q_CAP_DIFFBUS(CHIPS)':
 C_PATH='@t6g_mb_lib.t6g(sch_1):page158_i87@pure_quanta.q_cap_diffbus(chips)',
 P_PATH='@t6g_mb_lib.t6g(sch_1):page180_i87@pure_quanta.q_cap_diffbus(chips)',
 PATH='I87',
 DRAWING='@T6G_MB_LIB.T6G(SCH_1):PAGE158',
 PIN_NAMES_ROTATE='True',
 TOLERANCE='10%',
 MATERIAL='X6S',
 PHYS_PAGE='180',
 XY='(-7300,2300)',
 ROT='0',
 VER='2',
 PACK_TYPE='C0402',
 LOCATION='C6021',
 CDS_LIB='pure_quanta',
 CDS_PART_NAME='Q_CAP_DIFFBUS_C0402-DIFF BUS_0.33UF,6.3V,10%,X6S,SA',
 VOLTAGE='6.3V',
 ROOM='USB3_HUB2',
 PART_NUMBER='SP_CH4331KEB01',
 VALUE='DIFF BUS_0.33UF',
 PRIM_FILE='./archive_libs/logical/q_cap_diffbus/chips/chips.prt';

PART_NAME
 C6022 'Q_CAP_DIFFBUS_C0402-DIFF BUS_0.33UF,6.3V,10%,X6S,SA':
 ROOM='USB3_HUB2';

SECTION_NUMBER 1
 '@T6G_MB_LIB.T6G(SCH_1):PAGE158_I88@PURE_QUANTA.Q_CAP_DIFFBUS(CHIPS)':
 C_PATH='@t6g_mb_lib.t6g(sch_1):page158_i88@pure_quanta.q_cap_diffbus(chips)',
 P_PATH='@t6g_mb_lib.t6g(sch_1):page180_i88@pure_quanta.q_cap_diffbus(chips)',
 PATH='I88',
 DRAWING='@T6G_MB_LIB.T6G(SCH_1):PAGE158',
 PIN_NAMES_ROTATE='True',
 TOLERANCE='10%',
 MATERIAL='X6S',
 PHYS_PAGE='180',
 XY='(-7300,2250)',
 ROT='0',
 VER='2',
 PACK_TYPE='C0402',
 LOCATION='C6022',
 CDS_LIB='pure_quanta',
 CDS_PART_NAME='Q_CAP_DIFFBUS_C0402-DIFF BUS_0.33UF,6.3V,10%,X6S,SA',
 VOLTAGE='6.3V',
 ROOM='USB3_HUB2',
 PART_NUMBER='SP_CH4331KEB01',
 VALUE='DIFF BUS_0.33UF',
 PRIM_FILE='./archive_libs/logical/q_cap_diffbus/chips/chips.prt';

PART_NAME
 C6023 'Q_CAP_0402-0.1UF,25V,10%,X7R,CH4104K1B00':
 ROOM='USB3_HUB1';

SECTION_NUMBER 1
 '@T6G_MB_LIB.T6G(SCH_1):PAGE158_I137@PURE_QUANTA.Q_CAP(CHIPS)':
 C_PATH='@t6g_mb_lib.t6g(sch_1):page158_i137@pure_quanta.q_cap(chips)',
 P_PATH='@t6g_mb_lib.t6g(sch_1):page180_i137@pure_quanta.q_cap(chips)',
 PATH='I137',
 DRAWING='@T6G_MB_LIB.T6G(SCH_1):PAGE158',
 TOLERANCE='10%',
 MATERIAL='X7R',
 PHYS_PAGE='180',
 XY='(-3150,4550)',
 ROT='0',
 VER='2',
 PACK_TYPE='0402',
 LOCATION='C6023',
 CDS_LIB='pure_quanta',
 CDS_PART_NAME='Q_CAP_0402-0.1UF,25V,10%,X7R,CH4104K1B00',
 VOLTAGE='25V',
 ROOM='USB3_HUB1',
 PART_NUMBER='CH4104K1B00',
 VALUE='0.1UF',
 PRIM_FILE='./archive_libs/logical/q_cap/chips/chips.prt';

PART_NAME
 C6024 'Q_CAP_0402-0.1UF,25V,10%,X7R,CH4104K1B00':
 ROOM='USB3_HUB1';

SECTION_NUMBER 1
 '@T6G_MB_LIB.T6G(SCH_1):PAGE158_I138@PURE_QUANTA.Q_CAP(CHIPS)':
 C_PATH='@t6g_mb_lib.t6g(sch_1):page158_i138@pure_quanta.q_cap(chips)',
 P_PATH='@t6g_mb_lib.t6g(sch_1):page180_i138@pure_quanta.q_cap(chips)',
 PATH='I138',
 DRAWING='@T6G_MB_LIB.T6G(SCH_1):PAGE158',
 TOLERANCE='10%',
 MATERIAL='X7R',
 PHYS_PAGE='180',
 XY='(-3150,4500)',
 ROT='0',
 VER='2',
 PACK_TYPE='0402',
 LOCATION='C6024',
 CDS_LIB='pure_quanta',
 CDS_PART_NAME='Q_CAP_0402-0.1UF,25V,10%,X7R,CH4104K1B00',
 VOLTAGE='25V',
 ROOM='USB3_HUB1',
 PART_NUMBER='CH4104K1B00',
 VALUE='0.1UF',
 PRIM_FILE='./archive_libs/logical/q_cap/chips/chips.prt';

PART_NAME
 C6025 'Q_CAP_0402-0.1UF,25V,10%,X7R,CH4104K1B00':
 ROOM='USB3_HUB2';

SECTION_NUMBER 1
 '@T6G_MB_LIB.T6G(SCH_1):PAGE158_I139@PURE_QUANTA.Q_CAP(CHIPS)':
 C_PATH='@t6g_mb_lib.t6g(sch_1):page158_i139@pure_quanta.q_cap(chips)',
 P_PATH='@t6g_mb_lib.t6g(sch_1):page180_i139@pure_quanta.q_cap(chips)',
 PATH='I139',
 DRAWING='@T6G_MB_LIB.T6G(SCH_1):PAGE158',
 TOLERANCE='10%',
 MATERIAL='X7R',
 PHYS_PAGE='180',
 XY='(-3125,3975)',
 ROT='0',
 VER='2',
 PACK_TYPE='0402',
 LOCATION='C6025',
 CDS_LIB='pure_quanta',
 CDS_PART_NAME='Q_CAP_0402-0.1UF,25V,10%,X7R,CH4104K1B00',
 VOLTAGE='25V',
 ROOM='USB3_HUB2',
 PART_NUMBER='CH4104K1B00',
 VALUE='0.1UF',
 PRIM_FILE='./archive_libs/logical/q_cap/chips/chips.prt';

PART_NAME
 C6026 'Q_CAP_0402-0.1UF,25V,10%,X7R,CH4104K1B00':
 ROOM='USB3_HUB2';

SECTION_NUMBER 1
 '@T6G_MB_LIB.T6G(SCH_1):PAGE158_I140@PURE_QUANTA.Q_CAP(CHIPS)':
 C_PATH='@t6g_mb_lib.t6g(sch_1):page158_i140@pure_quanta.q_cap(chips)',
 P_PATH='@t6g_mb_lib.t6g(sch_1):page180_i140@pure_quanta.q_cap(chips)',
 PATH='I140',
 DRAWING='@T6G_MB_LIB.T6G(SCH_1):PAGE158',
 TOLERANCE='10%',
 MATERIAL='X7R',
 PHYS_PAGE='180',
 XY='(-3125,3925)',
 ROT='0',
 VER='2',
 PACK_TYPE='0402',
 LOCATION='C6026',
 CDS_LIB='pure_quanta',
 CDS_PART_NAME='Q_CAP_0402-0.1UF,25V,10%,X7R,CH4104K1B00',
 VOLTAGE='25V',
 ROOM='USB3_HUB2',
 PART_NUMBER='CH4104K1B00',
 VALUE='0.1UF',
 PRIM_FILE='./archive_libs/logical/q_cap/chips/chips.prt';

PART_NAME
 C6027 'Q_CAP_C0805-22UF,16V,20%,X6S,CH6223MEA00':
 ROOM='USB3_HUB1_CYP';

SECTION_NUMBER 1
 '@T6G_MB_LIB.T6G(SCH_1):PAGE153_I28@PURE_QUANTA.Q_CAP(CHIPS)':
 C_PATH='@t6g_mb_lib.t6g(sch_1):page153_i28@pure_quanta.q_cap(chips)',
 P_PATH='@t6g_mb_lib.t6g(sch_1):page176_i28@pure_quanta.q_cap(chips)',
 PATH='I28',
 DRAWING='@T6G_MB_LIB.T6G(SCH_1):PAGE153',
 TOLERANCE='20%',
 MATERIAL='X6S',
 PHYS_PAGE='176',
 XY='(-1525,6025)',
 ROT='0',
 VER='1',
 PACK_TYPE='C0805',
 LOCATION='C6027',
 CDS_LIB='pure_quanta',
 CDS_PART_NAME='Q_CAP_C0805-22UF,16V,20%,X6S,CH6223MEA00',
 VOLTAGE='16V',
 ROOM='USB3_HUB1_CYP',
 PART_NUMBER='CH6223MEA00',
 VALUE='22UF',
 PRIM_FILE='./archive_libs/logical/q_cap/chips/chips.prt';

PART_NAME
 C6028 'Q_CAP_0402-470PF,50V,10%,X7R,TMP_QCH14706KB18':
 ROOM='USB3_HUB1_CYP';

SECTION_NUMBER 1
 '@T6G_MB_LIB.T6G(SCH_1):PAGE153_I29@PURE_QUANTA.Q_CAP(CHIPS)':
 C_PATH='@t6g_mb_lib.t6g(sch_1):page153_i29@pure_quanta.q_cap(chips)',
 P_PATH='@t6g_mb_lib.t6g(sch_1):page176_i29@pure_quanta.q_cap(chips)',
 PATH='I29',
 DRAWING='@T6G_MB_LIB.T6G(SCH_1):PAGE153',
 TOLERANCE='10%',
 MATERIAL='X7R',
 PHYS_PAGE='176',
 XY='(-1075,6000)',
 ROT='0',
 VER='1',
 PACK_TYPE='0402',
 LOCATION='C6028',
 CDS_LIB='pure_quanta',
 CDS_PART_NAME='Q_CAP_0402-470PF,50V,10%,X7R,TMP_QCH14706KB18',
 VOLTAGE='50V',
 ROOM='USB3_HUB1_CYP',
 PART_NUMBER='TMP_QCH14706KB18',
 VALUE='470PF',
 PRIM_FILE='./archive_libs/logical/q_cap/chips/chips.prt';

PART_NAME
 C6030 'Q_CAP_C0603-22UF,6.3V,20%,X6S,CH6221ME900':
 ROOM='USB3_HUB1_CYP';

SECTION_NUMBER 1
 '@T6G_MB_LIB.T6G(SCH_1):PAGE154_I27@PURE_QUANTA.Q_CAP(CHIPS)':
 C_PATH='@t6g_mb_lib.t6g(sch_1):page154_i27@pure_quanta.q_cap(chips)',
 P_PATH='@t6g_mb_lib.t6g(sch_1):page177_i27@pure_quanta.q_cap(chips)',
 PATH='I27',
 DRAWING='@T6G_MB_LIB.T6G(SCH_1):PAGE154',
 TOLERANCE='20%',
 MATERIAL='X6S',
 PHYS_PAGE='177',
 XY='(-8200,5250)',
 ROT='2',
 VER='1',
 PACK_TYPE='C0603',
 LOCATION='C6030',
 CDS_LIB='pure_quanta',
 CDS_PART_NAME='Q_CAP_C0603-22UF,6.3V,20%,X6S,CH6221ME900',
 VOLTAGE='6.3V',
 ROOM='USB3_HUB1_CYP',
 PART_NUMBER='CH6221ME900',
 VALUE='22UF',
 PRIM_FILE='./archive_libs/logical/q_cap/chips/chips.prt';

PART_NAME
 C6031 'Q_CAP_C0402-1UF,25V,10%,X6S,CH5104KEB02':
 ROOM='USB3_HUB1_CYP';

SECTION_NUMBER 1
 '@T6G_MB_LIB.T6G(SCH_1):PAGE154_I29@PURE_QUANTA.Q_CAP(CHIPS)':
 C_PATH='@t6g_mb_lib.t6g(sch_1):page154_i29@pure_quanta.q_cap(chips)',
 P_PATH='@t6g_mb_lib.t6g(sch_1):page177_i29@pure_quanta.q_cap(chips)',
 PATH='I29',
 DRAWING='@T6G_MB_LIB.T6G(SCH_1):PAGE154',
 TOLERANCE='10%',
 MATERIAL='X6S',
 PHYS_PAGE='177',
 XY='(-7975,5250)',
 ROT='0',
 VER='1',
 PACK_TYPE='C0402',
 LOCATION='C6031',
 CDS_LIB='pure_quanta',
 CDS_PART_NAME='Q_CAP_C0402-1UF,25V,10%,X6S,CH5104KEB02',
 VOLTAGE='25V',
 ROOM='USB3_HUB1_CYP',
 PART_NUMBER='CH5104KEB02',
 VALUE='1UF',
 PRIM_FILE='./archive_libs/logical/q_cap/chips/chips.prt';

PART_NAME
 C6032 'Q_CAP_0402-0.1UF,25V,10%,X7R,CH4104K1B00':
 ROOM='USB3_HUB1_CYP';

SECTION_NUMBER 1
 '@T6G_MB_LIB.T6G(SCH_1):PAGE154_I35@PURE_QUANTA.Q_CAP(CHIPS)':
 C_PATH='@t6g_mb_lib.t6g(sch_1):page154_i35@pure_quanta.q_cap(chips)',
 P_PATH='@t6g_mb_lib.t6g(sch_1):page177_i35@pure_quanta.q_cap(chips)',
 PATH='I35',
 DRAWING='@T6G_MB_LIB.T6G(SCH_1):PAGE154',
 TOLERANCE='10%',
 MATERIAL='X7R',
 PHYS_PAGE='177',
 XY='(-7475,4925)',
 ROT='0',
 VER='1',
 PACK_TYPE='0402',
 LOCATION='C6032',
 CDS_LIB='pure_quanta',
 CDS_PART_NAME='Q_CAP_0402-0.1UF,25V,10%,X7R,CH4104K1B00',
 VOLTAGE='25V',
 ROOM='USB3_HUB1_CYP',
 PART_NUMBER='CH4104K1B00',
 VALUE='0.1UF',
 PRIM_FILE='./archive_libs/logical/q_cap/chips/chips.prt';

PART_NAME
 C6033 'Q_CAP_C0402-0.01UF,50V,10%,X7R,CH31006KB18':
 ROOM='USB3_HUB1_CYP';

SECTION_NUMBER 1
 '@T6G_MB_LIB.T6G(SCH_1):PAGE154_I34@PURE_QUANTA.Q_CAP(CHIPS)':
 C_PATH='@t6g_mb_lib.t6g(sch_1):page154_i34@pure_quanta.q_cap(chips)',
 P_PATH='@t6g_mb_lib.t6g(sch_1):page177_i34@pure_quanta.q_cap(chips)',
 PATH='I34',
 DRAWING='@T6G_MB_LIB.T6G(SCH_1):PAGE154',
 TOLERANCE='10%',
 MATERIAL='X7R',
 PHYS_PAGE='177',
 XY='(-7225,4925)',
 ROT='0',
 VER='1',
 PACK_TYPE='C0402',
 LOCATION='C6033',
 CDS_LIB='pure_quanta',
 CDS_PART_NAME='Q_CAP_C0402-0.01UF,50V,10%,X7R,CH31006KB18',
 VOLTAGE='50V',
 ROOM='USB3_HUB1_CYP',
 PART_NUMBER='CH31006KB18',
 VALUE='0.01UF',
 PRIM_FILE='./archive_libs/logical/q_cap/chips/chips.prt';

PART_NAME
 C6034 'Q_CAP_0402-0.1UF,25V,10%,X7R,CH4104K1B00':
 ROOM='USB3_HUB1_CYP';

SECTION_NUMBER 1
 '@T6G_MB_LIB.T6G(SCH_1):PAGE154_I32@PURE_QUANTA.Q_CAP(CHIPS)':
 C_PATH='@t6g_mb_lib.t6g(sch_1):page154_i32@pure_quanta.q_cap(chips)',
 P_PATH='@t6g_mb_lib.t6g(sch_1):page177_i32@pure_quanta.q_cap(chips)',
 PATH='I32',
 DRAWING='@T6G_MB_LIB.T6G(SCH_1):PAGE154',
 TOLERANCE='10%',
 MATERIAL='X7R',
 PHYS_PAGE='177',
 XY='(-6950,4925)',
 ROT='0',
 VER='1',
 PACK_TYPE='0402',
 LOCATION='C6034',
 CDS_LIB='pure_quanta',
 CDS_PART_NAME='Q_CAP_0402-0.1UF,25V,10%,X7R,CH4104K1B00',
 VOLTAGE='25V',
 ROOM='USB3_HUB1_CYP',
 PART_NUMBER='CH4104K1B00',
 VALUE='0.1UF',
 PRIM_FILE='./archive_libs/logical/q_cap/chips/chips.prt';

PART_NAME
 C6035 'Q_CAP_C0402-0.01UF,50V,10%,X7R,CH31006KB18':
 ROOM='USB3_HUB1_CYP';

SECTION_NUMBER 1
 '@T6G_MB_LIB.T6G(SCH_1):PAGE154_I31@PURE_QUANTA.Q_CAP(CHIPS)':
 C_PATH='@t6g_mb_lib.t6g(sch_1):page154_i31@pure_quanta.q_cap(chips)',
 P_PATH='@t6g_mb_lib.t6g(sch_1):page177_i31@pure_quanta.q_cap(chips)',
 PATH='I31',
 DRAWING='@T6G_MB_LIB.T6G(SCH_1):PAGE154',
 TOLERANCE='10%',
 MATERIAL='X7R',
 PHYS_PAGE='177',
 XY='(-6725,4900)',
 ROT='0',
 VER='1',
 PACK_TYPE='C0402',
 LOCATION='C6035',
 CDS_LIB='pure_quanta',
 CDS_PART_NAME='Q_CAP_C0402-0.01UF,50V,10%,X7R,CH31006KB18',
 VOLTAGE='50V',
 ROOM='USB3_HUB1_CYP',
 PART_NUMBER='CH31006KB18',
 VALUE='0.01UF',
 PRIM_FILE='./archive_libs/logical/q_cap/chips/chips.prt';

PART_NAME
 C6036 'Q_CAP_0402-0.1UF,25V,10%,X7R,CH4104K1B00':
 ROOM='USB3_HUB1_CYP';

SECTION_NUMBER 1
 '@T6G_MB_LIB.T6G(SCH_1):PAGE154_I37@PURE_QUANTA.Q_CAP(CHIPS)':
 C_PATH='@t6g_mb_lib.t6g(sch_1):page154_i37@pure_quanta.q_cap(chips)',
 P_PATH='@t6g_mb_lib.t6g(sch_1):page177_i37@pure_quanta.q_cap(chips)',
 PATH='I37',
 DRAWING='@T6G_MB_LIB.T6G(SCH_1):PAGE154',
 TOLERANCE='10%',
 MATERIAL='X7R',
 PHYS_PAGE='177',
 XY='(-6450,4925)',
 ROT='0',
 VER='1',
 PACK_TYPE='0402',
 LOCATION='C6036',
 CDS_LIB='pure_quanta',
 CDS_PART_NAME='Q_CAP_0402-0.1UF,25V,10%,X7R,CH4104K1B00',
 VOLTAGE='25V',
 ROOM='USB3_HUB1_CYP',
 PART_NUMBER='CH4104K1B00',
 VALUE='0.1UF',
 PRIM_FILE='./archive_libs/logical/q_cap/chips/chips.prt';

PART_NAME
 C6037 'Q_CAP_C0402-0.01UF,50V,10%,X7R,CH31006KB18':
 ROOM='USB3_HUB1_CYP';

SECTION_NUMBER 1
 '@T6G_MB_LIB.T6G(SCH_1):PAGE154_I38@PURE_QUANTA.Q_CAP(CHIPS)':
 C_PATH='@t6g_mb_lib.t6g(sch_1):page154_i38@pure_quanta.q_cap(chips)',
 P_PATH='@t6g_mb_lib.t6g(sch_1):page177_i38@pure_quanta.q_cap(chips)',
 PATH='I38',
 DRAWING='@T6G_MB_LIB.T6G(SCH_1):PAGE154',
 TOLERANCE='10%',
 MATERIAL='X7R',
 PHYS_PAGE='177',
 XY='(-6225,4925)',
 ROT='0',
 VER='1',
 PACK_TYPE='C0402',
 LOCATION='C6037',
 CDS_LIB='pure_quanta',
 CDS_PART_NAME='Q_CAP_C0402-0.01UF,50V,10%,X7R,CH31006KB18',
 VOLTAGE='50V',
 ROOM='USB3_HUB1_CYP',
 PART_NUMBER='CH31006KB18',
 VALUE='0.01UF',
 PRIM_FILE='./archive_libs/logical/q_cap/chips/chips.prt';

PART_NAME
 C6038 'Q_CAP_0402-0.1UF,25V,10%,X7R,CH4104K1B00':
 ROOM='USB3_HUB1_CYP';

SECTION_NUMBER 1
 '@T6G_MB_LIB.T6G(SCH_1):PAGE154_I41@PURE_QUANTA.Q_CAP(CHIPS)':
 C_PATH='@t6g_mb_lib.t6g(sch_1):page154_i41@pure_quanta.q_cap(chips)',
 P_PATH='@t6g_mb_lib.t6g(sch_1):page177_i41@pure_quanta.q_cap(chips)',
 PATH='I41',
 DRAWING='@T6G_MB_LIB.T6G(SCH_1):PAGE154',
 TOLERANCE='10%',
 MATERIAL='X7R',
 PHYS_PAGE='177',
 XY='(-5875,4900)',
 ROT='0',
 VER='1',
 PACK_TYPE='0402',
 LOCATION='C6038',
 CDS_LIB='pure_quanta',
 CDS_PART_NAME='Q_CAP_0402-0.1UF,25V,10%,X7R,CH4104K1B00',
 VOLTAGE='25V',
 ROOM='USB3_HUB1_CYP',
 PART_NUMBER='CH4104K1B00',
 VALUE='0.1UF',
 PRIM_FILE='./archive_libs/logical/q_cap/chips/chips.prt';

PART_NAME
 C6039 'Q_CAP_C0402-0.01UF,50V,10%,X7R,CH31006KB18':
 ROOM='USB3_HUB1_CYP';

SECTION_NUMBER 1
 '@T6G_MB_LIB.T6G(SCH_1):PAGE154_I40@PURE_QUANTA.Q_CAP(CHIPS)':
 C_PATH='@t6g_mb_lib.t6g(sch_1):page154_i40@pure_quanta.q_cap(chips)',
 P_PATH='@t6g_mb_lib.t6g(sch_1):page177_i40@pure_quanta.q_cap(chips)',
 PATH='I40',
 DRAWING='@T6G_MB_LIB.T6G(SCH_1):PAGE154',
 TOLERANCE='10%',
 MATERIAL='X7R',
 PHYS_PAGE='177',
 XY='(-5650,4900)',
 ROT='0',
 VER='1',
 PACK_TYPE='C0402',
 LOCATION='C6039',
 CDS_LIB='pure_quanta',
 CDS_PART_NAME='Q_CAP_C0402-0.01UF,50V,10%,X7R,CH31006KB18',
 VOLTAGE='50V',
 ROOM='USB3_HUB1_CYP',
 PART_NUMBER='CH31006KB18',
 VALUE='0.01UF',
 PRIM_FILE='./archive_libs/logical/q_cap/chips/chips.prt';

PART_NAME
 C6040 'Q_CAP_C0402-0.01UF,50V,10%,X7R,CH31006KB18':
 ROOM='USB3_HUB1_CYP';

SECTION_NUMBER 1
 '@T6G_MB_LIB.T6G(SCH_1):PAGE154_I5@PURE_QUANTA.Q_CAP(CHIPS)':
 C_PATH='@t6g_mb_lib.t6g(sch_1):page154_i5@pure_quanta.q_cap(chips)',
 P_PATH='@t6g_mb_lib.t6g(sch_1):page177_i5@pure_quanta.q_cap(chips)',
 PATH='I5',
 DRAWING='@T6G_MB_LIB.T6G(SCH_1):PAGE154',
 TOLERANCE='10%',
 MATERIAL='X7R',
 PHYS_PAGE='177',
 XY='(-6850,3900)',
 ROT='0',
 VER='1',
 PACK_TYPE='C0402',
 LOCATION='C6040',
 CDS_LIB='pure_quanta',
 CDS_PART_NAME='Q_CAP_C0402-0.01UF,50V,10%,X7R,CH31006KB18',
 VOLTAGE='50V',
 ROOM='USB3_HUB1_CYP',
 PART_NUMBER='CH31006KB18',
 VALUE='0.01UF',
 PRIM_FILE='./archive_libs/logical/q_cap/chips/chips.prt';

PART_NAME
 C6041 'Q_CAP_0402-0.1UF,25V,10%,X7R,CH4104K1B00':
 ROOM='USB3_HUB1_CYP';

SECTION_NUMBER 1
 '@T6G_MB_LIB.T6G(SCH_1):PAGE154_I7@PURE_QUANTA.Q_CAP(CHIPS)':
 C_PATH='@t6g_mb_lib.t6g(sch_1):page154_i7@pure_quanta.q_cap(chips)',
 P_PATH='@t6g_mb_lib.t6g(sch_1):page177_i7@pure_quanta.q_cap(chips)',
 PATH='I7',
 DRAWING='@T6G_MB_LIB.T6G(SCH_1):PAGE154',
 TOLERANCE='10%',
 MATERIAL='X7R',
 PHYS_PAGE='177',
 XY='(-6425,3900)',
 ROT='0',
 VER='1',
 PACK_TYPE='0402',
 LOCATION='C6041',
 CDS_LIB='pure_quanta',
 CDS_PART_NAME='Q_CAP_0402-0.1UF,25V,10%,X7R,CH4104K1B00',
 VOLTAGE='25V',
 ROOM='USB3_HUB1_CYP',
 PART_NUMBER='CH4104K1B00',
 VALUE='0.1UF',
 PRIM_FILE='./archive_libs/logical/q_cap/chips/chips.prt';

PART_NAME
 C6042 'Q_CAP_C0603-22UF,6.3V,20%,X6S,CH6221ME900':
 ROOM='USB3_HUB1_CYP';

SECTION_NUMBER 1
 '@T6G_MB_LIB.T6G(SCH_1):PAGE154_I9@PURE_QUANTA.Q_CAP(CHIPS)':
 C_PATH='@t6g_mb_lib.t6g(sch_1):page154_i9@pure_quanta.q_cap(chips)',
 P_PATH='@t6g_mb_lib.t6g(sch_1):page177_i9@pure_quanta.q_cap(chips)',
 PATH='I9',
 DRAWING='@T6G_MB_LIB.T6G(SCH_1):PAGE154',
 TOLERANCE='20%',
 MATERIAL='X6S',
 PHYS_PAGE='177',
 XY='(-7450,3200)',
 ROT='0',
 VER='1',
 PACK_TYPE='C0603',
 LOCATION='C6042',
 CDS_LIB='pure_quanta',
 CDS_PART_NAME='Q_CAP_C0603-22UF,6.3V,20%,X6S,CH6221ME900',
 VOLTAGE='6.3V',
 ROOM='USB3_HUB1_CYP',
 PART_NUMBER='CH6221ME900',
 VALUE='22UF',
 PRIM_FILE='./archive_libs/logical/q_cap/chips/chips.prt';

PART_NAME
 C6043 'Q_CAP_C0402-1UF,25V,10%,X6S,CH5104KEB02':
 ROOM='USB3_HUB1_CYP';

SECTION_NUMBER 1
 '@T6G_MB_LIB.T6G(SCH_1):PAGE154_I10@PURE_QUANTA.Q_CAP(CHIPS)':
 C_PATH='@t6g_mb_lib.t6g(sch_1):page154_i10@pure_quanta.q_cap(chips)',
 P_PATH='@t6g_mb_lib.t6g(sch_1):page177_i10@pure_quanta.q_cap(chips)',
 PATH='I10',
 DRAWING='@T6G_MB_LIB.T6G(SCH_1):PAGE154',
 TOLERANCE='10%',
 MATERIAL='X6S',
 PHYS_PAGE='177',
 XY='(-6975,3200)',
 ROT='0',
 VER='1',
 PACK_TYPE='C0402',
 LOCATION='C6043',
 CDS_LIB='pure_quanta',
 CDS_PART_NAME='Q_CAP_C0402-1UF,25V,10%,X6S,CH5104KEB02',
 VOLTAGE='25V',
 ROOM='USB3_HUB1_CYP',
 PART_NUMBER='CH5104KEB02',
 VALUE='1UF',
 PRIM_FILE='./archive_libs/logical/q_cap/chips/chips.prt';

PART_NAME
 C6044 'Q_CAP_0402-0.1UF,25V,10%,X7R,CH4104K1B00':
 ROOM='USB3_HUB1_CYP';

SECTION_NUMBER 1
 '@T6G_MB_LIB.T6G(SCH_1):PAGE154_I12@PURE_QUANTA.Q_CAP(CHIPS)':
 C_PATH='@t6g_mb_lib.t6g(sch_1):page154_i12@pure_quanta.q_cap(chips)',
 P_PATH='@t6g_mb_lib.t6g(sch_1):page177_i12@pure_quanta.q_cap(chips)',
 PATH='I12',
 DRAWING='@T6G_MB_LIB.T6G(SCH_1):PAGE154',
 TOLERANCE='10%',
 MATERIAL='X7R',
 PHYS_PAGE='177',
 XY='(-6450,3225)',
 ROT='0',
 VER='1',
 PACK_TYPE='0402',
 LOCATION='C6044',
 CDS_LIB='pure_quanta',
 CDS_PART_NAME='Q_CAP_0402-0.1UF,25V,10%,X7R,CH4104K1B00',
 VOLTAGE='25V',
 ROOM='USB3_HUB1_CYP',
 PART_NUMBER='CH4104K1B00',
 VALUE='0.1UF',
 PRIM_FILE='./archive_libs/logical/q_cap/chips/chips.prt';

PART_NAME
 C6045 'Q_CAP_C0402-0.01UF,50V,10%,X7R,CH31006KB18':
 ROOM='USB3_HUB1_CYP';

SECTION_NUMBER 1
 '@T6G_MB_LIB.T6G(SCH_1):PAGE154_I13@PURE_QUANTA.Q_CAP(CHIPS)':
 C_PATH='@t6g_mb_lib.t6g(sch_1):page154_i13@pure_quanta.q_cap(chips)',
 P_PATH='@t6g_mb_lib.t6g(sch_1):page177_i13@pure_quanta.q_cap(chips)',
 PATH='I13',
 DRAWING='@T6G_MB_LIB.T6G(SCH_1):PAGE154',
 TOLERANCE='10%',
 MATERIAL='X7R',
 PHYS_PAGE='177',
 XY='(-5950,3200)',
 ROT='0',
 VER='1',
 PACK_TYPE='C0402',
 LOCATION='C6045',
 CDS_LIB='pure_quanta',
 CDS_PART_NAME='Q_CAP_C0402-0.01UF,50V,10%,X7R,CH31006KB18',
 VOLTAGE='50V',
 ROOM='USB3_HUB1_CYP',
 PART_NUMBER='CH31006KB18',
 VALUE='0.01UF',
 PRIM_FILE='./archive_libs/logical/q_cap/chips/chips.prt';

PART_NAME
 C6046 'Q_CAP_C0603-22UF,6.3V,20%,X6S,CH6221ME900':
 ROOM='USB3_HUB1_CYP';

SECTION_NUMBER 1
 '@T6G_MB_LIB.T6G(SCH_1):PAGE154_I14@PURE_QUANTA.Q_CAP(CHIPS)':
 C_PATH='@t6g_mb_lib.t6g(sch_1):page154_i14@pure_quanta.q_cap(chips)',
 P_PATH='@t6g_mb_lib.t6g(sch_1):page177_i14@pure_quanta.q_cap(chips)',
 PATH='I14',
 DRAWING='@T6G_MB_LIB.T6G(SCH_1):PAGE154',
 TOLERANCE='20%',
 MATERIAL='X6S',
 PHYS_PAGE='177',
 XY='(-8350,2225)',
 ROT='2',
 VER='1',
 PACK_TYPE='C0603',
 LOCATION='C6046',
 CDS_LIB='pure_quanta',
 CDS_PART_NAME='Q_CAP_C0603-22UF,6.3V,20%,X6S,CH6221ME900',
 VOLTAGE='6.3V',
 ROOM='USB3_HUB1_CYP',
 PART_NUMBER='CH6221ME900',
 VALUE='22UF',
 PRIM_FILE='./archive_libs/logical/q_cap/chips/chips.prt';

PART_NAME
 C6047 'Q_CAP_C0402-1UF,25V,10%,X6S,CH5104KEB02':
 ROOM='USB3_HUB1_CYP';

SECTION_NUMBER 1
 '@T6G_MB_LIB.T6G(SCH_1):PAGE154_I15@PURE_QUANTA.Q_CAP(CHIPS)':
 C_PATH='@t6g_mb_lib.t6g(sch_1):page154_i15@pure_quanta.q_cap(chips)',
 P_PATH='@t6g_mb_lib.t6g(sch_1):page177_i15@pure_quanta.q_cap(chips)',
 PATH='I15',
 DRAWING='@T6G_MB_LIB.T6G(SCH_1):PAGE154',
 TOLERANCE='10%',
 MATERIAL='X6S',
 PHYS_PAGE='177',
 XY='(-8150,2225)',
 ROT='0',
 VER='1',
 PACK_TYPE='C0402',
 LOCATION='C6047',
 CDS_LIB='pure_quanta',
 CDS_PART_NAME='Q_CAP_C0402-1UF,25V,10%,X6S,CH5104KEB02',
 VOLTAGE='25V',
 ROOM='USB3_HUB1_CYP',
 PART_NUMBER='CH5104KEB02',
 VALUE='1UF',
 PRIM_FILE='./archive_libs/logical/q_cap/chips/chips.prt';

PART_NAME
 C6048 'Q_CAP_0402-0.1UF,25V,10%,X7R,CH4104K1B00':
 ROOM='USB3_HUB1_CYP';

SECTION_NUMBER 1
 '@T6G_MB_LIB.T6G(SCH_1):PAGE154_I17@PURE_QUANTA.Q_CAP(CHIPS)':
 C_PATH='@t6g_mb_lib.t6g(sch_1):page154_i17@pure_quanta.q_cap(chips)',
 P_PATH='@t6g_mb_lib.t6g(sch_1):page177_i17@pure_quanta.q_cap(chips)',
 PATH='I17',
 DRAWING='@T6G_MB_LIB.T6G(SCH_1):PAGE154',
 TOLERANCE='10%',
 MATERIAL='X7R',
 PHYS_PAGE='177',
 XY='(-7525,2125)',
 ROT='0',
 VER='1',
 PACK_TYPE='0402',
 LOCATION='C6048',
 CDS_LIB='pure_quanta',
 CDS_PART_NAME='Q_CAP_0402-0.1UF,25V,10%,X7R,CH4104K1B00',
 VOLTAGE='25V',
 ROOM='USB3_HUB1_CYP',
 PART_NUMBER='CH4104K1B00',
 VALUE='0.1UF',
 PRIM_FILE='./archive_libs/logical/q_cap/chips/chips.prt';

PART_NAME
 C6049 'Q_CAP_C0402-0.01UF,50V,10%,X7R,CH31006KB18':
 ROOM='USB3_HUB1_CYP';

SECTION_NUMBER 1
 '@T6G_MB_LIB.T6G(SCH_1):PAGE154_I19@PURE_QUANTA.Q_CAP(CHIPS)':
 C_PATH='@t6g_mb_lib.t6g(sch_1):page154_i19@pure_quanta.q_cap(chips)',
 P_PATH='@t6g_mb_lib.t6g(sch_1):page177_i19@pure_quanta.q_cap(chips)',
 PATH='I19',
 DRAWING='@T6G_MB_LIB.T6G(SCH_1):PAGE154',
 TOLERANCE='10%',
 MATERIAL='X7R',
 PHYS_PAGE='177',
 XY='(-7175,2125)',
 ROT='0',
 VER='1',
 PACK_TYPE='C0402',
 LOCATION='C6049',
 CDS_LIB='pure_quanta',
 CDS_PART_NAME='Q_CAP_C0402-0.01UF,50V,10%,X7R,CH31006KB18',
 VOLTAGE='50V',
 ROOM='USB3_HUB1_CYP',
 PART_NUMBER='CH31006KB18',
 VALUE='0.01UF',
 PRIM_FILE='./archive_libs/logical/q_cap/chips/chips.prt';

PART_NAME
 C6050 'Q_CAP_0402-0.1UF,25V,10%,X7R,CH4104K1B00':
 ROOM='USB3_HUB1_CYP';

SECTION_NUMBER 1
 '@T6G_MB_LIB.T6G(SCH_1):PAGE154_I20@PURE_QUANTA.Q_CAP(CHIPS)':
 C_PATH='@t6g_mb_lib.t6g(sch_1):page154_i20@pure_quanta.q_cap(chips)',
 P_PATH='@t6g_mb_lib.t6g(sch_1):page177_i20@pure_quanta.q_cap(chips)',
 PATH='I20',
 DRAWING='@T6G_MB_LIB.T6G(SCH_1):PAGE154',
 TOLERANCE='10%',
 MATERIAL='X7R',
 PHYS_PAGE='177',
 XY='(-6725,2125)',
 ROT='0',
 VER='1',
 PACK_TYPE='0402',
 LOCATION='C6050',
 CDS_LIB='pure_quanta',
 CDS_PART_NAME='Q_CAP_0402-0.1UF,25V,10%,X7R,CH4104K1B00',
 VOLTAGE='25V',
 ROOM='USB3_HUB1_CYP',
 PART_NUMBER='CH4104K1B00',
 VALUE='0.1UF',
 PRIM_FILE='./archive_libs/logical/q_cap/chips/chips.prt';

PART_NAME
 C6051 'Q_CAP_C0402-0.01UF,50V,10%,X7R,CH31006KB18':
 ROOM='USB3_HUB1_CYP';

SECTION_NUMBER 1
 '@T6G_MB_LIB.T6G(SCH_1):PAGE154_I21@PURE_QUANTA.Q_CAP(CHIPS)':
 C_PATH='@t6g_mb_lib.t6g(sch_1):page154_i21@pure_quanta.q_cap(chips)',
 P_PATH='@t6g_mb_lib.t6g(sch_1):page177_i21@pure_quanta.q_cap(chips)',
 PATH='I21',
 DRAWING='@T6G_MB_LIB.T6G(SCH_1):PAGE154',
 TOLERANCE='10%',
 MATERIAL='X7R',
 PHYS_PAGE='177',
 XY='(-6400,2125)',
 ROT='0',
 VER='1',
 PACK_TYPE='C0402',
 LOCATION='C6051',
 CDS_LIB='pure_quanta',
 CDS_PART_NAME='Q_CAP_C0402-0.01UF,50V,10%,X7R,CH31006KB18',
 VOLTAGE='50V',
 ROOM='USB3_HUB1_CYP',
 PART_NUMBER='CH31006KB18',
 VALUE='0.01UF',
 PRIM_FILE='./archive_libs/logical/q_cap/chips/chips.prt';

PART_NAME
 C6052 'Q_CAP_0402-0.1UF,25V,10%,X7R,CH4104K1B00':
 ROOM='USB3_HUB1_CYP';

SECTION_NUMBER 1
 '@T6G_MB_LIB.T6G(SCH_1):PAGE154_I23@PURE_QUANTA.Q_CAP(CHIPS)':
 C_PATH='@t6g_mb_lib.t6g(sch_1):page154_i23@pure_quanta.q_cap(chips)',
 P_PATH='@t6g_mb_lib.t6g(sch_1):page177_i23@pure_quanta.q_cap(chips)',
 PATH='I23',
 DRAWING='@T6G_MB_LIB.T6G(SCH_1):PAGE154',
 TOLERANCE='10%',
 MATERIAL='X7R',
 PHYS_PAGE='177',
 XY='(-6025,2125)',
 ROT='0',
 VER='1',
 PACK_TYPE='0402',
 LOCATION='C6052',
 CDS_LIB='pure_quanta',
 CDS_PART_NAME='Q_CAP_0402-0.1UF,25V,10%,X7R,CH4104K1B00',
 VOLTAGE='25V',
 ROOM='USB3_HUB1_CYP',
 PART_NUMBER='CH4104K1B00',
 VALUE='0.1UF',
 PRIM_FILE='./archive_libs/logical/q_cap/chips/chips.prt';

PART_NAME
 C6053 'Q_CAP_C0402-0.01UF,50V,10%,X7R,CH31006KB18':
 ROOM='USB3_HUB1_CYP';

SECTION_NUMBER 1
 '@T6G_MB_LIB.T6G(SCH_1):PAGE154_I22@PURE_QUANTA.Q_CAP(CHIPS)':
 C_PATH='@t6g_mb_lib.t6g(sch_1):page154_i22@pure_quanta.q_cap(chips)',
 P_PATH='@t6g_mb_lib.t6g(sch_1):page177_i22@pure_quanta.q_cap(chips)',
 PATH='I22',
 DRAWING='@T6G_MB_LIB.T6G(SCH_1):PAGE154',
 TOLERANCE='10%',
 MATERIAL='X7R',
 PHYS_PAGE='177',
 XY='(-5725,2125)',
 ROT='0',
 VER='1',
 PACK_TYPE='C0402',
 LOCATION='C6053',
 CDS_LIB='pure_quanta',
 CDS_PART_NAME='Q_CAP_C0402-0.01UF,50V,10%,X7R,CH31006KB18',
 VOLTAGE='50V',
 ROOM='USB3_HUB1_CYP',
 PART_NUMBER='CH31006KB18',
 VALUE='0.01UF',
 PRIM_FILE='./archive_libs/logical/q_cap/chips/chips.prt';

PART_NAME
 C6054 'Q_CAP_C0402-0.001UF,50V,10%,X7R,CH30106KB19':
 ROOM='USB3_HUB1_CYP';

SECTION_NUMBER 1
 '@T6G_MB_LIB.T6G(SCH_1):PAGE154_I43@PURE_QUANTA.Q_CAP(CHIPS)':
 C_PATH='@t6g_mb_lib.t6g(sch_1):page154_i43@pure_quanta.q_cap(chips)',
 P_PATH='@t6g_mb_lib.t6g(sch_1):page177_i43@pure_quanta.q_cap(chips)',
 PATH='I43',
 DRAWING='@T6G_MB_LIB.T6G(SCH_1):PAGE154',
 TOLERANCE='10%',
 MATERIAL='X7R',
 PHYS_PAGE='177',
 XY='(-3750,4850)',
 ROT='0',
 VER='1',
 PACK_TYPE='C0402',
 LOCATION='C6054',
 CDS_LIB='pure_quanta',
 CDS_PART_NAME='Q_CAP_C0402-0.001UF,50V,10%,X7R,CH30106KB19',
 VOLTAGE='50V',
 ROOM='USB3_HUB1_CYP',
 PART_NUMBER='CH30106KB19',
 VALUE='0.001UF',
 PRIM_FILE='./archive_libs/logical/q_cap/chips/chips.prt';

PART_NAME
 C6055 'Q_CAP_C0402-0.01UF,50V,10%,X7R,CH31006KB18':
 ROOM='USB3_HUB1_CYP';

SECTION_NUMBER 1
 '@T6G_MB_LIB.T6G(SCH_1):PAGE154_I44@PURE_QUANTA.Q_CAP(CHIPS)':
 C_PATH='@t6g_mb_lib.t6g(sch_1):page154_i44@pure_quanta.q_cap(chips)',
 P_PATH='@t6g_mb_lib.t6g(sch_1):page177_i44@pure_quanta.q_cap(chips)',
 PATH='I44',
 DRAWING='@T6G_MB_LIB.T6G(SCH_1):PAGE154',
 TOLERANCE='10%',
 MATERIAL='X7R',
 PHYS_PAGE='177',
 XY='(-3500,4850)',
 ROT='0',
 VER='1',
 PACK_TYPE='C0402',
 LOCATION='C6055',
 CDS_LIB='pure_quanta',
 CDS_PART_NAME='Q_CAP_C0402-0.01UF,50V,10%,X7R,CH31006KB18',
 VOLTAGE='50V',
 ROOM='USB3_HUB1_CYP',
 PART_NUMBER='CH31006KB18',
 VALUE='0.01UF',
 PRIM_FILE='./archive_libs/logical/q_cap/chips/chips.prt';

PART_NAME
 C6056 'Q_CAP_C0402-0.001UF,50V,10%,X7R,CH30106KB19':
 ROOM='USB3_HUB1_CYP';

SECTION_NUMBER 1
 '@T6G_MB_LIB.T6G(SCH_1):PAGE154_I46@PURE_QUANTA.Q_CAP(CHIPS)':
 C_PATH='@t6g_mb_lib.t6g(sch_1):page154_i46@pure_quanta.q_cap(chips)',
 P_PATH='@t6g_mb_lib.t6g(sch_1):page177_i46@pure_quanta.q_cap(chips)',
 PATH='I46',
 DRAWING='@T6G_MB_LIB.T6G(SCH_1):PAGE154',
 TOLERANCE='10%',
 MATERIAL='X7R',
 PHYS_PAGE='177',
 XY='(-3250,4850)',
 ROT='0',
 VER='1',
 PACK_TYPE='C0402',
 LOCATION='C6056',
 CDS_LIB='pure_quanta',
 CDS_PART_NAME='Q_CAP_C0402-0.001UF,50V,10%,X7R,CH30106KB19',
 VOLTAGE='50V',
 ROOM='USB3_HUB1_CYP',
 PART_NUMBER='CH30106KB19',
 VALUE='0.001UF',
 PRIM_FILE='./archive_libs/logical/q_cap/chips/chips.prt';

PART_NAME
 C6057 'Q_CAP_C0402-0.01UF,50V,10%,X7R,CH31006KB18':
 ROOM='USB3_HUB1_CYP';

SECTION_NUMBER 1
 '@T6G_MB_LIB.T6G(SCH_1):PAGE154_I47@PURE_QUANTA.Q_CAP(CHIPS)':
 C_PATH='@t6g_mb_lib.t6g(sch_1):page154_i47@pure_quanta.q_cap(chips)',
 P_PATH='@t6g_mb_lib.t6g(sch_1):page177_i47@pure_quanta.q_cap(chips)',
 PATH='I47',
 DRAWING='@T6G_MB_LIB.T6G(SCH_1):PAGE154',
 TOLERANCE='10%',
 MATERIAL='X7R',
 PHYS_PAGE='177',
 XY='(-3000,4850)',
 ROT='0',
 VER='1',
 PACK_TYPE='C0402',
 LOCATION='C6057',
 CDS_LIB='pure_quanta',
 CDS_PART_NAME='Q_CAP_C0402-0.01UF,50V,10%,X7R,CH31006KB18',
 VOLTAGE='50V',
 ROOM='USB3_HUB1_CYP',
 PART_NUMBER='CH31006KB18',
 VALUE='0.01UF',
 PRIM_FILE='./archive_libs/logical/q_cap/chips/chips.prt';

PART_NAME
 C6058 'Q_CAP_C0402-0.001UF,50V,10%,X7R,CH30106KB19':
 ROOM='USB3_HUB1_CYP';

SECTION_NUMBER 1
 '@T6G_MB_LIB.T6G(SCH_1):PAGE154_I49@PURE_QUANTA.Q_CAP(CHIPS)':
 C_PATH='@t6g_mb_lib.t6g(sch_1):page154_i49@pure_quanta.q_cap(chips)',
 P_PATH='@t6g_mb_lib.t6g(sch_1):page177_i49@pure_quanta.q_cap(chips)',
 PATH='I49',
 DRAWING='@T6G_MB_LIB.T6G(SCH_1):PAGE154',
 TOLERANCE='10%',
 MATERIAL='X7R',
 PHYS_PAGE='177',
 XY='(-2650,4850)',
 ROT='0',
 VER='1',
 PACK_TYPE='C0402',
 LOCATION='C6058',
 CDS_LIB='pure_quanta',
 CDS_PART_NAME='Q_CAP_C0402-0.001UF,50V,10%,X7R,CH30106KB19',
 VOLTAGE='50V',
 ROOM='USB3_HUB1_CYP',
 PART_NUMBER='CH30106KB19',
 VALUE='0.001UF',
 PRIM_FILE='./archive_libs/logical/q_cap/chips/chips.prt';

PART_NAME
 C6059 'Q_CAP_C0402-0.01UF,50V,10%,X7R,CH31006KB18':
 ROOM='USB3_HUB1_CYP';

SECTION_NUMBER 1
 '@T6G_MB_LIB.T6G(SCH_1):PAGE154_I50@PURE_QUANTA.Q_CAP(CHIPS)':
 C_PATH='@t6g_mb_lib.t6g(sch_1):page154_i50@pure_quanta.q_cap(chips)',
 P_PATH='@t6g_mb_lib.t6g(sch_1):page177_i50@pure_quanta.q_cap(chips)',
 PATH='I50',
 DRAWING='@T6G_MB_LIB.T6G(SCH_1):PAGE154',
 TOLERANCE='10%',
 MATERIAL='X7R',
 PHYS_PAGE='177',
 XY='(-2400,4850)',
 ROT='0',
 VER='1',
 PACK_TYPE='C0402',
 LOCATION='C6059',
 CDS_LIB='pure_quanta',
 CDS_PART_NAME='Q_CAP_C0402-0.01UF,50V,10%,X7R,CH31006KB18',
 VOLTAGE='50V',
 ROOM='USB3_HUB1_CYP',
 PART_NUMBER='CH31006KB18',
 VALUE='0.01UF',
 PRIM_FILE='./archive_libs/logical/q_cap/chips/chips.prt';

PART_NAME
 C6060 'Q_CAP_C0402-0.001UF,50V,10%,X7R,CH30106KB19':
 ROOM='USB3_HUB1_CYP';

SECTION_NUMBER 1
 '@T6G_MB_LIB.T6G(SCH_1):PAGE154_I52@PURE_QUANTA.Q_CAP(CHIPS)':
 C_PATH='@t6g_mb_lib.t6g(sch_1):page154_i52@pure_quanta.q_cap(chips)',
 P_PATH='@t6g_mb_lib.t6g(sch_1):page177_i52@pure_quanta.q_cap(chips)',
 PATH='I52',
 DRAWING='@T6G_MB_LIB.T6G(SCH_1):PAGE154',
 TOLERANCE='10%',
 MATERIAL='X7R',
 PHYS_PAGE='177',
 XY='(-2025,4850)',
 ROT='0',
 VER='1',
 PACK_TYPE='C0402',
 LOCATION='C6060',
 CDS_LIB='pure_quanta',
 CDS_PART_NAME='Q_CAP_C0402-0.001UF,50V,10%,X7R,CH30106KB19',
 VOLTAGE='50V',
 ROOM='USB3_HUB1_CYP',
 PART_NUMBER='CH30106KB19',
 VALUE='0.001UF',
 PRIM_FILE='./archive_libs/logical/q_cap/chips/chips.prt';

PART_NAME
 C6061 'Q_CAP_C0402-0.01UF,50V,10%,X7R,CH31006KB18':
 ROOM='USB3_HUB1_CYP';

SECTION_NUMBER 1
 '@T6G_MB_LIB.T6G(SCH_1):PAGE154_I53@PURE_QUANTA.Q_CAP(CHIPS)':
 C_PATH='@t6g_mb_lib.t6g(sch_1):page154_i53@pure_quanta.q_cap(chips)',
 P_PATH='@t6g_mb_lib.t6g(sch_1):page177_i53@pure_quanta.q_cap(chips)',
 PATH='I53',
 DRAWING='@T6G_MB_LIB.T6G(SCH_1):PAGE154',
 TOLERANCE='10%',
 MATERIAL='X7R',
 PHYS_PAGE='177',
 XY='(-1775,4850)',
 ROT='0',
 VER='1',
 PACK_TYPE='C0402',
 LOCATION='C6061',
 CDS_LIB='pure_quanta',
 CDS_PART_NAME='Q_CAP_C0402-0.01UF,50V,10%,X7R,CH31006KB18',
 VOLTAGE='50V',
 ROOM='USB3_HUB1_CYP',
 PART_NUMBER='CH31006KB18',
 VALUE='0.01UF',
 PRIM_FILE='./archive_libs/logical/q_cap/chips/chips.prt';

PART_NAME
 C6062 'Q_CAP_C0402-0.001UF,50V,10%,X7R,CH30106KB19':
 ROOM='USB3_HUB1_CYP';

SECTION_NUMBER 1
 '@T6G_MB_LIB.T6G(SCH_1):PAGE154_I55@PURE_QUANTA.Q_CAP(CHIPS)':
 C_PATH='@t6g_mb_lib.t6g(sch_1):page154_i55@pure_quanta.q_cap(chips)',
 P_PATH='@t6g_mb_lib.t6g(sch_1):page177_i55@pure_quanta.q_cap(chips)',
 PATH='I55',
 DRAWING='@T6G_MB_LIB.T6G(SCH_1):PAGE154',
 TOLERANCE='10%',
 MATERIAL='X7R',
 PHYS_PAGE='177',
 XY='(-1425,4850)',
 ROT='0',
 VER='1',
 PACK_TYPE='C0402',
 LOCATION='C6062',
 CDS_LIB='pure_quanta',
 CDS_PART_NAME='Q_CAP_C0402-0.001UF,50V,10%,X7R,CH30106KB19',
 VOLTAGE='50V',
 ROOM='USB3_HUB1_CYP',
 PART_NUMBER='CH30106KB19',
 VALUE='0.001UF',
 PRIM_FILE='./archive_libs/logical/q_cap/chips/chips.prt';

PART_NAME
 C6063 'Q_CAP_C0402-0.01UF,50V,10%,X7R,CH31006KB18':
 ROOM='USB3_HUB1_CYP';

SECTION_NUMBER 1
 '@T6G_MB_LIB.T6G(SCH_1):PAGE154_I56@PURE_QUANTA.Q_CAP(CHIPS)':
 C_PATH='@t6g_mb_lib.t6g(sch_1):page154_i56@pure_quanta.q_cap(chips)',
 P_PATH='@t6g_mb_lib.t6g(sch_1):page177_i56@pure_quanta.q_cap(chips)',
 PATH='I56',
 DRAWING='@T6G_MB_LIB.T6G(SCH_1):PAGE154',
 TOLERANCE='10%',
 MATERIAL='X7R',
 PHYS_PAGE='177',
 XY='(-1175,4850)',
 ROT='0',
 VER='1',
 PACK_TYPE='C0402',
 LOCATION='C6063',
 CDS_LIB='pure_quanta',
 CDS_PART_NAME='Q_CAP_C0402-0.01UF,50V,10%,X7R,CH31006KB18',
 VOLTAGE='50V',
 ROOM='USB3_HUB1_CYP',
 PART_NUMBER='CH31006KB18',
 VALUE='0.01UF',
 PRIM_FILE='./archive_libs/logical/q_cap/chips/chips.prt';

PART_NAME
 C6064 'Q_CAP_0402-0.1UF,25V,10%,X7R,CH4104K1B00':
 ROOM='USB3_HUB1_CYP';

SECTION_NUMBER 1
 '@T6G_MB_LIB.T6G(SCH_1):PAGE154_I58@PURE_QUANTA.Q_CAP(CHIPS)':
 C_PATH='@t6g_mb_lib.t6g(sch_1):page154_i58@pure_quanta.q_cap(chips)',
 P_PATH='@t6g_mb_lib.t6g(sch_1):page177_i58@pure_quanta.q_cap(chips)',
 PATH='I58',
 DRAWING='@T6G_MB_LIB.T6G(SCH_1):PAGE154',
 TOLERANCE='10%',
 MATERIAL='X7R',
 PHYS_PAGE='177',
 XY='(-725,5250)',
 ROT='2',
 VER='1',
 PACK_TYPE='0402',
 LOCATION='C6064',
 CDS_LIB='pure_quanta',
 CDS_PART_NAME='Q_CAP_0402-0.1UF,25V,10%,X7R,CH4104K1B00',
 VOLTAGE='25V',
 ROOM='USB3_HUB1_CYP',
 PART_NUMBER='CH4104K1B00',
 VALUE='0.1UF',
 PRIM_FILE='./archive_libs/logical/q_cap/chips/chips.prt';

PART_NAME
 C6065 'Q_CAP_C0402-1UF,25V,10%,X6S,CH5104KEB02':
 ROOM='USB3_HUB1_CYP';

SECTION_NUMBER 1
 '@T6G_MB_LIB.T6G(SCH_1):PAGE154_I59@PURE_QUANTA.Q_CAP(CHIPS)':
 C_PATH='@t6g_mb_lib.t6g(sch_1):page154_i59@pure_quanta.q_cap(chips)',
 P_PATH='@t6g_mb_lib.t6g(sch_1):page177_i59@pure_quanta.q_cap(chips)',
 PATH='I59',
 DRAWING='@T6G_MB_LIB.T6G(SCH_1):PAGE154',
 TOLERANCE='10%',
 MATERIAL='X6S',
 PHYS_PAGE='177',
 XY='(-600,5250)',
 ROT='0',
 VER='1',
 PACK_TYPE='C0402',
 LOCATION='C6065',
 CDS_LIB='pure_quanta',
 CDS_PART_NAME='Q_CAP_C0402-1UF,25V,10%,X6S,CH5104KEB02',
 VOLTAGE='25V',
 ROOM='USB3_HUB1_CYP',
 PART_NUMBER='CH5104KEB02',
 VALUE='1UF',
 PRIM_FILE='./archive_libs/logical/q_cap/chips/chips.prt';

PART_NAME
 C6066 'Q_CAP_C0603-22UF,6.3V,20%,X6S,CH6221ME900':
 ROOM='USB3_HUB1_CYP';

SECTION_NUMBER 1
 '@T6G_MB_LIB.T6G(SCH_1):PAGE154_I60@PURE_QUANTA.Q_CAP(CHIPS)':
 C_PATH='@t6g_mb_lib.t6g(sch_1):page154_i60@pure_quanta.q_cap(chips)',
 P_PATH='@t6g_mb_lib.t6g(sch_1):page177_i60@pure_quanta.q_cap(chips)',
 PATH='I60',
 DRAWING='@T6G_MB_LIB.T6G(SCH_1):PAGE154',
 TOLERANCE='20%',
 MATERIAL='X6S',
 PHYS_PAGE='177',
 XY='(-325,5250)',
 ROT='0',
 VER='1',
 PACK_TYPE='C0603',
 LOCATION='C6066',
 CDS_LIB='pure_quanta',
 CDS_PART_NAME='Q_CAP_C0603-22UF,6.3V,20%,X6S,CH6221ME900',
 VOLTAGE='6.3V',
 ROOM='USB3_HUB1_CYP',
 PART_NUMBER='CH6221ME900',
 VALUE='22UF',
 PRIM_FILE='./archive_libs/logical/q_cap/chips/chips.prt';

PART_NAME
 C6067 'Q_CAP_C0402-0.001UF,50V,10%,X7R,CH30106KB19':
 ROOM='USB3_HUB1_CYP';

SECTION_NUMBER 1
 '@T6G_MB_LIB.T6G(SCH_1):PAGE154_I79@PURE_QUANTA.Q_CAP(CHIPS)':
 C_PATH='@t6g_mb_lib.t6g(sch_1):page154_i79@pure_quanta.q_cap(chips)',
 P_PATH='@t6g_mb_lib.t6g(sch_1):page177_i79@pure_quanta.q_cap(chips)',
 PATH='I79',
 DRAWING='@T6G_MB_LIB.T6G(SCH_1):PAGE154',
 TOLERANCE='10%',
 MATERIAL='X7R',
 PHYS_PAGE='177',
 XY='(-3750,3350)',
 ROT='0',
 VER='1',
 PACK_TYPE='C0402',
 LOCATION='C6067',
 CDS_LIB='pure_quanta',
 CDS_PART_NAME='Q_CAP_C0402-0.001UF,50V,10%,X7R,CH30106KB19',
 VOLTAGE='50V',
 ROOM='USB3_HUB1_CYP',
 PART_NUMBER='CH30106KB19',
 VALUE='0.001UF',
 PRIM_FILE='./archive_libs/logical/q_cap/chips/chips.prt';

PART_NAME
 C6068 'Q_CAP_C0402-0.01UF,50V,10%,X7R,CH31006KB18':
 ROOM='USB3_HUB1_CYP';

SECTION_NUMBER 1
 '@T6G_MB_LIB.T6G(SCH_1):PAGE154_I78@PURE_QUANTA.Q_CAP(CHIPS)':
 C_PATH='@t6g_mb_lib.t6g(sch_1):page154_i78@pure_quanta.q_cap(chips)',
 P_PATH='@t6g_mb_lib.t6g(sch_1):page177_i78@pure_quanta.q_cap(chips)',
 PATH='I78',
 DRAWING='@T6G_MB_LIB.T6G(SCH_1):PAGE154',
 TOLERANCE='10%',
 MATERIAL='X7R',
 PHYS_PAGE='177',
 XY='(-3500,3350)',
 ROT='0',
 VER='1',
 PACK_TYPE='C0402',
 LOCATION='C6068',
 CDS_LIB='pure_quanta',
 CDS_PART_NAME='Q_CAP_C0402-0.01UF,50V,10%,X7R,CH31006KB18',
 VOLTAGE='50V',
 ROOM='USB3_HUB1_CYP',
 PART_NUMBER='CH31006KB18',
 VALUE='0.01UF',
 PRIM_FILE='./archive_libs/logical/q_cap/chips/chips.prt';

PART_NAME
 C6069 'Q_CAP_C0402-0.001UF,50V,10%,X7R,CH30106KB19':
 ROOM='USB3_HUB1_CYP';

SECTION_NUMBER 1
 '@T6G_MB_LIB.T6G(SCH_1):PAGE154_I63@PURE_QUANTA.Q_CAP(CHIPS)':
 C_PATH='@t6g_mb_lib.t6g(sch_1):page154_i63@pure_quanta.q_cap(chips)',
 P_PATH='@t6g_mb_lib.t6g(sch_1):page177_i63@pure_quanta.q_cap(chips)',
 PATH='I63',
 DRAWING='@T6G_MB_LIB.T6G(SCH_1):PAGE154',
 TOLERANCE='10%',
 MATERIAL='X7R',
 PHYS_PAGE='177',
 XY='(-3250,3350)',
 ROT='0',
 VER='1',
 PACK_TYPE='C0402',
 LOCATION='C6069',
 CDS_LIB='pure_quanta',
 CDS_PART_NAME='Q_CAP_C0402-0.001UF,50V,10%,X7R,CH30106KB19',
 VOLTAGE='50V',
 ROOM='USB3_HUB1_CYP',
 PART_NUMBER='CH30106KB19',
 VALUE='0.001UF',
 PRIM_FILE='./archive_libs/logical/q_cap/chips/chips.prt';

PART_NAME
 C6070 'Q_CAP_C0402-0.01UF,50V,10%,X7R,CH31006KB18':
 ROOM='USB3_HUB1_CYP';

SECTION_NUMBER 1
 '@T6G_MB_LIB.T6G(SCH_1):PAGE154_I76@PURE_QUANTA.Q_CAP(CHIPS)':
 C_PATH='@t6g_mb_lib.t6g(sch_1):page154_i76@pure_quanta.q_cap(chips)',
 P_PATH='@t6g_mb_lib.t6g(sch_1):page177_i76@pure_quanta.q_cap(chips)',
 PATH='I76',
 DRAWING='@T6G_MB_LIB.T6G(SCH_1):PAGE154',
 TOLERANCE='10%',
 MATERIAL='X7R',
 PHYS_PAGE='177',
 XY='(-3000,3350)',
 ROT='0',
 VER='1',
 PACK_TYPE='C0402',
 LOCATION='C6070',
 CDS_LIB='pure_quanta',
 CDS_PART_NAME='Q_CAP_C0402-0.01UF,50V,10%,X7R,CH31006KB18',
 VOLTAGE='50V',
 ROOM='USB3_HUB1_CYP',
 PART_NUMBER='CH31006KB18',
 VALUE='0.01UF',
 PRIM_FILE='./archive_libs/logical/q_cap/chips/chips.prt';

PART_NAME
 C6071 'Q_CAP_C0402-0.001UF,50V,10%,X7R,CH30106KB19':
 ROOM='USB3_HUB1_CYP';

SECTION_NUMBER 1
 '@T6G_MB_LIB.T6G(SCH_1):PAGE154_I75@PURE_QUANTA.Q_CAP(CHIPS)':
 C_PATH='@t6g_mb_lib.t6g(sch_1):page154_i75@pure_quanta.q_cap(chips)',
 P_PATH='@t6g_mb_lib.t6g(sch_1):page177_i75@pure_quanta.q_cap(chips)',
 PATH='I75',
 DRAWING='@T6G_MB_LIB.T6G(SCH_1):PAGE154',
 TOLERANCE='10%',
 MATERIAL='X7R',
 PHYS_PAGE='177',
 XY='(-2650,3350)',
 ROT='0',
 VER='1',
 PACK_TYPE='C0402',
 LOCATION='C6071',
 CDS_LIB='pure_quanta',
 CDS_PART_NAME='Q_CAP_C0402-0.001UF,50V,10%,X7R,CH30106KB19',
 VOLTAGE='50V',
 ROOM='USB3_HUB1_CYP',
 PART_NUMBER='CH30106KB19',
 VALUE='0.001UF',
 PRIM_FILE='./archive_libs/logical/q_cap/chips/chips.prt';

PART_NAME
 C6072 'Q_CAP_C0402-0.01UF,50V,10%,X7R,CH31006KB18':
 ROOM='USB3_HUB1_CYP';

SECTION_NUMBER 1
 '@T6G_MB_LIB.T6G(SCH_1):PAGE154_I74@PURE_QUANTA.Q_CAP(CHIPS)':
 C_PATH='@t6g_mb_lib.t6g(sch_1):page154_i74@pure_quanta.q_cap(chips)',
 P_PATH='@t6g_mb_lib.t6g(sch_1):page177_i74@pure_quanta.q_cap(chips)',
 PATH='I74',
 DRAWING='@T6G_MB_LIB.T6G(SCH_1):PAGE154',
 TOLERANCE='10%',
 MATERIAL='X7R',
 PHYS_PAGE='177',
 XY='(-2400,3350)',
 ROT='0',
 VER='1',
 PACK_TYPE='C0402',
 LOCATION='C6072',
 CDS_LIB='pure_quanta',
 CDS_PART_NAME='Q_CAP_C0402-0.01UF,50V,10%,X7R,CH31006KB18',
 VOLTAGE='50V',
 ROOM='USB3_HUB1_CYP',
 PART_NUMBER='CH31006KB18',
 VALUE='0.01UF',
 PRIM_FILE='./archive_libs/logical/q_cap/chips/chips.prt';

PART_NAME
 C6073 'Q_CAP_C0402-0.001UF,50V,10%,X7R,CH30106KB19':
 ROOM='USB3_HUB1_CYP';

SECTION_NUMBER 1
 '@T6G_MB_LIB.T6G(SCH_1):PAGE154_I73@PURE_QUANTA.Q_CAP(CHIPS)':
 C_PATH='@t6g_mb_lib.t6g(sch_1):page154_i73@pure_quanta.q_cap(chips)',
 P_PATH='@t6g_mb_lib.t6g(sch_1):page177_i73@pure_quanta.q_cap(chips)',
 PATH='I73',
 DRAWING='@T6G_MB_LIB.T6G(SCH_1):PAGE154',
 TOLERANCE='10%',
 MATERIAL='X7R',
 PHYS_PAGE='177',
 XY='(-2025,3350)',
 ROT='0',
 VER='1',
 PACK_TYPE='C0402',
 LOCATION='C6073',
 CDS_LIB='pure_quanta',
 CDS_PART_NAME='Q_CAP_C0402-0.001UF,50V,10%,X7R,CH30106KB19',
 VOLTAGE='50V',
 ROOM='USB3_HUB1_CYP',
 PART_NUMBER='CH30106KB19',
 VALUE='0.001UF',
 PRIM_FILE='./archive_libs/logical/q_cap/chips/chips.prt';

PART_NAME
 C6074 'Q_CAP_C0402-0.01UF,50V,10%,X7R,CH31006KB18':
 ROOM='USB3_HUB1_CYP';

SECTION_NUMBER 1
 '@T6G_MB_LIB.T6G(SCH_1):PAGE154_I71@PURE_QUANTA.Q_CAP(CHIPS)':
 C_PATH='@t6g_mb_lib.t6g(sch_1):page154_i71@pure_quanta.q_cap(chips)',
 P_PATH='@t6g_mb_lib.t6g(sch_1):page177_i71@pure_quanta.q_cap(chips)',
 PATH='I71',
 DRAWING='@T6G_MB_LIB.T6G(SCH_1):PAGE154',
 TOLERANCE='10%',
 MATERIAL='X7R',
 PHYS_PAGE='177',
 XY='(-1775,3350)',
 ROT='0',
 VER='1',
 PACK_TYPE='C0402',
 LOCATION='C6074',
 CDS_LIB='pure_quanta',
 CDS_PART_NAME='Q_CAP_C0402-0.01UF,50V,10%,X7R,CH31006KB18',
 VOLTAGE='50V',
 ROOM='USB3_HUB1_CYP',
 PART_NUMBER='CH31006KB18',
 VALUE='0.01UF',
 PRIM_FILE='./archive_libs/logical/q_cap/chips/chips.prt';

PART_NAME
 C6075 'Q_CAP_C0402-0.001UF,50V,10%,X7R,CH30106KB19':
 ROOM='USB3_HUB1_CYP';

SECTION_NUMBER 1
 '@T6G_MB_LIB.T6G(SCH_1):PAGE154_I69@PURE_QUANTA.Q_CAP(CHIPS)':
 C_PATH='@t6g_mb_lib.t6g(sch_1):page154_i69@pure_quanta.q_cap(chips)',
 P_PATH='@t6g_mb_lib.t6g(sch_1):page177_i69@pure_quanta.q_cap(chips)',
 PATH='I69',
 DRAWING='@T6G_MB_LIB.T6G(SCH_1):PAGE154',
 TOLERANCE='10%',
 MATERIAL='X7R',
 PHYS_PAGE='177',
 XY='(-1425,3350)',
 ROT='0',
 VER='1',
 PACK_TYPE='C0402',
 LOCATION='C6075',
 CDS_LIB='pure_quanta',
 CDS_PART_NAME='Q_CAP_C0402-0.001UF,50V,10%,X7R,CH30106KB19',
 VOLTAGE='50V',
 ROOM='USB3_HUB1_CYP',
 PART_NUMBER='CH30106KB19',
 VALUE='0.001UF',
 PRIM_FILE='./archive_libs/logical/q_cap/chips/chips.prt';

PART_NAME
 C6076 'Q_CAP_C0402-0.01UF,50V,10%,X7R,CH31006KB18':
 ROOM='USB3_HUB1_CYP';

SECTION_NUMBER 1
 '@T6G_MB_LIB.T6G(SCH_1):PAGE154_I68@PURE_QUANTA.Q_CAP(CHIPS)':
 C_PATH='@t6g_mb_lib.t6g(sch_1):page154_i68@pure_quanta.q_cap(chips)',
 P_PATH='@t6g_mb_lib.t6g(sch_1):page177_i68@pure_quanta.q_cap(chips)',
 PATH='I68',
 DRAWING='@T6G_MB_LIB.T6G(SCH_1):PAGE154',
 TOLERANCE='10%',
 MATERIAL='X7R',
 PHYS_PAGE='177',
 XY='(-1175,3350)',
 ROT='0',
 VER='1',
 PACK_TYPE='C0402',
 LOCATION='C6076',
 CDS_LIB='pure_quanta',
 CDS_PART_NAME='Q_CAP_C0402-0.01UF,50V,10%,X7R,CH31006KB18',
 VOLTAGE='50V',
 ROOM='USB3_HUB1_CYP',
 PART_NUMBER='CH31006KB18',
 VALUE='0.01UF',
 PRIM_FILE='./archive_libs/logical/q_cap/chips/chips.prt';

PART_NAME
 C6077 'Q_CAP_0402-0.1UF,25V,10%,X7R,CH4104K1B00':
 ROOM='USB3_HUB1_CYP';

SECTION_NUMBER 1
 '@T6G_MB_LIB.T6G(SCH_1):PAGE154_I66@PURE_QUANTA.Q_CAP(CHIPS)':
 C_PATH='@t6g_mb_lib.t6g(sch_1):page154_i66@pure_quanta.q_cap(chips)',
 P_PATH='@t6g_mb_lib.t6g(sch_1):page177_i66@pure_quanta.q_cap(chips)',
 PATH='I66',
 DRAWING='@T6G_MB_LIB.T6G(SCH_1):PAGE154',
 TOLERANCE='10%',
 MATERIAL='X7R',
 PHYS_PAGE='177',
 XY='(-725,3750)',
 ROT='2',
 VER='1',
 PACK_TYPE='0402',
 LOCATION='C6077',
 CDS_LIB='pure_quanta',
 CDS_PART_NAME='Q_CAP_0402-0.1UF,25V,10%,X7R,CH4104K1B00',
 VOLTAGE='25V',
 ROOM='USB3_HUB1_CYP',
 PART_NUMBER='CH4104K1B00',
 VALUE='0.1UF',
 PRIM_FILE='./archive_libs/logical/q_cap/chips/chips.prt';

PART_NAME
 C6078 'Q_CAP_C0402-1UF,25V,10%,X6S,CH5104KEB02':
 ROOM='USB3_HUB1_CYP';

SECTION_NUMBER 1
 '@T6G_MB_LIB.T6G(SCH_1):PAGE154_I65@PURE_QUANTA.Q_CAP(CHIPS)':
 C_PATH='@t6g_mb_lib.t6g(sch_1):page154_i65@pure_quanta.q_cap(chips)',
 P_PATH='@t6g_mb_lib.t6g(sch_1):page177_i65@pure_quanta.q_cap(chips)',
 PATH='I65',
 DRAWING='@T6G_MB_LIB.T6G(SCH_1):PAGE154',
 TOLERANCE='10%',
 MATERIAL='X6S',
 PHYS_PAGE='177',
 XY='(-600,3750)',
 ROT='0',
 VER='1',
 PACK_TYPE='C0402',
 LOCATION='C6078',
 CDS_LIB='pure_quanta',
 CDS_PART_NAME='Q_CAP_C0402-1UF,25V,10%,X6S,CH5104KEB02',
 VOLTAGE='25V',
 ROOM='USB3_HUB1_CYP',
 PART_NUMBER='CH5104KEB02',
 VALUE='1UF',
 PRIM_FILE='./archive_libs/logical/q_cap/chips/chips.prt';

PART_NAME
 C6079 'Q_CAP_C0603-22UF,6.3V,20%,X6S,CH6221ME900':
 ROOM='USB3_HUB1_CYP';

SECTION_NUMBER 1
 '@T6G_MB_LIB.T6G(SCH_1):PAGE154_I64@PURE_QUANTA.Q_CAP(CHIPS)':
 C_PATH='@t6g_mb_lib.t6g(sch_1):page154_i64@pure_quanta.q_cap(chips)',
 P_PATH='@t6g_mb_lib.t6g(sch_1):page177_i64@pure_quanta.q_cap(chips)',
 PATH='I64',
 DRAWING='@T6G_MB_LIB.T6G(SCH_1):PAGE154',
 TOLERANCE='20%',
 MATERIAL='X6S',
 PHYS_PAGE='177',
 XY='(-325,3750)',
 ROT='0',
 VER='1',
 PACK_TYPE='C0603',
 LOCATION='C6079',
 CDS_LIB='pure_quanta',
 CDS_PART_NAME='Q_CAP_C0603-22UF,6.3V,20%,X6S,CH6221ME900',
 VOLTAGE='6.3V',
 ROOM='USB3_HUB1_CYP',
 PART_NUMBER='CH6221ME900',
 VALUE='22UF',
 PRIM_FILE='./archive_libs/logical/q_cap/chips/chips.prt';

PART_NAME
 C6080 'Q_CAP_C0402-0.01UF,50V,10%,X7R,CH31006KB18':
 ROOM='USB3_HUB1_CYP';

SECTION_NUMBER 1
 '@T6G_MB_LIB.T6G(SCH_1):PAGE154_I81@PURE_QUANTA.Q_CAP(CHIPS)':
 C_PATH='@t6g_mb_lib.t6g(sch_1):page154_i81@pure_quanta.q_cap(chips)',
 P_PATH='@t6g_mb_lib.t6g(sch_1):page177_i81@pure_quanta.q_cap(chips)',
 PATH='I81',
 DRAWING='@T6G_MB_LIB.T6G(SCH_1):PAGE154',
 TOLERANCE='10%',
 MATERIAL='X7R',
 PHYS_PAGE='177',
 XY='(-3700,2225)',
 ROT='2',
 VER='1',
 PACK_TYPE='C0402',
 LOCATION='C6080',
 CDS_LIB='pure_quanta',
 CDS_PART_NAME='Q_CAP_C0402-0.01UF,50V,10%,X7R,CH31006KB18',
 VOLTAGE='50V',
 ROOM='USB3_HUB1_CYP',
 PART_NUMBER='CH31006KB18',
 VALUE='0.01UF',
 PRIM_FILE='./archive_libs/logical/q_cap/chips/chips.prt';

PART_NAME
 C6081 'Q_CAP_0402-0.1UF,25V,10%,X7R,CH4104K1B00':
 ROOM='USB3_HUB1_CYP';

SECTION_NUMBER 1
 '@T6G_MB_LIB.T6G(SCH_1):PAGE154_I82@PURE_QUANTA.Q_CAP(CHIPS)':
 C_PATH='@t6g_mb_lib.t6g(sch_1):page154_i82@pure_quanta.q_cap(chips)',
 P_PATH='@t6g_mb_lib.t6g(sch_1):page177_i82@pure_quanta.q_cap(chips)',
 PATH='I82',
 DRAWING='@T6G_MB_LIB.T6G(SCH_1):PAGE154',
 TOLERANCE='10%',
 MATERIAL='X7R',
 PHYS_PAGE='177',
 XY='(-3275,2225)',
 ROT='2',
 VER='1',
 PACK_TYPE='0402',
 LOCATION='C6081',
 CDS_LIB='pure_quanta',
 CDS_PART_NAME='Q_CAP_0402-0.1UF,25V,10%,X7R,CH4104K1B00',
 VOLTAGE='25V',
 ROOM='USB3_HUB1_CYP',
 PART_NUMBER='CH4104K1B00',
 VALUE='0.1UF',
 PRIM_FILE='./archive_libs/logical/q_cap/chips/chips.prt';

PART_NAME
 C6082 'Q_CAP_C0402-1UF,25V,10%,X6S,CH5104KEB02':
 ROOM='USB3_HUB1_CYP';

SECTION_NUMBER 1
 '@T6G_MB_LIB.T6G(SCH_1):PAGE154_I83@PURE_QUANTA.Q_CAP(CHIPS)':
 C_PATH='@t6g_mb_lib.t6g(sch_1):page154_i83@pure_quanta.q_cap(chips)',
 P_PATH='@t6g_mb_lib.t6g(sch_1):page177_i83@pure_quanta.q_cap(chips)',
 PATH='I83',
 DRAWING='@T6G_MB_LIB.T6G(SCH_1):PAGE154',
 TOLERANCE='10%',
 MATERIAL='X6S',
 PHYS_PAGE='177',
 XY='(-3100,2225)',
 ROT='0',
 VER='1',
 PACK_TYPE='C0402',
 LOCATION='C6082',
 CDS_LIB='pure_quanta',
 CDS_PART_NAME='Q_CAP_C0402-1UF,25V,10%,X6S,CH5104KEB02',
 VOLTAGE='25V',
 ROOM='USB3_HUB1_CYP',
 PART_NUMBER='CH5104KEB02',
 VALUE='1UF',
 PRIM_FILE='./archive_libs/logical/q_cap/chips/chips.prt';

PART_NAME
 C6083 'Q_CAP_0402-0.1UF,25V,10%,X7R,CH4104K1B00':
 ROOM='USB3_HUB1_CYP';

SECTION_NUMBER 1
 '@T6G_MB_LIB.T6G(SCH_1):PAGE153_I75@PURE_QUANTA.Q_CAP(CHIPS)':
 C_PATH='@t6g_mb_lib.t6g(sch_1):page153_i75@pure_quanta.q_cap(chips)',
 P_PATH='@t6g_mb_lib.t6g(sch_1):page176_i75@pure_quanta.q_cap(chips)',
 PATH='I75',
 DRAWING='@T6G_MB_LIB.T6G(SCH_1):PAGE153',
 TOLERANCE='10%',
 MATERIAL='X7R',
 PHYS_PAGE='176',
 XY='(-2650,3325)',
 ROT='0',
 VER='1',
 PACK_TYPE='0402',
 LOCATION='C6083',
 CDS_LIB='pure_quanta',
 CDS_PART_NAME='Q_CAP_0402-0.1UF,25V,10%,X7R,CH4104K1B00',
 VOLTAGE='25V',
 ROOM='USB3_HUB1_CYP',
 PART_NUMBER='CH4104K1B00',
 VALUE='0.1UF',
 PRIM_FILE='./archive_libs/logical/q_cap/chips/chips.prt';

PART_NAME
 C6084 'Q_CAP_0402-0.1UF,25V,10%,EMPTY,CH4104K1B00':
 ROOM='HSC BOM2';

SECTION_NUMBER 1
 '@T6G_MB_LIB.T6G(SCH_1):PAGE371_I107@PURE_QUANTA.Q_CAP(CHIPS)':
 C_PATH='@t6g_mb_lib.t6g(sch_1):page371_i107@pure_quanta.q_cap(chips)',
 P_PATH='@t6g_mb_lib.t6g(sch_1):page267_i107@pure_quanta.q_cap(chips)',
 PATH='I107',
 DRAWING='@T6G_MB_LIB.T6G(SCH_1):PAGE371',
 TOLERANCE='10%',
 MATERIAL='EMPTY',
 PHYS_PAGE='267',
 XY='(-6825,6275)',
 ROT='0',
 VER='1',
 PACK_TYPE='0402',
 LOCATION='C6084',
 CDS_LIB='pure_quanta',
 CDS_PART_NAME='Q_CAP_0402-0.1UF,25V,10%,EMPTY,CH4104K1B00',
 VOLTAGE='25V',
 ROOM='HSC BOM2',
 PART_NUMBER='CH4104K1B00',
 VALUE='0.1UF',
 PRIM_FILE='./archive_libs/logical/q_cap/chips/chips.prt';

PART_NAME
 C6085 'Q_CAP_0402-0.1UF,25V,10%,EMPTY,CH4104K1B00':;

SECTION_NUMBER 1
 '@T6G_MB_LIB.T6G(SCH_1):PAGE380_I41@PURE_QUANTA.Q_CAP(CHIPS)':
 C_PATH='@t6g_mb_lib.t6g(sch_1):page380_i41@pure_quanta.q_cap(chips)',
 P_PATH='@t6g_mb_lib.t6g(sch_1):page270_i41@pure_quanta.q_cap(chips)',
 PATH='I41',
 DRAWING='@T6G_MB_LIB.T6G(SCH_1):PAGE380',
 TOLERANCE='10%',
 MATERIAL='EMPTY',
 PHYS_PAGE='270',
 XY='(-7175,1675)',
 ROT='2',
 VER='1',
 PACK_TYPE='0402',
 LOCATION='C6085',
 CDS_LIB='pure_quanta',
 CDS_PART_NAME='Q_CAP_0402-0.1UF,25V,10%,EMPTY,CH4104K1B00',
 VOLTAGE='25V',
 PART_NUMBER='CH4104K1B00',
 VALUE='0.1UF',
 PRIM_FILE='./archive_libs/logical/q_cap/chips/chips.prt';

PART_NAME
 C6086 'Q_CAP_0402-0.1UF,25V,10%,X7R,CH4104K1B00':;

SECTION_NUMBER 1
 '@T6G_MB_LIB.T6G(SCH_1):PAGE271_I11@PURE_QUANTA.Q_CAP(CHIPS)':
 C_PATH='@t6g_mb_lib.t6g(sch_1):page271_i11@pure_quanta.q_cap(chips)',
 P_PATH='@t6g_mb_lib.t6g(sch_1):page271_i11@pure_quanta.q_cap(chips)',
 PATH='I11',
 DRAWING='@T6G_MB_LIB.T6G(SCH_1):PAGE271',
 TOLERANCE='10%',
 MATERIAL='X7R',
 PHYS_PAGE='271',
 XY='(-6175,4975)',
 ROT='0',
 VER='1',
 PACK_TYPE='0402',
 LOCATION='C6086',
 CDS_LIB='pure_quanta',
 CDS_PART_NAME='Q_CAP_0402-0.1UF,25V,10%,X7R,CH4104K1B00',
 VOLTAGE='25V',
 PART_NUMBER='CH4104K1B00',
 VALUE='0.1UF',
 PRIM_FILE='./archive_libs/logical/q_cap/chips/chips.prt';

PART_NAME
 C6087 'Q_CAP_0402-0.1UF,25V,10%,X7R,CH4104K1B00':;

SECTION_NUMBER 1
 '@T6G_MB_LIB.T6G(SCH_1):PAGE271_I22@PURE_QUANTA.Q_CAP(CHIPS)':
 C_PATH='@t6g_mb_lib.t6g(sch_1):page271_i22@pure_quanta.q_cap(chips)',
 P_PATH='@t6g_mb_lib.t6g(sch_1):page271_i22@pure_quanta.q_cap(chips)',
 PATH='I22',
 DRAWING='@T6G_MB_LIB.T6G(SCH_1):PAGE271',
 TOLERANCE='10%',
 MATERIAL='X7R',
 PHYS_PAGE='271',
 XY='(-5325,5950)',
 ROT='0',
 VER='1',
 PACK_TYPE='0402',
 LOCATION='C6087',
 CDS_LIB='pure_quanta',
 CDS_PART_NAME='Q_CAP_0402-0.1UF,25V,10%,X7R,CH4104K1B00',
 VOLTAGE='25V',
 PART_NUMBER='CH4104K1B00',
 VALUE='0.1UF',
 PRIM_FILE='./archive_libs/logical/q_cap/chips/chips.prt';

PART_NAME
 C6088 'Q_CAP_C0805-10UF,16V,10%,X6S,CH6103KEA00':
 GROUP='HUB_MRP',
 ROOM='USB3_HUB2_MRP';

SECTION_NUMBER 1
 '@T6G_MB_LIB.T6G(SCH_1):PAGE155_I127@PURE_QUANTA.Q_CAP(CHIPS)':
 C_PATH='@t6g_mb_lib.t6g(sch_1):page155_i127@pure_quanta.q_cap(chips)',
 P_PATH='@t6g_mb_lib.t6g(sch_1):page178_i127@pure_quanta.q_cap(chips)',
 PATH='I127',
 DRAWING='@T6G_MB_LIB.T6G(SCH_1):PAGE155',
 BOM_COST='VR_SYSTEM ',
 TOLERANCE='10%',
 MATERIAL='X6S',
 PHYS_PAGE='178',
 XY='(-8025,5875)',
 ROT='0',
 VER='1',
 PACK_TYPE='C0805',
 LOCATION='C6088',
 CDS_LIB='pure_quanta',
 CDS_PART_NAME='Q_CAP_C0805-10UF,16V,10%,X6S,CH6103KEA00',
 GROUP='HUB_MRP',
 VOLTAGE='16V',
 ROOM='USB3_HUB2_MRP',
 PART_NUMBER='CH6103KEA00',
 VALUE='10UF',
 PRIM_FILE='./archive_libs/logical/q_cap/chips/chips.prt';

PART_NAME
 C6089 'Q_CAP_C0402-1UF,25V,10%,X6S,CH5104KEB02':
 GROUP='HUB_TI',
 ROOM='USB3_HUB2_TI';

SECTION_NUMBER 1
 '@T6G_MB_LIB.T6G(SCH_1):PAGE155_I145@PURE_QUANTA.Q_CAP(CHIPS)':
 C_PATH='@t6g_mb_lib.t6g(sch_1):page155_i145@pure_quanta.q_cap(chips)',
 P_PATH='@t6g_mb_lib.t6g(sch_1):page178_i145@pure_quanta.q_cap(chips)',
 PATH='I145',
 DRAWING='@T6G_MB_LIB.T6G(SCH_1):PAGE155',
 TOLERANCE='10%',
 MATERIAL='X6S',
 PHYS_PAGE='178',
 XY='(-8175,3425)',
 ROT='0',
 VER='1',
 PACK_TYPE='C0402',
 LOCATION='C6089',
 CDS_LIB='pure_quanta',
 CDS_PART_NAME='Q_CAP_C0402-1UF,25V,10%,X6S,CH5104KEB02',
 GROUP='HUB_TI',
 VOLTAGE='25V',
 ROOM='USB3_HUB2_TI',
 PART_NUMBER='CH5104KEB02',
 VALUE='1UF',
 PRIM_FILE='./archive_libs/logical/q_cap/chips/chips.prt';

PART_NAME
 C6090 'Q_CAP_0402-27PF,50V,5%,NPO,CH02706JB06':
 ROOM='USB3_HUB2';

SECTION_NUMBER 1
 '@T6G_MB_LIB.T6G(SCH_1):PAGE157_I174@PURE_QUANTA.Q_CAP(CHIPS)':
 C_PATH='@t6g_mb_lib.t6g(sch_1):page157_i174@pure_quanta.q_cap(chips)',
 P_PATH='@t6g_mb_lib.t6g(sch_1):page179_i174@pure_quanta.q_cap(chips)',
 PATH='I174',
 DRAWING='@T6G_MB_LIB.T6G(SCH_1):PAGE157',
 SEC_TYPE='0402',
 TOLERANCE='5%',
 MATERIAL='NPO',
 PHYS_PAGE='179',
 XY='(-7375,2900)',
 ROT='2',
 VER='1',
 PACK_TYPE='0402',
 LOCATION='C6090',
 SEC='1',
 CDS_LIB='pure_quanta',
 CDS_PART_NAME='Q_CAP_0402-27PF,50V,5%,NPO,CH02706JB06',
 VOLTAGE='50V',
 ROOM='USB3_HUB2',
 PART_NUMBER='CH02706JB06',
 VALUE='27PF',
 PRIM_FILE='./archive_libs/logical/q_cap/chips/chips.prt';

PART_NAME
 C6091 'Q_CAP_0402-27PF,50V,5%,NPO,CH02706JB06':
 ROOM='USB3_HUB2';

SECTION_NUMBER 1
 '@T6G_MB_LIB.T6G(SCH_1):PAGE157_I175@PURE_QUANTA.Q_CAP(CHIPS)':
 C_PATH='@t6g_mb_lib.t6g(sch_1):page157_i175@pure_quanta.q_cap(chips)',
 P_PATH='@t6g_mb_lib.t6g(sch_1):page179_i175@pure_quanta.q_cap(chips)',
 PATH='I175',
 DRAWING='@T6G_MB_LIB.T6G(SCH_1):PAGE157',
 SEC_TYPE='0402',
 TOLERANCE='5%',
 MATERIAL='NPO',
 PHYS_PAGE='179',
 XY='(-6250,2875)',
 ROT='0',
 VER='1',
 PACK_TYPE='0402',
 LOCATION='C6091',
 SEC='1',
 CDS_LIB='pure_quanta',
 CDS_PART_NAME='Q_CAP_0402-27PF,50V,5%,NPO,CH02706JB06',
 VOLTAGE='50V',
 ROOM='USB3_HUB2',
 PART_NUMBER='CH02706JB06',
 VALUE='27PF',
 PRIM_FILE='./archive_libs/logical/q_cap/chips/chips.prt';

PART_NAME
 C6092 'Q_CAP_C0402-1UF,25V,10%,X6S,CH5104KEB02':
 ROOM='USB3_HUB2';

SECTION_NUMBER 1
 '@T6G_MB_LIB.T6G(SCH_1):PAGE157_I21@PURE_QUANTA.Q_CAP(CHIPS)':
 C_PATH='@t6g_mb_lib.t6g(sch_1):page157_i21@pure_quanta.q_cap(chips)',
 P_PATH='@t6g_mb_lib.t6g(sch_1):page179_i21@pure_quanta.q_cap(chips)',
 PATH='I21',
 DRAWING='@T6G_MB_LIB.T6G(SCH_1):PAGE157',
 TOLERANCE='10%',
 MATERIAL='X6S',
 PHYS_PAGE='179',
 XY='(-5425,1675)',
 ROT='0',
 VER='1',
 PACK_TYPE='C0402',
 LOCATION='C6092',
 CDS_LIB='pure_quanta',
 CDS_PART_NAME='Q_CAP_C0402-1UF,25V,10%,X6S,CH5104KEB02',
 VOLTAGE='25V',
 ROOM='USB3_HUB2',
 PART_NUMBER='CH5104KEB02',
 VALUE='1UF',
 PRIM_FILE='./archive_libs/logical/q_cap/chips/chips.prt';

PART_NAME
 C6093 'Q_CAP_C0402-1PF,50V,0.05P,COG,CH-106T0B00':
 ROOM='USB3_HUB2';

SECTION_NUMBER 1
 '@T6G_MB_LIB.T6G(SCH_1):PAGE157_I24@PURE_QUANTA.Q_CAP(CHIPS)':
 C_PATH='@t6g_mb_lib.t6g(sch_1):page157_i24@pure_quanta.q_cap(chips)',
 P_PATH='@t6g_mb_lib.t6g(sch_1):page179_i24@pure_quanta.q_cap(chips)',
 PATH='I24',
 DRAWING='@T6G_MB_LIB.T6G(SCH_1):PAGE157',
 TOLERANCE='0.05P',
 MATERIAL='COG',
 PHYS_PAGE='179',
 XY='(-5025,1675)',
 ROT='0',
 VER='1',
 PACK_TYPE='C0402',
 LOCATION='C6093',
 CDS_LIB='pure_quanta',
 CDS_PART_NAME='Q_CAP_C0402-1PF,50V,0.05P,COG,CH-106T0B00',
 VOLTAGE='50V',
 ROOM='USB3_HUB2',
 PART_NUMBER='CH-106T0B00',
 VALUE='1PF',
 PRIM_FILE='./archive_libs/logical/q_cap/chips/chips.prt';

PART_NAME
 C6094 'Q_CAP_C0402-0.01UF,50V,10%,X7R,CH31006KB18':
 ROOM='USB3_HUB2';

SECTION_NUMBER 1
 '@T6G_MB_LIB.T6G(SCH_1):PAGE157_I22@PURE_QUANTA.Q_CAP(CHIPS)':
 C_PATH='@t6g_mb_lib.t6g(sch_1):page157_i22@pure_quanta.q_cap(chips)',
 P_PATH='@t6g_mb_lib.t6g(sch_1):page179_i22@pure_quanta.q_cap(chips)',
 PATH='I22',
 DRAWING='@T6G_MB_LIB.T6G(SCH_1):PAGE157',
 TOLERANCE='10%',
 MATERIAL='X7R',
 PHYS_PAGE='179',
 XY='(-4600,1675)',
 ROT='0',
 VER='1',
 PACK_TYPE='C0402',
 LOCATION='C6094',
 CDS_LIB='pure_quanta',
 CDS_PART_NAME='Q_CAP_C0402-0.01UF,50V,10%,X7R,CH31006KB18',
 VOLTAGE='50V',
 ROOM='USB3_HUB2',
 PART_NUMBER='CH31006KB18',
 VALUE='0.01UF',
 PRIM_FILE='./archive_libs/logical/q_cap/chips/chips.prt';

PART_NAME
 C6095 'Q_CAP_0402-0.1UF,25V,10%,X7R,CH4104K1B00':
 ROOM='USB3_HUB2';

SECTION_NUMBER 1
 '@T6G_MB_LIB.T6G(SCH_1):PAGE157_I23@PURE_QUANTA.Q_CAP(CHIPS)':
 C_PATH='@t6g_mb_lib.t6g(sch_1):page157_i23@pure_quanta.q_cap(chips)',
 P_PATH='@t6g_mb_lib.t6g(sch_1):page179_i23@pure_quanta.q_cap(chips)',
 PATH='I23',
 DRAWING='@T6G_MB_LIB.T6G(SCH_1):PAGE157',
 TOLERANCE='10%',
 MATERIAL='X7R',
 PHYS_PAGE='179',
 XY='(-4350,1675)',
 ROT='0',
 VER='1',
 PACK_TYPE='0402',
 LOCATION='C6095',
 CDS_LIB='pure_quanta',
 CDS_PART_NAME='Q_CAP_0402-0.1UF,25V,10%,X7R,CH4104K1B00',
 VOLTAGE='25V',
 ROOM='USB3_HUB2',
 PART_NUMBER='CH4104K1B00',
 VALUE='0.1UF',
 PRIM_FILE='./archive_libs/logical/q_cap/chips/chips.prt';

PART_NAME
 C6096 'Q_CAP_C0402-1PF,50V,0.05P,COG,CH-106T0B00':
 ROOM='USB3_HUB2';

SECTION_NUMBER 1
 '@T6G_MB_LIB.T6G(SCH_1):PAGE157_I27@PURE_QUANTA.Q_CAP(CHIPS)':
 C_PATH='@t6g_mb_lib.t6g(sch_1):page157_i27@pure_quanta.q_cap(chips)',
 P_PATH='@t6g_mb_lib.t6g(sch_1):page179_i27@pure_quanta.q_cap(chips)',
 PATH='I27',
 DRAWING='@T6G_MB_LIB.T6G(SCH_1):PAGE157',
 TOLERANCE='0.05P',
 MATERIAL='COG',
 PHYS_PAGE='179',
 XY='(-4075,1675)',
 ROT='0',
 VER='1',
 PACK_TYPE='C0402',
 LOCATION='C6096',
 CDS_LIB='pure_quanta',
 CDS_PART_NAME='Q_CAP_C0402-1PF,50V,0.05P,COG,CH-106T0B00',
 VOLTAGE='50V',
 ROOM='USB3_HUB2',
 PART_NUMBER='CH-106T0B00',
 VALUE='1PF',
 PRIM_FILE='./archive_libs/logical/q_cap/chips/chips.prt';

PART_NAME
 C6097 'Q_CAP_C0402-0.01UF,50V,10%,X7R,CH31006KB18':
 ROOM='USB3_HUB2';

SECTION_NUMBER 1
 '@T6G_MB_LIB.T6G(SCH_1):PAGE157_I26@PURE_QUANTA.Q_CAP(CHIPS)':
 C_PATH='@t6g_mb_lib.t6g(sch_1):page157_i26@pure_quanta.q_cap(chips)',
 P_PATH='@t6g_mb_lib.t6g(sch_1):page179_i26@pure_quanta.q_cap(chips)',
 PATH='I26',
 DRAWING='@T6G_MB_LIB.T6G(SCH_1):PAGE157',
 TOLERANCE='10%',
 MATERIAL='X7R',
 PHYS_PAGE='179',
 XY='(-3825,1675)',
 ROT='0',
 VER='1',
 PACK_TYPE='C0402',
 LOCATION='C6097',
 CDS_LIB='pure_quanta',
 CDS_PART_NAME='Q_CAP_C0402-0.01UF,50V,10%,X7R,CH31006KB18',
 VOLTAGE='50V',
 ROOM='USB3_HUB2',
 PART_NUMBER='CH31006KB18',
 VALUE='0.01UF',
 PRIM_FILE='./archive_libs/logical/q_cap/chips/chips.prt';

PART_NAME
 C6098 'Q_CAP_0402-0.1UF,25V,10%,X7R,CH4104K1B00':
 ROOM='USB3_HUB2';

SECTION_NUMBER 1
 '@T6G_MB_LIB.T6G(SCH_1):PAGE157_I25@PURE_QUANTA.Q_CAP(CHIPS)':
 C_PATH='@t6g_mb_lib.t6g(sch_1):page157_i25@pure_quanta.q_cap(chips)',
 P_PATH='@t6g_mb_lib.t6g(sch_1):page179_i25@pure_quanta.q_cap(chips)',
 PATH='I25',
 DRAWING='@T6G_MB_LIB.T6G(SCH_1):PAGE157',
 TOLERANCE='10%',
 MATERIAL='X7R',
 PHYS_PAGE='179',
 XY='(-3575,1675)',
 ROT='0',
 VER='1',
 PACK_TYPE='0402',
 LOCATION='C6098',
 CDS_LIB='pure_quanta',
 CDS_PART_NAME='Q_CAP_0402-0.1UF,25V,10%,X7R,CH4104K1B00',
 VOLTAGE='25V',
 ROOM='USB3_HUB2',
 PART_NUMBER='CH4104K1B00',
 VALUE='0.1UF',
 PRIM_FILE='./archive_libs/logical/q_cap/chips/chips.prt';

PART_NAME
 C6099 'Q_CAP_C0402-1PF,50V,0.05P,COG,CH-106T0B00':
 ROOM='USB3_HUB2';

SECTION_NUMBER 1
 '@T6G_MB_LIB.T6G(SCH_1):PAGE157_I30@PURE_QUANTA.Q_CAP(CHIPS)':
 C_PATH='@t6g_mb_lib.t6g(sch_1):page157_i30@pure_quanta.q_cap(chips)',
 P_PATH='@t6g_mb_lib.t6g(sch_1):page179_i30@pure_quanta.q_cap(chips)',
 PATH='I30',
 DRAWING='@T6G_MB_LIB.T6G(SCH_1):PAGE157',
 TOLERANCE='0.05P',
 MATERIAL='COG',
 PHYS_PAGE='179',
 XY='(-3325,1675)',
 ROT='0',
 VER='1',
 PACK_TYPE='C0402',
 LOCATION='C6099',
 CDS_LIB='pure_quanta',
 CDS_PART_NAME='Q_CAP_C0402-1PF,50V,0.05P,COG,CH-106T0B00',
 VOLTAGE='50V',
 ROOM='USB3_HUB2',
 PART_NUMBER='CH-106T0B00',
 VALUE='1PF',
 PRIM_FILE='./archive_libs/logical/q_cap/chips/chips.prt';

PART_NAME
 C6100 'Q_CAP_C0402-0.01UF,50V,10%,X7R,CH31006KB18':
 ROOM='USB3_HUB2';

SECTION_NUMBER 1
 '@T6G_MB_LIB.T6G(SCH_1):PAGE157_I29@PURE_QUANTA.Q_CAP(CHIPS)':
 C_PATH='@t6g_mb_lib.t6g(sch_1):page157_i29@pure_quanta.q_cap(chips)',
 P_PATH='@t6g_mb_lib.t6g(sch_1):page179_i29@pure_quanta.q_cap(chips)',
 PATH='I29',
 DRAWING='@T6G_MB_LIB.T6G(SCH_1):PAGE157',
 TOLERANCE='10%',
 MATERIAL='X7R',
 PHYS_PAGE='179',
 XY='(-3075,1675)',
 ROT='0',
 VER='1',
 PACK_TYPE='C0402',
 LOCATION='C6100',
 CDS_LIB='pure_quanta',
 CDS_PART_NAME='Q_CAP_C0402-0.01UF,50V,10%,X7R,CH31006KB18',
 VOLTAGE='50V',
 ROOM='USB3_HUB2',
 PART_NUMBER='CH31006KB18',
 VALUE='0.01UF',
 PRIM_FILE='./archive_libs/logical/q_cap/chips/chips.prt';

PART_NAME
 C6101 'Q_CAP_0402-0.1UF,25V,10%,X7R,CH4104K1B00':
 ROOM='USB3_HUB2';

SECTION_NUMBER 1
 '@T6G_MB_LIB.T6G(SCH_1):PAGE157_I28@PURE_QUANTA.Q_CAP(CHIPS)':
 C_PATH='@t6g_mb_lib.t6g(sch_1):page157_i28@pure_quanta.q_cap(chips)',
 P_PATH='@t6g_mb_lib.t6g(sch_1):page179_i28@pure_quanta.q_cap(chips)',
 PATH='I28',
 DRAWING='@T6G_MB_LIB.T6G(SCH_1):PAGE157',
 TOLERANCE='10%',
 MATERIAL='X7R',
 PHYS_PAGE='179',
 XY='(-2825,1675)',
 ROT='0',
 VER='1',
 PACK_TYPE='0402',
 LOCATION='C6101',
 CDS_LIB='pure_quanta',
 CDS_PART_NAME='Q_CAP_0402-0.1UF,25V,10%,X7R,CH4104K1B00',
 VOLTAGE='25V',
 ROOM='USB3_HUB2',
 PART_NUMBER='CH4104K1B00',
 VALUE='0.1UF',
 PRIM_FILE='./archive_libs/logical/q_cap/chips/chips.prt';

PART_NAME
 C6102 'Q_CAP_C0402-1PF,50V,0.05P,COG,CH-106T0B00':
 ROOM='USB3_HUB2';

SECTION_NUMBER 1
 '@T6G_MB_LIB.T6G(SCH_1):PAGE157_I33@PURE_QUANTA.Q_CAP(CHIPS)':
 C_PATH='@t6g_mb_lib.t6g(sch_1):page157_i33@pure_quanta.q_cap(chips)',
 P_PATH='@t6g_mb_lib.t6g(sch_1):page179_i33@pure_quanta.q_cap(chips)',
 PATH='I33',
 DRAWING='@T6G_MB_LIB.T6G(SCH_1):PAGE157',
 TOLERANCE='0.05P',
 MATERIAL='COG',
 PHYS_PAGE='179',
 XY='(-2575,1675)',
 ROT='0',
 VER='1',
 PACK_TYPE='C0402',
 LOCATION='C6102',
 CDS_LIB='pure_quanta',
 CDS_PART_NAME='Q_CAP_C0402-1PF,50V,0.05P,COG,CH-106T0B00',
 VOLTAGE='50V',
 ROOM='USB3_HUB2',
 PART_NUMBER='CH-106T0B00',
 VALUE='1PF',
 PRIM_FILE='./archive_libs/logical/q_cap/chips/chips.prt';

PART_NAME
 C6103 'Q_CAP_C0402-0.01UF,50V,10%,X7R,CH31006KB18':
 ROOM='USB3_HUB2';

SECTION_NUMBER 1
 '@T6G_MB_LIB.T6G(SCH_1):PAGE157_I32@PURE_QUANTA.Q_CAP(CHIPS)':
 C_PATH='@t6g_mb_lib.t6g(sch_1):page157_i32@pure_quanta.q_cap(chips)',
 P_PATH='@t6g_mb_lib.t6g(sch_1):page179_i32@pure_quanta.q_cap(chips)',
 PATH='I32',
 DRAWING='@T6G_MB_LIB.T6G(SCH_1):PAGE157',
 TOLERANCE='10%',
 MATERIAL='X7R',
 PHYS_PAGE='179',
 XY='(-2325,1675)',
 ROT='0',
 VER='1',
 PACK_TYPE='C0402',
 LOCATION='C6103',
 CDS_LIB='pure_quanta',
 CDS_PART_NAME='Q_CAP_C0402-0.01UF,50V,10%,X7R,CH31006KB18',
 VOLTAGE='50V',
 ROOM='USB3_HUB2',
 PART_NUMBER='CH31006KB18',
 VALUE='0.01UF',
 PRIM_FILE='./archive_libs/logical/q_cap/chips/chips.prt';

PART_NAME
 C6104 'Q_CAP_0402-0.1UF,25V,10%,X7R,CH4104K1B00':
 ROOM='USB3_HUB2';

SECTION_NUMBER 1
 '@T6G_MB_LIB.T6G(SCH_1):PAGE157_I31@PURE_QUANTA.Q_CAP(CHIPS)':
 C_PATH='@t6g_mb_lib.t6g(sch_1):page157_i31@pure_quanta.q_cap(chips)',
 P_PATH='@t6g_mb_lib.t6g(sch_1):page179_i31@pure_quanta.q_cap(chips)',
 PATH='I31',
 DRAWING='@T6G_MB_LIB.T6G(SCH_1):PAGE157',
 TOLERANCE='10%',
 MATERIAL='X7R',
 PHYS_PAGE='179',
 XY='(-2050,1675)',
 ROT='0',
 VER='1',
 PACK_TYPE='0402',
 LOCATION='C6104',
 CDS_LIB='pure_quanta',
 CDS_PART_NAME='Q_CAP_0402-0.1UF,25V,10%,X7R,CH4104K1B00',
 VOLTAGE='25V',
 ROOM='USB3_HUB2',
 PART_NUMBER='CH4104K1B00',
 VALUE='0.1UF',
 PRIM_FILE='./archive_libs/logical/q_cap/chips/chips.prt';

PART_NAME
 C6105 'Q_CAP_C0805-10UF,25V,10%,X6S,CH6104KEA00':
 ROOM='USB3_HUB2';

SECTION_NUMBER 1
 '@T6G_MB_LIB.T6G(SCH_1):PAGE157_I36@PURE_QUANTA.Q_CAP(CHIPS)':
 C_PATH='@t6g_mb_lib.t6g(sch_1):page157_i36@pure_quanta.q_cap(chips)',
 P_PATH='@t6g_mb_lib.t6g(sch_1):page179_i36@pure_quanta.q_cap(chips)',
 PATH='I36',
 DRAWING='@T6G_MB_LIB.T6G(SCH_1):PAGE157',
 TOLERANCE='10%',
 MATERIAL='X6S',
 PHYS_PAGE='179',
 XY='(-7100,825)',
 ROT='0',
 VER='1',
 PACK_TYPE='C0805',
 LOCATION='C6105',
 CDS_LIB='pure_quanta',
 CDS_PART_NAME='Q_CAP_C0805-10UF,25V,10%,X6S,CH6104KEA00',
 VOLTAGE='25V',
 ROOM='USB3_HUB2',
 PART_NUMBER='CH6104KEA00',
 VALUE='10UF',
 PRIM_FILE='./archive_libs/logical/q_cap/chips/chips.prt';

PART_NAME
 C6106 'Q_CAP_C0402-1PF,50V,0.05P,COG,CH-106T0B00':
 ROOM='USB3_HUB2';

SECTION_NUMBER 1
 '@T6G_MB_LIB.T6G(SCH_1):PAGE157_I41@PURE_QUANTA.Q_CAP(CHIPS)':
 C_PATH='@t6g_mb_lib.t6g(sch_1):page157_i41@pure_quanta.q_cap(chips)',
 P_PATH='@t6g_mb_lib.t6g(sch_1):page179_i41@pure_quanta.q_cap(chips)',
 PATH='I41',
 DRAWING='@T6G_MB_LIB.T6G(SCH_1):PAGE157',
 TOLERANCE='0.05P',
 MATERIAL='COG',
 PHYS_PAGE='179',
 XY='(-6700,825)',
 ROT='0',
 VER='1',
 PACK_TYPE='C0402',
 LOCATION='C6106',
 CDS_LIB='pure_quanta',
 CDS_PART_NAME='Q_CAP_C0402-1PF,50V,0.05P,COG,CH-106T0B00',
 VOLTAGE='50V',
 ROOM='USB3_HUB2',
 PART_NUMBER='CH-106T0B00',
 VALUE='1PF',
 PRIM_FILE='./archive_libs/logical/q_cap/chips/chips.prt';

PART_NAME
 C6107 'Q_CAP_C0402-0.01UF,50V,10%,X7R,CH31006KB18':
 ROOM='USB3_HUB2';

SECTION_NUMBER 1
 '@T6G_MB_LIB.T6G(SCH_1):PAGE157_I40@PURE_QUANTA.Q_CAP(CHIPS)':
 C_PATH='@t6g_mb_lib.t6g(sch_1):page157_i40@pure_quanta.q_cap(chips)',
 P_PATH='@t6g_mb_lib.t6g(sch_1):page179_i40@pure_quanta.q_cap(chips)',
 PATH='I40',
 DRAWING='@T6G_MB_LIB.T6G(SCH_1):PAGE157',
 TOLERANCE='10%',
 MATERIAL='X7R',
 PHYS_PAGE='179',
 XY='(-6275,825)',
 ROT='0',
 VER='1',
 PACK_TYPE='C0402',
 LOCATION='C6107',
 CDS_LIB='pure_quanta',
 CDS_PART_NAME='Q_CAP_C0402-0.01UF,50V,10%,X7R,CH31006KB18',
 VOLTAGE='50V',
 ROOM='USB3_HUB2',
 PART_NUMBER='CH31006KB18',
 VALUE='0.01UF',
 PRIM_FILE='./archive_libs/logical/q_cap/chips/chips.prt';

PART_NAME
 C6108 'Q_CAP_0402-0.1UF,25V,10%,X7R,CH4104K1B00':
 ROOM='USB3_HUB2';

SECTION_NUMBER 1
 '@T6G_MB_LIB.T6G(SCH_1):PAGE157_I39@PURE_QUANTA.Q_CAP(CHIPS)':
 C_PATH='@t6g_mb_lib.t6g(sch_1):page157_i39@pure_quanta.q_cap(chips)',
 P_PATH='@t6g_mb_lib.t6g(sch_1):page179_i39@pure_quanta.q_cap(chips)',
 PATH='I39',
 DRAWING='@T6G_MB_LIB.T6G(SCH_1):PAGE157',
 TOLERANCE='10%',
 MATERIAL='X7R',
 PHYS_PAGE='179',
 XY='(-6025,825)',
 ROT='0',
 VER='1',
 PACK_TYPE='0402',
 LOCATION='C6108',
 CDS_LIB='pure_quanta',
 CDS_PART_NAME='Q_CAP_0402-0.1UF,25V,10%,X7R,CH4104K1B00',
 VOLTAGE='25V',
 ROOM='USB3_HUB2',
 PART_NUMBER='CH4104K1B00',
 VALUE='0.1UF',
 PRIM_FILE='./archive_libs/logical/q_cap/chips/chips.prt';

PART_NAME
 C6109 'Q_CAP_C0402-1PF,50V,0.05P,COG,CH-106T0B00':
 ROOM='USB3_HUB2';

SECTION_NUMBER 1
 '@T6G_MB_LIB.T6G(SCH_1):PAGE157_I44@PURE_QUANTA.Q_CAP(CHIPS)':
 C_PATH='@t6g_mb_lib.t6g(sch_1):page157_i44@pure_quanta.q_cap(chips)',
 P_PATH='@t6g_mb_lib.t6g(sch_1):page179_i44@pure_quanta.q_cap(chips)',
 PATH='I44',
 DRAWING='@T6G_MB_LIB.T6G(SCH_1):PAGE157',
 TOLERANCE='0.05P',
 MATERIAL='COG',
 PHYS_PAGE='179',
 XY='(-5750,850)',
 ROT='0',
 VER='1',
 PACK_TYPE='C0402',
 LOCATION='C6109',
 CDS_LIB='pure_quanta',
 CDS_PART_NAME='Q_CAP_C0402-1PF,50V,0.05P,COG,CH-106T0B00',
 VOLTAGE='50V',
 ROOM='USB3_HUB2',
 PART_NUMBER='CH-106T0B00',
 VALUE='1PF',
 PRIM_FILE='./archive_libs/logical/q_cap/chips/chips.prt';

PART_NAME
 C6110 'Q_CAP_C0402-0.01UF,50V,10%,X7R,CH31006KB18':
 ROOM='USB3_HUB2';

SECTION_NUMBER 1
 '@T6G_MB_LIB.T6G(SCH_1):PAGE157_I43@PURE_QUANTA.Q_CAP(CHIPS)':
 C_PATH='@t6g_mb_lib.t6g(sch_1):page157_i43@pure_quanta.q_cap(chips)',
 P_PATH='@t6g_mb_lib.t6g(sch_1):page179_i43@pure_quanta.q_cap(chips)',
 PATH='I43',
 DRAWING='@T6G_MB_LIB.T6G(SCH_1):PAGE157',
 TOLERANCE='10%',
 MATERIAL='X7R',
 PHYS_PAGE='179',
 XY='(-5450,825)',
 ROT='0',
 VER='1',
 PACK_TYPE='C0402',
 LOCATION='C6110',
 CDS_LIB='pure_quanta',
 CDS_PART_NAME='Q_CAP_C0402-0.01UF,50V,10%,X7R,CH31006KB18',
 VOLTAGE='50V',
 ROOM='USB3_HUB2',
 PART_NUMBER='CH31006KB18',
 VALUE='0.01UF',
 PRIM_FILE='./archive_libs/logical/q_cap/chips/chips.prt';

PART_NAME
 C6111 'Q_CAP_0402-0.1UF,25V,10%,X7R,CH4104K1B00':
 ROOM='USB3_HUB2';

SECTION_NUMBER 1
 '@T6G_MB_LIB.T6G(SCH_1):PAGE157_I42@PURE_QUANTA.Q_CAP(CHIPS)':
 C_PATH='@t6g_mb_lib.t6g(sch_1):page157_i42@pure_quanta.q_cap(chips)',
 P_PATH='@t6g_mb_lib.t6g(sch_1):page179_i42@pure_quanta.q_cap(chips)',
 PATH='I42',
 DRAWING='@T6G_MB_LIB.T6G(SCH_1):PAGE157',
 TOLERANCE='10%',
 MATERIAL='X7R',
 PHYS_PAGE='179',
 XY='(-5175,850)',
 ROT='0',
 VER='1',
 PACK_TYPE='0402',
 LOCATION='C6111',
 CDS_LIB='pure_quanta',
 CDS_PART_NAME='Q_CAP_0402-0.1UF,25V,10%,X7R,CH4104K1B00',
 VOLTAGE='25V',
 ROOM='USB3_HUB2',
 PART_NUMBER='CH4104K1B00',
 VALUE='0.1UF',
 PRIM_FILE='./archive_libs/logical/q_cap/chips/chips.prt';

PART_NAME
 C6112 'Q_CAP_C0402-1PF,50V,0.05P,COG,CH-106T0B00':
 ROOM='USB3_HUB2';

SECTION_NUMBER 1
 '@T6G_MB_LIB.T6G(SCH_1):PAGE157_I47@PURE_QUANTA.Q_CAP(CHIPS)':
 C_PATH='@t6g_mb_lib.t6g(sch_1):page157_i47@pure_quanta.q_cap(chips)',
 P_PATH='@t6g_mb_lib.t6g(sch_1):page179_i47@pure_quanta.q_cap(chips)',
 PATH='I47',
 DRAWING='@T6G_MB_LIB.T6G(SCH_1):PAGE157',
 TOLERANCE='0.05P',
 MATERIAL='COG',
 PHYS_PAGE='179',
 XY='(-4875,850)',
 ROT='0',
 VER='1',
 PACK_TYPE='C0402',
 LOCATION='C6112',
 CDS_LIB='pure_quanta',
 CDS_PART_NAME='Q_CAP_C0402-1PF,50V,0.05P,COG,CH-106T0B00',
 VOLTAGE='50V',
 ROOM='USB3_HUB2',
 PART_NUMBER='CH-106T0B00',
 VALUE='1PF',
 PRIM_FILE='./archive_libs/logical/q_cap/chips/chips.prt';

PART_NAME
 C6113 'Q_CAP_C0402-0.01UF,50V,10%,X7R,CH31006KB18':
 ROOM='USB3_HUB2';

SECTION_NUMBER 1
 '@T6G_MB_LIB.T6G(SCH_1):PAGE157_I46@PURE_QUANTA.Q_CAP(CHIPS)':
 C_PATH='@t6g_mb_lib.t6g(sch_1):page157_i46@pure_quanta.q_cap(chips)',
 P_PATH='@t6g_mb_lib.t6g(sch_1):page179_i46@pure_quanta.q_cap(chips)',
 PATH='I46',
 DRAWING='@T6G_MB_LIB.T6G(SCH_1):PAGE157',
 TOLERANCE='10%',
 MATERIAL='X7R',
 PHYS_PAGE='179',
 XY='(-4550,825)',
 ROT='0',
 VER='1',
 PACK_TYPE='C0402',
 LOCATION='C6113',
 CDS_LIB='pure_quanta',
 CDS_PART_NAME='Q_CAP_C0402-0.01UF,50V,10%,X7R,CH31006KB18',
 VOLTAGE='50V',
 ROOM='USB3_HUB2',
 PART_NUMBER='CH31006KB18',
 VALUE='0.01UF',
 PRIM_FILE='./archive_libs/logical/q_cap/chips/chips.prt';

PART_NAME
 C6114 'Q_CAP_0402-0.1UF,25V,10%,X7R,CH4104K1B00':
 ROOM='USB3_HUB2';

SECTION_NUMBER 1
 '@T6G_MB_LIB.T6G(SCH_1):PAGE157_I45@PURE_QUANTA.Q_CAP(CHIPS)':
 C_PATH='@t6g_mb_lib.t6g(sch_1):page157_i45@pure_quanta.q_cap(chips)',
 P_PATH='@t6g_mb_lib.t6g(sch_1):page179_i45@pure_quanta.q_cap(chips)',
 PATH='I45',
 DRAWING='@T6G_MB_LIB.T6G(SCH_1):PAGE157',
 TOLERANCE='10%',
 MATERIAL='X7R',
 PHYS_PAGE='179',
 XY='(-4250,850)',
 ROT='0',
 VER='1',
 PACK_TYPE='0402',
 LOCATION='C6114',
 CDS_LIB='pure_quanta',
 CDS_PART_NAME='Q_CAP_0402-0.1UF,25V,10%,X7R,CH4104K1B00',
 VOLTAGE='25V',
 ROOM='USB3_HUB2',
 PART_NUMBER='CH4104K1B00',
 VALUE='0.1UF',
 PRIM_FILE='./archive_libs/logical/q_cap/chips/chips.prt';

PART_NAME
 C6115 'Q_CAP_C0402-1PF,50V,0.05P,COG,CH-106T0B00':
 ROOM='USB3_HUB2';

SECTION_NUMBER 1
 '@T6G_MB_LIB.T6G(SCH_1):PAGE157_I50@PURE_QUANTA.Q_CAP(CHIPS)':
 C_PATH='@t6g_mb_lib.t6g(sch_1):page157_i50@pure_quanta.q_cap(chips)',
 P_PATH='@t6g_mb_lib.t6g(sch_1):page179_i50@pure_quanta.q_cap(chips)',
 PATH='I50',
 DRAWING='@T6G_MB_LIB.T6G(SCH_1):PAGE157',
 TOLERANCE='0.05P',
 MATERIAL='COG',
 PHYS_PAGE='179',
 XY='(-3925,850)',
 ROT='0',
 VER='1',
 PACK_TYPE='C0402',
 LOCATION='C6115',
 CDS_LIB='pure_quanta',
 CDS_PART_NAME='Q_CAP_C0402-1PF,50V,0.05P,COG,CH-106T0B00',
 VOLTAGE='50V',
 ROOM='USB3_HUB2',
 PART_NUMBER='CH-106T0B00',
 VALUE='1PF',
 PRIM_FILE='./archive_libs/logical/q_cap/chips/chips.prt';

PART_NAME
 C6116 'Q_CAP_C0402-0.01UF,50V,10%,X7R,CH31006KB18':
 ROOM='USB3_HUB2';

SECTION_NUMBER 1
 '@T6G_MB_LIB.T6G(SCH_1):PAGE157_I49@PURE_QUANTA.Q_CAP(CHIPS)':
 C_PATH='@t6g_mb_lib.t6g(sch_1):page157_i49@pure_quanta.q_cap(chips)',
 P_PATH='@t6g_mb_lib.t6g(sch_1):page179_i49@pure_quanta.q_cap(chips)',
 PATH='I49',
 DRAWING='@T6G_MB_LIB.T6G(SCH_1):PAGE157',
 TOLERANCE='10%',
 MATERIAL='X7R',
 PHYS_PAGE='179',
 XY='(-3675,850)',
 ROT='0',
 VER='1',
 PACK_TYPE='C0402',
 LOCATION='C6116',
 CDS_LIB='pure_quanta',
 CDS_PART_NAME='Q_CAP_C0402-0.01UF,50V,10%,X7R,CH31006KB18',
 VOLTAGE='50V',
 ROOM='USB3_HUB2',
 PART_NUMBER='CH31006KB18',
 VALUE='0.01UF',
 PRIM_FILE='./archive_libs/logical/q_cap/chips/chips.prt';

PART_NAME
 C6117 'Q_CAP_0402-0.1UF,25V,10%,X7R,CH4104K1B00':
 ROOM='USB3_HUB2';

SECTION_NUMBER 1
 '@T6G_MB_LIB.T6G(SCH_1):PAGE157_I48@PURE_QUANTA.Q_CAP(CHIPS)':
 C_PATH='@t6g_mb_lib.t6g(sch_1):page157_i48@pure_quanta.q_cap(chips)',
 P_PATH='@t6g_mb_lib.t6g(sch_1):page179_i48@pure_quanta.q_cap(chips)',
 PATH='I48',
 DRAWING='@T6G_MB_LIB.T6G(SCH_1):PAGE157',
 TOLERANCE='10%',
 MATERIAL='X7R',
 PHYS_PAGE='179',
 XY='(-3400,850)',
 ROT='0',
 VER='1',
 PACK_TYPE='0402',
 LOCATION='C6117',
 CDS_LIB='pure_quanta',
 CDS_PART_NAME='Q_CAP_0402-0.1UF,25V,10%,X7R,CH4104K1B00',
 VOLTAGE='25V',
 ROOM='USB3_HUB2',
 PART_NUMBER='CH4104K1B00',
 VALUE='0.1UF',
 PRIM_FILE='./archive_libs/logical/q_cap/chips/chips.prt';

PART_NAME
 C6118 'Q_CAP_C0805-10UF,25V,10%,X6S,CH6104KEA00':
 ROOM='USB3_HUB2';

SECTION_NUMBER 1
 '@T6G_MB_LIB.T6G(SCH_1):PAGE157_I54@PURE_QUANTA.Q_CAP(CHIPS)':
 C_PATH='@t6g_mb_lib.t6g(sch_1):page157_i54@pure_quanta.q_cap(chips)',
 P_PATH='@t6g_mb_lib.t6g(sch_1):page179_i54@pure_quanta.q_cap(chips)',
 PATH='I54',
 DRAWING='@T6G_MB_LIB.T6G(SCH_1):PAGE157',
 TOLERANCE='10%',
 MATERIAL='X6S',
 PHYS_PAGE='179',
 XY='(-3125,825)',
 ROT='0',
 VER='1',
 PACK_TYPE='C0805',
 LOCATION='C6118',
 CDS_LIB='pure_quanta',
 CDS_PART_NAME='Q_CAP_C0805-10UF,25V,10%,X6S,CH6104KEA00',
 VOLTAGE='25V',
 ROOM='USB3_HUB2',
 PART_NUMBER='CH6104KEA00',
 VALUE='10UF',
 PRIM_FILE='./archive_libs/logical/q_cap/chips/chips.prt';

PART_NAME
 C6119 'Q_CAP_C0402-1PF,50V,0.05P,COG,CH-106T0B00':
 ROOM='USB3_HUB2';

SECTION_NUMBER 1
 '@T6G_MB_LIB.T6G(SCH_1):PAGE157_I53@PURE_QUANTA.Q_CAP(CHIPS)':
 C_PATH='@t6g_mb_lib.t6g(sch_1):page157_i53@pure_quanta.q_cap(chips)',
 P_PATH='@t6g_mb_lib.t6g(sch_1):page179_i53@pure_quanta.q_cap(chips)',
 PATH='I53',
 DRAWING='@T6G_MB_LIB.T6G(SCH_1):PAGE157',
 TOLERANCE='0.05P',
 MATERIAL='COG',
 PHYS_PAGE='179',
 XY='(-2750,850)',
 ROT='0',
 VER='1',
 PACK_TYPE='C0402',
 LOCATION='C6119',
 CDS_LIB='pure_quanta',
 CDS_PART_NAME='Q_CAP_C0402-1PF,50V,0.05P,COG,CH-106T0B00',
 VOLTAGE='50V',
 ROOM='USB3_HUB2',
 PART_NUMBER='CH-106T0B00',
 VALUE='1PF',
 PRIM_FILE='./archive_libs/logical/q_cap/chips/chips.prt';

PART_NAME
 C6120 'Q_CAP_C0402-0.01UF,50V,10%,X7R,CH31006KB18':
 ROOM='USB3_HUB2';

SECTION_NUMBER 1
 '@T6G_MB_LIB.T6G(SCH_1):PAGE157_I52@PURE_QUANTA.Q_CAP(CHIPS)':
 C_PATH='@t6g_mb_lib.t6g(sch_1):page157_i52@pure_quanta.q_cap(chips)',
 P_PATH='@t6g_mb_lib.t6g(sch_1):page179_i52@pure_quanta.q_cap(chips)',
 PATH='I52',
 DRAWING='@T6G_MB_LIB.T6G(SCH_1):PAGE157',
 TOLERANCE='10%',
 MATERIAL='X7R',
 PHYS_PAGE='179',
 XY='(-2450,850)',
 ROT='0',
 VER='1',
 PACK_TYPE='C0402',
 LOCATION='C6120',
 CDS_LIB='pure_quanta',
 CDS_PART_NAME='Q_CAP_C0402-0.01UF,50V,10%,X7R,CH31006KB18',
 VOLTAGE='50V',
 ROOM='USB3_HUB2',
 PART_NUMBER='CH31006KB18',
 VALUE='0.01UF',
 PRIM_FILE='./archive_libs/logical/q_cap/chips/chips.prt';

PART_NAME
 C6121 'Q_CAP_0402-0.1UF,25V,10%,X7R,CH4104K1B00':
 ROOM='USB3_HUB2';

SECTION_NUMBER 1
 '@T6G_MB_LIB.T6G(SCH_1):PAGE157_I51@PURE_QUANTA.Q_CAP(CHIPS)':
 C_PATH='@t6g_mb_lib.t6g(sch_1):page157_i51@pure_quanta.q_cap(chips)',
 P_PATH='@t6g_mb_lib.t6g(sch_1):page179_i51@pure_quanta.q_cap(chips)',
 PATH='I51',
 DRAWING='@T6G_MB_LIB.T6G(SCH_1):PAGE157',
 TOLERANCE='10%',
 MATERIAL='X7R',
 PHYS_PAGE='179',
 XY='(-2200,850)',
 ROT='0',
 VER='1',
 PACK_TYPE='0402',
 LOCATION='C6121',
 CDS_LIB='pure_quanta',
 CDS_PART_NAME='Q_CAP_0402-0.1UF,25V,10%,X7R,CH4104K1B00',
 VOLTAGE='25V',
 ROOM='USB3_HUB2',
 PART_NUMBER='CH4104K1B00',
 VALUE='0.1UF',
 PRIM_FILE='./archive_libs/logical/q_cap/chips/chips.prt';

PART_NAME
 C6122 'Q_CAP_C0402-100NF,50V,10%,X7R,CH4106K1B01':;

SECTION_NUMBER 1
 '@T6G_MB_LIB.T6G(SCH_1):PAGE273_I79@PURE_QUANTA.Q_CAP(CHIPS)':
 C_PATH='@t6g_mb_lib.t6g(sch_1):page273_i79@pure_quanta.q_cap(chips)',
 P_PATH='@t6g_mb_lib.t6g(sch_1):page188_i79@pure_quanta.q_cap(chips)',
 PATH='I79',
 DRAWING='@T6G_MB_LIB.T6G(SCH_1):PAGE273',
 TOLERANCE='10%',
 MATERIAL='X7R',
 PHYS_PAGE='188',
 XY='(-4275,3525)',
 ROT='0',
 VER='1',
 PACK_TYPE='C0402',
 LOCATION='C6122',
 CDS_LIB='pure_quanta',
 CDS_PART_NAME='Q_CAP_C0402-100NF,50V,10%,X7R,CH4106K1B01',
 VOLTAGE='50V',
 PART_NUMBER='CH4106K1B01',
 VALUE='100NF',
 PRIM_FILE='./archive_libs/logical/q_cap/chips/chips.prt';

PART_NAME
 C6500 'Q_CAP_0402-0.1UF,25V,10%,X7R,CH4104K1B00':;

SECTION_NUMBER 1
 '@T6G_MB_LIB.T6G(SCH_1):PAGE273_I133@PURE_QUANTA.Q_CAP(CHIPS)':
 C_PATH='@t6g_mb_lib.t6g(sch_1):page273_i133@pure_quanta.q_cap(chips)',
 P_PATH='@t6g_mb_lib.t6g(sch_1):page188_i133@pure_quanta.q_cap(chips)',
 PATH='I133',
 DRAWING='@T6G_MB_LIB.T6G(SCH_1):PAGE273',
 TOLERANCE='10%',
 MATERIAL='X7R',
 PHYS_PAGE='188',
 XY='(-7575,2125)',
 ROT='0',
 VER='1',
 PACK_TYPE='0402',
 LOCATION='C6500',
 CDS_LIB='pure_quanta',
 CDS_PART_NAME='Q_CAP_0402-0.1UF,25V,10%,X7R,CH4104K1B00',
 VOLTAGE='25V',
 PART_NUMBER='CH4104K1B00',
 VALUE='0.1UF',
 PRIM_FILE='./archive_libs/logical/q_cap/chips/chips.prt';

PART_NAME
 C6501 'Q_CAP_DIFFBUS_C0201-DIFF BUS_0.22UF,6.3V,20%,X6S,SA':;

SECTION_NUMBER 1
 '@T6G_MB_LIB.T6G(SCH_1):PAGE384_I77@PURE_QUANTA.Q_CAP_DIFFBUS(CHIPS)':
 C_PATH='@t6g_mb_lib.t6g(sch_1):page384_i77@pure_quanta.q_cap_diffbus(chips)',
 P_PATH='@t6g_mb_lib.t6g(sch_1):page275_i77@pure_quanta.q_cap_diffbus(chips)',
 PATH='I77',
 DRAWING='@T6G_MB_LIB.T6G(SCH_1):PAGE384',
 PIN_NAMES_ROTATE='TRUE',
 TOLERANCE='20%',
 MATERIAL='X6S',
 PHYS_PAGE='275',
 XY='(-2400,2275)',
 ROT='2',
 VER='2',
 PACK_TYPE='C0201',
 LOCATION='C6501',
 CDS_LIB='pure_quanta',
 CDS_PART_NAME='Q_CAP_DIFFBUS_C0201-DIFF BUS_0.22UF,6.3V,20%,X6S,SA',
 VOLTAGE='6.3V',
 PART_NUMBER='SP_CH4221MEE01',
 VALUE='DIFF BUS_0.22UF',
 PRIM_FILE='./archive_libs/logical/q_cap_diffbus/chips/chips.prt';

PART_NAME
 C6502 'Q_CAP_DIFFBUS_C0201-DIFF BUS_0.22UF,6.3V,20%,X6S,SA':;

SECTION_NUMBER 1
 '@T6G_MB_LIB.T6G(SCH_1):PAGE384_I78@PURE_QUANTA.Q_CAP_DIFFBUS(CHIPS)':
 C_PATH='@t6g_mb_lib.t6g(sch_1):page384_i78@pure_quanta.q_cap_diffbus(chips)',
 P_PATH='@t6g_mb_lib.t6g(sch_1):page275_i78@pure_quanta.q_cap_diffbus(chips)',
 PATH='I78',
 DRAWING='@T6G_MB_LIB.T6G(SCH_1):PAGE384',
 PIN_NAMES_ROTATE='TRUE',
 TOLERANCE='20%',
 MATERIAL='X6S',
 PHYS_PAGE='275',
 XY='(-2400,2225)',
 ROT='2',
 VER='2',
 PACK_TYPE='C0201',
 LOCATION='C6502',
 CDS_LIB='pure_quanta',
 CDS_PART_NAME='Q_CAP_DIFFBUS_C0201-DIFF BUS_0.22UF,6.3V,20%,X6S,SA',
 VOLTAGE='6.3V',
 PART_NUMBER='SP_CH4221MEE01',
 VALUE='DIFF BUS_0.22UF',
 PRIM_FILE='./archive_libs/logical/q_cap_diffbus/chips/chips.prt';

PART_NAME
 C6503 'Q_CAP_DIFFBUS_C0201-DIFF BUS_0.22UF,6.3V,20%,X6S,SA':;

SECTION_NUMBER 1
 '@T6G_MB_LIB.T6G(SCH_1):PAGE384_I75@PURE_QUANTA.Q_CAP_DIFFBUS(CHIPS)':
 C_PATH='@t6g_mb_lib.t6g(sch_1):page384_i75@pure_quanta.q_cap_diffbus(chips)',
 P_PATH='@t6g_mb_lib.t6g(sch_1):page275_i75@pure_quanta.q_cap_diffbus(chips)',
 PATH='I75',
 DRAWING='@T6G_MB_LIB.T6G(SCH_1):PAGE384',
 PIN_NAMES_ROTATE='TRUE',
 TOLERANCE='20%',
 MATERIAL='X6S',
 PHYS_PAGE='275',
 XY='(-2400,2075)',
 ROT='2',
 VER='2',
 PACK_TYPE='C0201',
 LOCATION='C6503',
 CDS_LIB='pure_quanta',
 CDS_PART_NAME='Q_CAP_DIFFBUS_C0201-DIFF BUS_0.22UF,6.3V,20%,X6S,SA',
 VOLTAGE='6.3V',
 PART_NUMBER='SP_CH4221MEE01',
 VALUE='DIFF BUS_0.22UF',
 PRIM_FILE='./archive_libs/logical/q_cap_diffbus/chips/chips.prt';

PART_NAME
 C6504 'Q_CAP_DIFFBUS_C0201-DIFF BUS_0.22UF,6.3V,20%,X6S,SA':;

SECTION_NUMBER 1
 '@T6G_MB_LIB.T6G(SCH_1):PAGE384_I76@PURE_QUANTA.Q_CAP_DIFFBUS(CHIPS)':
 C_PATH='@t6g_mb_lib.t6g(sch_1):page384_i76@pure_quanta.q_cap_diffbus(chips)',
 P_PATH='@t6g_mb_lib.t6g(sch_1):page275_i76@pure_quanta.q_cap_diffbus(chips)',
 PATH='I76',
 DRAWING='@T6G_MB_LIB.T6G(SCH_1):PAGE384',
 PIN_NAMES_ROTATE='TRUE',
 TOLERANCE='20%',
 MATERIAL='X6S',
 PHYS_PAGE='275',
 XY='(-2400,2025)',
 ROT='2',
 VER='2',
 PACK_TYPE='C0201',
 LOCATION='C6504',
 CDS_LIB='pure_quanta',
 CDS_PART_NAME='Q_CAP_DIFFBUS_C0201-DIFF BUS_0.22UF,6.3V,20%,X6S,SA',
 VOLTAGE='6.3V',
 PART_NUMBER='SP_CH4221MEE01',
 VALUE='DIFF BUS_0.22UF',
 PRIM_FILE='./archive_libs/logical/q_cap_diffbus/chips/chips.prt';

PART_NAME
 C6505 'Q_CAP_DIFFBUS_C0201-DIFF BUS_0.22UF,6.3V,20%,X6S,SA':;

SECTION_NUMBER 1
 '@T6G_MB_LIB.T6G(SCH_1):PAGE384_I74@PURE_QUANTA.Q_CAP_DIFFBUS(CHIPS)':
 C_PATH='@t6g_mb_lib.t6g(sch_1):page384_i74@pure_quanta.q_cap_diffbus(chips)',
 P_PATH='@t6g_mb_lib.t6g(sch_1):page275_i74@pure_quanta.q_cap_diffbus(chips)',
 PATH='I74',
 DRAWING='@T6G_MB_LIB.T6G(SCH_1):PAGE384',
 PIN_NAMES_ROTATE='TRUE',
 TOLERANCE='20%',
 MATERIAL='X6S',
 PHYS_PAGE='275',
 XY='(-2400,1875)',
 ROT='2',
 VER='2',
 PACK_TYPE='C0201',
 LOCATION='C6505',
 CDS_LIB='pure_quanta',
 CDS_PART_NAME='Q_CAP_DIFFBUS_C0201-DIFF BUS_0.22UF,6.3V,20%,X6S,SA',
 VOLTAGE='6.3V',
 PART_NUMBER='SP_CH4221MEE01',
 VALUE='DIFF BUS_0.22UF',
 PRIM_FILE='./archive_libs/logical/q_cap_diffbus/chips/chips.prt';

PART_NAME
 C6506 'Q_CAP_DIFFBUS_C0201-DIFF BUS_0.22UF,6.3V,20%,X6S,SA':;

SECTION_NUMBER 1
 '@T6G_MB_LIB.T6G(SCH_1):PAGE384_I72@PURE_QUANTA.Q_CAP_DIFFBUS(CHIPS)':
 C_PATH='@t6g_mb_lib.t6g(sch_1):page384_i72@pure_quanta.q_cap_diffbus(chips)',
 P_PATH='@t6g_mb_lib.t6g(sch_1):page275_i72@pure_quanta.q_cap_diffbus(chips)',
 PATH='I72',
 DRAWING='@T6G_MB_LIB.T6G(SCH_1):PAGE384',
 PIN_NAMES_ROTATE='TRUE',
 TOLERANCE='20%',
 MATERIAL='X6S',
 PHYS_PAGE='275',
 XY='(-2400,1825)',
 ROT='2',
 VER='2',
 PACK_TYPE='C0201',
 LOCATION='C6506',
 CDS_LIB='pure_quanta',
 CDS_PART_NAME='Q_CAP_DIFFBUS_C0201-DIFF BUS_0.22UF,6.3V,20%,X6S,SA',
 VOLTAGE='6.3V',
 PART_NUMBER='SP_CH4221MEE01',
 VALUE='DIFF BUS_0.22UF',
 PRIM_FILE='./archive_libs/logical/q_cap_diffbus/chips/chips.prt';

PART_NAME
 C6507 'Q_CAP_DIFFBUS_C0201-DIFF BUS_0.22UF,6.3V,20%,X6S,SA':;

SECTION_NUMBER 1
 '@T6G_MB_LIB.T6G(SCH_1):PAGE384_I73@PURE_QUANTA.Q_CAP_DIFFBUS(CHIPS)':
 C_PATH='@t6g_mb_lib.t6g(sch_1):page384_i73@pure_quanta.q_cap_diffbus(chips)',
 P_PATH='@t6g_mb_lib.t6g(sch_1):page275_i73@pure_quanta.q_cap_diffbus(chips)',
 PATH='I73',
 DRAWING='@T6G_MB_LIB.T6G(SCH_1):PAGE384',
 PIN_NAMES_ROTATE='TRUE',
 TOLERANCE='20%',
 MATERIAL='X6S',
 PHYS_PAGE='275',
 XY='(-2400,1675)',
 ROT='2',
 VER='2',
 PACK_TYPE='C0201',
 LOCATION='C6507',
 CDS_LIB='pure_quanta',
 CDS_PART_NAME='Q_CAP_DIFFBUS_C0201-DIFF BUS_0.22UF,6.3V,20%,X6S,SA',
 VOLTAGE='6.3V',
 PART_NUMBER='SP_CH4221MEE01',
 VALUE='DIFF BUS_0.22UF',
 PRIM_FILE='./archive_libs/logical/q_cap_diffbus/chips/chips.prt';

PART_NAME
 C6508 'Q_CAP_DIFFBUS_C0201-DIFF BUS_0.22UF,6.3V,20%,X6S,SA':;

SECTION_NUMBER 1
 '@T6G_MB_LIB.T6G(SCH_1):PAGE384_I71@PURE_QUANTA.Q_CAP_DIFFBUS(CHIPS)':
 C_PATH='@t6g_mb_lib.t6g(sch_1):page384_i71@pure_quanta.q_cap_diffbus(chips)',
 P_PATH='@t6g_mb_lib.t6g(sch_1):page275_i71@pure_quanta.q_cap_diffbus(chips)',
 PATH='I71',
 DRAWING='@T6G_MB_LIB.T6G(SCH_1):PAGE384',
 PIN_NAMES_ROTATE='TRUE',
 TOLERANCE='20%',
 MATERIAL='X6S',
 PHYS_PAGE='275',
 XY='(-2400,1625)',
 ROT='2',
 VER='2',
 PACK_TYPE='C0201',
 LOCATION='C6508',
 CDS_LIB='pure_quanta',
 CDS_PART_NAME='Q_CAP_DIFFBUS_C0201-DIFF BUS_0.22UF,6.3V,20%,X6S,SA',
 VOLTAGE='6.3V',
 PART_NUMBER='SP_CH4221MEE01',
 VALUE='DIFF BUS_0.22UF',
 PRIM_FILE='./archive_libs/logical/q_cap_diffbus/chips/chips.prt';

PART_NAME
 C6509 'Q_CAP_DIFFBUS_C0201-DIFF BUS_0.22UF,6.3V,20%,X6S,SA':;

SECTION_NUMBER 1
 '@T6G_MB_LIB.T6G(SCH_1):PAGE384_I65@PURE_QUANTA.Q_CAP_DIFFBUS(CHIPS)':
 C_PATH='@t6g_mb_lib.t6g(sch_1):page384_i65@pure_quanta.q_cap_diffbus(chips)',
 P_PATH='@t6g_mb_lib.t6g(sch_1):page275_i65@pure_quanta.q_cap_diffbus(chips)',
 PATH='I65',
 DRAWING='@T6G_MB_LIB.T6G(SCH_1):PAGE384',
 PIN_NAMES_ROTATE='TRUE',
 TOLERANCE='20%',
 MATERIAL='X6S',
 PHYS_PAGE='275',
 XY='(-2400,1475)',
 ROT='2',
 VER='2',
 PACK_TYPE='C0201',
 LOCATION='C6509',
 CDS_LIB='pure_quanta',
 CDS_PART_NAME='Q_CAP_DIFFBUS_C0201-DIFF BUS_0.22UF,6.3V,20%,X6S,SA',
 VOLTAGE='6.3V',
 PART_NUMBER='SP_CH4221MEE01',
 VALUE='DIFF BUS_0.22UF',
 PRIM_FILE='./archive_libs/logical/q_cap_diffbus/chips/chips.prt';

PART_NAME
 C6510 'Q_CAP_DIFFBUS_C0201-DIFF BUS_0.22UF,6.3V,20%,X6S,SA':;

SECTION_NUMBER 1
 '@T6G_MB_LIB.T6G(SCH_1):PAGE384_I66@PURE_QUANTA.Q_CAP_DIFFBUS(CHIPS)':
 C_PATH='@t6g_mb_lib.t6g(sch_1):page384_i66@pure_quanta.q_cap_diffbus(chips)',
 P_PATH='@t6g_mb_lib.t6g(sch_1):page275_i66@pure_quanta.q_cap_diffbus(chips)',
 PATH='I66',
 DRAWING='@T6G_MB_LIB.T6G(SCH_1):PAGE384',
 PIN_NAMES_ROTATE='TRUE',
 TOLERANCE='20%',
 MATERIAL='X6S',
 PHYS_PAGE='275',
 XY='(-2400,1425)',
 ROT='2',
 VER='2',
 PACK_TYPE='C0201',
 LOCATION='C6510',
 CDS_LIB='pure_quanta',
 CDS_PART_NAME='Q_CAP_DIFFBUS_C0201-DIFF BUS_0.22UF,6.3V,20%,X6S,SA',
 VOLTAGE='6.3V',
 PART_NUMBER='SP_CH4221MEE01',
 VALUE='DIFF BUS_0.22UF',
 PRIM_FILE='./archive_libs/logical/q_cap_diffbus/chips/chips.prt';

PART_NAME
 C6511 'Q_CAP_DIFFBUS_C0201-DIFF BUS_0.22UF,6.3V,20%,X6S,SA':;

SECTION_NUMBER 1
 '@T6G_MB_LIB.T6G(SCH_1):PAGE384_I63@PURE_QUANTA.Q_CAP_DIFFBUS(CHIPS)':
 C_PATH='@t6g_mb_lib.t6g(sch_1):page384_i63@pure_quanta.q_cap_diffbus(chips)',
 P_PATH='@t6g_mb_lib.t6g(sch_1):page275_i63@pure_quanta.q_cap_diffbus(chips)',
 PATH='I63',
 DRAWING='@T6G_MB_LIB.T6G(SCH_1):PAGE384',
 PIN_NAMES_ROTATE='TRUE',
 TOLERANCE='20%',
 MATERIAL='X6S',
 PHYS_PAGE='275',
 XY='(-2400,1275)',
 ROT='2',
 VER='2',
 PACK_TYPE='C0201',
 LOCATION='C6511',
 CDS_LIB='pure_quanta',
 CDS_PART_NAME='Q_CAP_DIFFBUS_C0201-DIFF BUS_0.22UF,6.3V,20%,X6S,SA',
 VOLTAGE='6.3V',
 PART_NUMBER='SP_CH4221MEE01',
 VALUE='DIFF BUS_0.22UF',
 PRIM_FILE='./archive_libs/logical/q_cap_diffbus/chips/chips.prt';

PART_NAME
 C6512 'Q_CAP_DIFFBUS_C0201-DIFF BUS_0.22UF,6.3V,20%,X6S,SA':;

SECTION_NUMBER 1
 '@T6G_MB_LIB.T6G(SCH_1):PAGE384_I64@PURE_QUANTA.Q_CAP_DIFFBUS(CHIPS)':
 C_PATH='@t6g_mb_lib.t6g(sch_1):page384_i64@pure_quanta.q_cap_diffbus(chips)',
 P_PATH='@t6g_mb_lib.t6g(sch_1):page275_i64@pure_quanta.q_cap_diffbus(chips)',
 PATH='I64',
 DRAWING='@T6G_MB_LIB.T6G(SCH_1):PAGE384',
 PIN_NAMES_ROTATE='TRUE',
 TOLERANCE='20%',
 MATERIAL='X6S',
 PHYS_PAGE='275',
 XY='(-2400,1225)',
 ROT='2',
 VER='2',
 PACK_TYPE='C0201',
 LOCATION='C6512',
 CDS_LIB='pure_quanta',
 CDS_PART_NAME='Q_CAP_DIFFBUS_C0201-DIFF BUS_0.22UF,6.3V,20%,X6S,SA',
 VOLTAGE='6.3V',
 PART_NUMBER='SP_CH4221MEE01',
 VALUE='DIFF BUS_0.22UF',
 PRIM_FILE='./archive_libs/logical/q_cap_diffbus/chips/chips.prt';

PART_NAME
 C6513 'Q_CAP_DIFFBUS_C0201-DIFF BUS_0.22UF,6.3V,20%,X6S,SA':;

SECTION_NUMBER 1
 '@T6G_MB_LIB.T6G(SCH_1):PAGE384_I60@PURE_QUANTA.Q_CAP_DIFFBUS(CHIPS)':
 C_PATH='@t6g_mb_lib.t6g(sch_1):page384_i60@pure_quanta.q_cap_diffbus(chips)',
 P_PATH='@t6g_mb_lib.t6g(sch_1):page275_i60@pure_quanta.q_cap_diffbus(chips)',
 PATH='I60',
 DRAWING='@T6G_MB_LIB.T6G(SCH_1):PAGE384',
 PIN_NAMES_ROTATE='TRUE',
 TOLERANCE='20%',
 MATERIAL='X6S',
 PHYS_PAGE='275',
 XY='(-2400,1075)',
 ROT='2',
 VER='2',
 PACK_TYPE='C0201',
 LOCATION='C6513',
 CDS_LIB='pure_quanta',
 CDS_PART_NAME='Q_CAP_DIFFBUS_C0201-DIFF BUS_0.22UF,6.3V,20%,X6S,SA',
 VOLTAGE='6.3V',
 PART_NUMBER='SP_CH4221MEE01',
 VALUE='DIFF BUS_0.22UF',
 PRIM_FILE='./archive_libs/logical/q_cap_diffbus/chips/chips.prt';

PART_NAME
 C6514 'Q_CAP_DIFFBUS_C0201-DIFF BUS_0.22UF,6.3V,20%,X6S,SA':;

SECTION_NUMBER 1
 '@T6G_MB_LIB.T6G(SCH_1):PAGE384_I61@PURE_QUANTA.Q_CAP_DIFFBUS(CHIPS)':
 C_PATH='@t6g_mb_lib.t6g(sch_1):page384_i61@pure_quanta.q_cap_diffbus(chips)',
 P_PATH='@t6g_mb_lib.t6g(sch_1):page275_i61@pure_quanta.q_cap_diffbus(chips)',
 PATH='I61',
 DRAWING='@T6G_MB_LIB.T6G(SCH_1):PAGE384',
 PIN_NAMES_ROTATE='TRUE',
 TOLERANCE='20%',
 MATERIAL='X6S',
 PHYS_PAGE='275',
 XY='(-2400,1025)',
 ROT='2',
 VER='2',
 PACK_TYPE='C0201',
 LOCATION='C6514',
 CDS_LIB='pure_quanta',
 CDS_PART_NAME='Q_CAP_DIFFBUS_C0201-DIFF BUS_0.22UF,6.3V,20%,X6S,SA',
 VOLTAGE='6.3V',
 PART_NUMBER='SP_CH4221MEE01',
 VALUE='DIFF BUS_0.22UF',
 PRIM_FILE='./archive_libs/logical/q_cap_diffbus/chips/chips.prt';

PART_NAME
 C6515 'Q_CAP_DIFFBUS_C0201-DIFF BUS_0.22UF,6.3V,20%,X6S,SA':;

SECTION_NUMBER 1
 '@T6G_MB_LIB.T6G(SCH_1):PAGE384_I62@PURE_QUANTA.Q_CAP_DIFFBUS(CHIPS)':
 C_PATH='@t6g_mb_lib.t6g(sch_1):page384_i62@pure_quanta.q_cap_diffbus(chips)',
 P_PATH='@t6g_mb_lib.t6g(sch_1):page275_i62@pure_quanta.q_cap_diffbus(chips)',
 PATH='I62',
 DRAWING='@T6G_MB_LIB.T6G(SCH_1):PAGE384',
 PIN_NAMES_ROTATE='TRUE',
 TOLERANCE='20%',
 MATERIAL='X6S',
 PHYS_PAGE='275',
 XY='(-2400,875)',
 ROT='2',
 VER='2',
 PACK_TYPE='C0201',
 LOCATION='C6515',
 CDS_LIB='pure_quanta',
 CDS_PART_NAME='Q_CAP_DIFFBUS_C0201-DIFF BUS_0.22UF,6.3V,20%,X6S,SA',
 VOLTAGE='6.3V',
 PART_NUMBER='SP_CH4221MEE01',
 VALUE='DIFF BUS_0.22UF',
 PRIM_FILE='./archive_libs/logical/q_cap_diffbus/chips/chips.prt';

PART_NAME
 C6516 'Q_CAP_DIFFBUS_C0201-DIFF BUS_0.22UF,6.3V,20%,X6S,SA':;

SECTION_NUMBER 1
 '@T6G_MB_LIB.T6G(SCH_1):PAGE384_I59@PURE_QUANTA.Q_CAP_DIFFBUS(CHIPS)':
 C_PATH='@t6g_mb_lib.t6g(sch_1):page384_i59@pure_quanta.q_cap_diffbus(chips)',
 P_PATH='@t6g_mb_lib.t6g(sch_1):page275_i59@pure_quanta.q_cap_diffbus(chips)',
 PATH='I59',
 DRAWING='@T6G_MB_LIB.T6G(SCH_1):PAGE384',
 PIN_NAMES_ROTATE='TRUE',
 TOLERANCE='20%',
 MATERIAL='X6S',
 PHYS_PAGE='275',
 XY='(-2400,825)',
 ROT='2',
 VER='2',
 PACK_TYPE='C0201',
 LOCATION='C6516',
 CDS_LIB='pure_quanta',
 CDS_PART_NAME='Q_CAP_DIFFBUS_C0201-DIFF BUS_0.22UF,6.3V,20%,X6S,SA',
 VOLTAGE='6.3V',
 PART_NUMBER='SP_CH4221MEE01',
 VALUE='DIFF BUS_0.22UF',
 PRIM_FILE='./archive_libs/logical/q_cap_diffbus/chips/chips.prt';

PART_NAME
 C6517 'Q_CAP_DIFFBUS_C0201-DIFF BUS_0.22UF,6.3V,20%,X6S,SA':;

SECTION_NUMBER 1
 '@T6G_MB_LIB.T6G(SCH_1):PAGE384_I99@PURE_QUANTA.Q_CAP_DIFFBUS(CHIPS)':
 C_PATH='@t6g_mb_lib.t6g(sch_1):page384_i99@pure_quanta.q_cap_diffbus(chips)',
 P_PATH='@t6g_mb_lib.t6g(sch_1):page275_i99@pure_quanta.q_cap_diffbus(chips)',
 PATH='I99',
 DRAWING='@T6G_MB_LIB.T6G(SCH_1):PAGE384',
 PIN_NAMES_ROTATE='TRUE',
 TOLERANCE='20%',
 MATERIAL='X6S',
 PHYS_PAGE='275',
 XY='(-7000,2325)',
 ROT='2',
 VER='2',
 PACK_TYPE='C0201',
 LOCATION='C6517',
 CDS_LIB='pure_quanta',
 CDS_PART_NAME='Q_CAP_DIFFBUS_C0201-DIFF BUS_0.22UF,6.3V,20%,X6S,SA',
 VOLTAGE='6.3V',
 PART_NUMBER='SP_CH4221MEE01',
 VALUE='DIFF BUS_0.22UF',
 PRIM_FILE='./archive_libs/logical/q_cap_diffbus/chips/chips.prt';

PART_NAME
 C6518 'Q_CAP_DIFFBUS_C0201-DIFF BUS_0.22UF,6.3V,20%,X6S,SA':;

SECTION_NUMBER 1
 '@T6G_MB_LIB.T6G(SCH_1):PAGE384_I100@PURE_QUANTA.Q_CAP_DIFFBUS(CHIPS)':
 C_PATH='@t6g_mb_lib.t6g(sch_1):page384_i100@pure_quanta.q_cap_diffbus(chips)',
 P_PATH='@t6g_mb_lib.t6g(sch_1):page275_i100@pure_quanta.q_cap_diffbus(chips)',
 PATH='I100',
 DRAWING='@T6G_MB_LIB.T6G(SCH_1):PAGE384',
 PIN_NAMES_ROTATE='TRUE',
 TOLERANCE='20%',
 MATERIAL='X6S',
 PHYS_PAGE='275',
 XY='(-7000,2275)',
 ROT='2',
 VER='2',
 PACK_TYPE='C0201',
 LOCATION='C6518',
 CDS_LIB='pure_quanta',
 CDS_PART_NAME='Q_CAP_DIFFBUS_C0201-DIFF BUS_0.22UF,6.3V,20%,X6S,SA',
 VOLTAGE='6.3V',
 PART_NUMBER='SP_CH4221MEE01',
 VALUE='DIFF BUS_0.22UF',
 PRIM_FILE='./archive_libs/logical/q_cap_diffbus/chips/chips.prt';

PART_NAME
 C6519 'Q_CAP_DIFFBUS_C0201-DIFF BUS_0.22UF,6.3V,20%,X6S,SA':;

SECTION_NUMBER 1
 '@T6G_MB_LIB.T6G(SCH_1):PAGE384_I102@PURE_QUANTA.Q_CAP_DIFFBUS(CHIPS)':
 C_PATH='@t6g_mb_lib.t6g(sch_1):page384_i102@pure_quanta.q_cap_diffbus(chips)',
 P_PATH='@t6g_mb_lib.t6g(sch_1):page275_i102@pure_quanta.q_cap_diffbus(chips)',
 PATH='I102',
 DRAWING='@T6G_MB_LIB.T6G(SCH_1):PAGE384',
 PIN_NAMES_ROTATE='TRUE',
 TOLERANCE='20%',
 MATERIAL='X6S',
 PHYS_PAGE='275',
 XY='(-7000,2125)',
 ROT='2',
 VER='2',
 PACK_TYPE='C0201',
 LOCATION='C6519',
 CDS_LIB='pure_quanta',
 CDS_PART_NAME='Q_CAP_DIFFBUS_C0201-DIFF BUS_0.22UF,6.3V,20%,X6S,SA',
 VOLTAGE='6.3V',
 PART_NUMBER='SP_CH4221MEE01',
 VALUE='DIFF BUS_0.22UF',
 PRIM_FILE='./archive_libs/logical/q_cap_diffbus/chips/chips.prt';

PART_NAME
 C6520 'Q_CAP_DIFFBUS_C0201-DIFF BUS_0.22UF,6.3V,20%,X6S,SA':;

SECTION_NUMBER 1
 '@T6G_MB_LIB.T6G(SCH_1):PAGE384_I101@PURE_QUANTA.Q_CAP_DIFFBUS(CHIPS)':
 C_PATH='@t6g_mb_lib.t6g(sch_1):page384_i101@pure_quanta.q_cap_diffbus(chips)',
 P_PATH='@t6g_mb_lib.t6g(sch_1):page275_i101@pure_quanta.q_cap_diffbus(chips)',
 PATH='I101',
 DRAWING='@T6G_MB_LIB.T6G(SCH_1):PAGE384',
 PIN_NAMES_ROTATE='TRUE',
 TOLERANCE='20%',
 MATERIAL='X6S',
 PHYS_PAGE='275',
 XY='(-7000,2075)',
 ROT='2',
 VER='2',
 PACK_TYPE='C0201',
 LOCATION='C6520',
 CDS_LIB='pure_quanta',
 CDS_PART_NAME='Q_CAP_DIFFBUS_C0201-DIFF BUS_0.22UF,6.3V,20%,X6S,SA',
 VOLTAGE='6.3V',
 PART_NUMBER='SP_CH4221MEE01',
 VALUE='DIFF BUS_0.22UF',
 PRIM_FILE='./archive_libs/logical/q_cap_diffbus/chips/chips.prt';

PART_NAME
 C6521 'Q_CAP_DIFFBUS_C0201-DIFF BUS_0.22UF,6.3V,20%,X6S,SA':;

SECTION_NUMBER 1
 '@T6G_MB_LIB.T6G(SCH_1):PAGE384_I119@PURE_QUANTA.Q_CAP_DIFFBUS(CHIPS)':
 C_PATH='@t6g_mb_lib.t6g(sch_1):page384_i119@pure_quanta.q_cap_diffbus(chips)',
 P_PATH='@t6g_mb_lib.t6g(sch_1):page275_i119@pure_quanta.q_cap_diffbus(chips)',
 PATH='I119',
 DRAWING='@T6G_MB_LIB.T6G(SCH_1):PAGE384',
 PIN_NAMES_ROTATE='TRUE',
 TOLERANCE='20%',
 MATERIAL='X6S',
 PHYS_PAGE='275',
 XY='(-7000,1925)',
 ROT='2',
 VER='2',
 PACK_TYPE='C0201',
 LOCATION='C6521',
 CDS_LIB='pure_quanta',
 CDS_PART_NAME='Q_CAP_DIFFBUS_C0201-DIFF BUS_0.22UF,6.3V,20%,X6S,SA',
 VOLTAGE='6.3V',
 PART_NUMBER='SP_CH4221MEE01',
 VALUE='DIFF BUS_0.22UF',
 PRIM_FILE='./archive_libs/logical/q_cap_diffbus/chips/chips.prt';

PART_NAME
 C6522 'Q_CAP_DIFFBUS_C0201-DIFF BUS_0.22UF,6.3V,20%,X6S,SA':;

SECTION_NUMBER 1
 '@T6G_MB_LIB.T6G(SCH_1):PAGE384_I118@PURE_QUANTA.Q_CAP_DIFFBUS(CHIPS)':
 C_PATH='@t6g_mb_lib.t6g(sch_1):page384_i118@pure_quanta.q_cap_diffbus(chips)',
 P_PATH='@t6g_mb_lib.t6g(sch_1):page275_i118@pure_quanta.q_cap_diffbus(chips)',
 PATH='I118',
 DRAWING='@T6G_MB_LIB.T6G(SCH_1):PAGE384',
 PIN_NAMES_ROTATE='TRUE',
 TOLERANCE='20%',
 MATERIAL='X6S',
 PHYS_PAGE='275',
 XY='(-7000,1875)',
 ROT='2',
 VER='2',
 PACK_TYPE='C0201',
 LOCATION='C6522',
 CDS_LIB='pure_quanta',
 CDS_PART_NAME='Q_CAP_DIFFBUS_C0201-DIFF BUS_0.22UF,6.3V,20%,X6S,SA',
 VOLTAGE='6.3V',
 PART_NUMBER='SP_CH4221MEE01',
 VALUE='DIFF BUS_0.22UF',
 PRIM_FILE='./archive_libs/logical/q_cap_diffbus/chips/chips.prt';

PART_NAME
 C6523 'Q_CAP_DIFFBUS_C0201-DIFF BUS_0.22UF,6.3V,20%,X6S,SA':;

SECTION_NUMBER 1
 '@T6G_MB_LIB.T6G(SCH_1):PAGE384_I120@PURE_QUANTA.Q_CAP_DIFFBUS(CHIPS)':
 C_PATH='@t6g_mb_lib.t6g(sch_1):page384_i120@pure_quanta.q_cap_diffbus(chips)',
 P_PATH='@t6g_mb_lib.t6g(sch_1):page275_i120@pure_quanta.q_cap_diffbus(chips)',
 PATH='I120',
 DRAWING='@T6G_MB_LIB.T6G(SCH_1):PAGE384',
 PIN_NAMES_ROTATE='TRUE',
 TOLERANCE='20%',
 MATERIAL='X6S',
 PHYS_PAGE='275',
 XY='(-7000,1725)',
 ROT='2',
 VER='2',
 PACK_TYPE='C0201',
 LOCATION='C6523',
 CDS_LIB='pure_quanta',
 CDS_PART_NAME='Q_CAP_DIFFBUS_C0201-DIFF BUS_0.22UF,6.3V,20%,X6S,SA',
 VOLTAGE='6.3V',
 PART_NUMBER='SP_CH4221MEE01',
 VALUE='DIFF BUS_0.22UF',
 PRIM_FILE='./archive_libs/logical/q_cap_diffbus/chips/chips.prt';

PART_NAME
 C6524 'Q_CAP_DIFFBUS_C0201-DIFF BUS_0.22UF,6.3V,20%,X6S,SA':;

SECTION_NUMBER 1
 '@T6G_MB_LIB.T6G(SCH_1):PAGE384_I121@PURE_QUANTA.Q_CAP_DIFFBUS(CHIPS)':
 C_PATH='@t6g_mb_lib.t6g(sch_1):page384_i121@pure_quanta.q_cap_diffbus(chips)',
 P_PATH='@t6g_mb_lib.t6g(sch_1):page275_i121@pure_quanta.q_cap_diffbus(chips)',
 PATH='I121',
 DRAWING='@T6G_MB_LIB.T6G(SCH_1):PAGE384',
 PIN_NAMES_ROTATE='TRUE',
 TOLERANCE='20%',
 MATERIAL='X6S',
 PHYS_PAGE='275',
 XY='(-7000,1675)',
 ROT='2',
 VER='2',
 PACK_TYPE='C0201',
 LOCATION='C6524',
 CDS_LIB='pure_quanta',
 CDS_PART_NAME='Q_CAP_DIFFBUS_C0201-DIFF BUS_0.22UF,6.3V,20%,X6S,SA',
 VOLTAGE='6.3V',
 PART_NUMBER='SP_CH4221MEE01',
 VALUE='DIFF BUS_0.22UF',
 PRIM_FILE='./archive_libs/logical/q_cap_diffbus/chips/chips.prt';

PART_NAME
 C6525 'Q_CAP_DIFFBUS_C0201-DIFF BUS_0.22UF,6.3V,20%,X6S,SA':;

SECTION_NUMBER 1
 '@T6G_MB_LIB.T6G(SCH_1):PAGE384_I123@PURE_QUANTA.Q_CAP_DIFFBUS(CHIPS)':
 C_PATH='@t6g_mb_lib.t6g(sch_1):page384_i123@pure_quanta.q_cap_diffbus(chips)',
 P_PATH='@t6g_mb_lib.t6g(sch_1):page275_i123@pure_quanta.q_cap_diffbus(chips)',
 PATH='I123',
 DRAWING='@T6G_MB_LIB.T6G(SCH_1):PAGE384',
 PIN_NAMES_ROTATE='TRUE',
 TOLERANCE='20%',
 MATERIAL='X6S',
 PHYS_PAGE='275',
 XY='(-7000,1525)',
 ROT='2',
 VER='2',
 PACK_TYPE='C0201',
 LOCATION='C6525',
 CDS_LIB='pure_quanta',
 CDS_PART_NAME='Q_CAP_DIFFBUS_C0201-DIFF BUS_0.22UF,6.3V,20%,X6S,SA',
 VOLTAGE='6.3V',
 PART_NUMBER='SP_CH4221MEE01',
 VALUE='DIFF BUS_0.22UF',
 PRIM_FILE='./archive_libs/logical/q_cap_diffbus/chips/chips.prt';

PART_NAME
 C6526 'Q_CAP_DIFFBUS_C0201-DIFF BUS_0.22UF,6.3V,20%,X6S,SA':;

SECTION_NUMBER 1
 '@T6G_MB_LIB.T6G(SCH_1):PAGE384_I122@PURE_QUANTA.Q_CAP_DIFFBUS(CHIPS)':
 C_PATH='@t6g_mb_lib.t6g(sch_1):page384_i122@pure_quanta.q_cap_diffbus(chips)',
 P_PATH='@t6g_mb_lib.t6g(sch_1):page275_i122@pure_quanta.q_cap_diffbus(chips)',
 PATH='I122',
 DRAWING='@T6G_MB_LIB.T6G(SCH_1):PAGE384',
 PIN_NAMES_ROTATE='TRUE',
 TOLERANCE='20%',
 MATERIAL='X6S',
 PHYS_PAGE='275',
 XY='(-7000,1475)',
 ROT='2',
 VER='2',
 PACK_TYPE='C0201',
 LOCATION='C6526',
 CDS_LIB='pure_quanta',
 CDS_PART_NAME='Q_CAP_DIFFBUS_C0201-DIFF BUS_0.22UF,6.3V,20%,X6S,SA',
 VOLTAGE='6.3V',
 PART_NUMBER='SP_CH4221MEE01',
 VALUE='DIFF BUS_0.22UF',
 PRIM_FILE='./archive_libs/logical/q_cap_diffbus/chips/chips.prt';

PART_NAME
 C6527 'Q_CAP_DIFFBUS_C0201-DIFF BUS_0.22UF,6.3V,20%,X6S,SA':;

SECTION_NUMBER 1
 '@T6G_MB_LIB.T6G(SCH_1):PAGE384_I124@PURE_QUANTA.Q_CAP_DIFFBUS(CHIPS)':
 C_PATH='@t6g_mb_lib.t6g(sch_1):page384_i124@pure_quanta.q_cap_diffbus(chips)',
 P_PATH='@t6g_mb_lib.t6g(sch_1):page275_i124@pure_quanta.q_cap_diffbus(chips)',
 PATH='I124',
 DRAWING='@T6G_MB_LIB.T6G(SCH_1):PAGE384',
 PIN_NAMES_ROTATE='TRUE',
 TOLERANCE='20%',
 MATERIAL='X6S',
 PHYS_PAGE='275',
 XY='(-7000,1325)',
 ROT='2',
 VER='2',
 PACK_TYPE='C0201',
 LOCATION='C6527',
 CDS_LIB='pure_quanta',
 CDS_PART_NAME='Q_CAP_DIFFBUS_C0201-DIFF BUS_0.22UF,6.3V,20%,X6S,SA',
 VOLTAGE='6.3V',
 PART_NUMBER='SP_CH4221MEE01',
 VALUE='DIFF BUS_0.22UF',
 PRIM_FILE='./archive_libs/logical/q_cap_diffbus/chips/chips.prt';

PART_NAME
 C6528 'Q_CAP_DIFFBUS_C0201-DIFF BUS_0.22UF,6.3V,20%,X6S,SA':;

SECTION_NUMBER 1
 '@T6G_MB_LIB.T6G(SCH_1):PAGE384_I125@PURE_QUANTA.Q_CAP_DIFFBUS(CHIPS)':
 C_PATH='@t6g_mb_lib.t6g(sch_1):page384_i125@pure_quanta.q_cap_diffbus(chips)',
 P_PATH='@t6g_mb_lib.t6g(sch_1):page275_i125@pure_quanta.q_cap_diffbus(chips)',
 PATH='I125',
 DRAWING='@T6G_MB_LIB.T6G(SCH_1):PAGE384',
 PIN_NAMES_ROTATE='TRUE',
 TOLERANCE='20%',
 MATERIAL='X6S',
 PHYS_PAGE='275',
 XY='(-7000,1275)',
 ROT='2',
 VER='2',
 PACK_TYPE='C0201',
 LOCATION='C6528',
 CDS_LIB='pure_quanta',
 CDS_PART_NAME='Q_CAP_DIFFBUS_C0201-DIFF BUS_0.22UF,6.3V,20%,X6S,SA',
 VOLTAGE='6.3V',
 PART_NUMBER='SP_CH4221MEE01',
 VALUE='DIFF BUS_0.22UF',
 PRIM_FILE='./archive_libs/logical/q_cap_diffbus/chips/chips.prt';

PART_NAME
 C6529 'Q_CAP_DIFFBUS_C0201-DIFF BUS_0.22UF,6.3V,20%,X6S,SA':;

SECTION_NUMBER 1
 '@T6G_MB_LIB.T6G(SCH_1):PAGE384_I126@PURE_QUANTA.Q_CAP_DIFFBUS(CHIPS)':
 C_PATH='@t6g_mb_lib.t6g(sch_1):page384_i126@pure_quanta.q_cap_diffbus(chips)',
 P_PATH='@t6g_mb_lib.t6g(sch_1):page275_i126@pure_quanta.q_cap_diffbus(chips)',
 PATH='I126',
 DRAWING='@T6G_MB_LIB.T6G(SCH_1):PAGE384',
 PIN_NAMES_ROTATE='TRUE',
 TOLERANCE='20%',
 MATERIAL='X6S',
 PHYS_PAGE='275',
 XY='(-7000,1125)',
 ROT='2',
 VER='2',
 PACK_TYPE='C0201',
 LOCATION='C6529',
 CDS_LIB='pure_quanta',
 CDS_PART_NAME='Q_CAP_DIFFBUS_C0201-DIFF BUS_0.22UF,6.3V,20%,X6S,SA',
 VOLTAGE='6.3V',
 PART_NUMBER='SP_CH4221MEE01',
 VALUE='DIFF BUS_0.22UF',
 PRIM_FILE='./archive_libs/logical/q_cap_diffbus/chips/chips.prt';

PART_NAME
 C6530 'Q_CAP_DIFFBUS_C0201-DIFF BUS_0.22UF,6.3V,20%,X6S,SA':;

SECTION_NUMBER 1
 '@T6G_MB_LIB.T6G(SCH_1):PAGE384_I127@PURE_QUANTA.Q_CAP_DIFFBUS(CHIPS)':
 C_PATH='@t6g_mb_lib.t6g(sch_1):page384_i127@pure_quanta.q_cap_diffbus(chips)',
 P_PATH='@t6g_mb_lib.t6g(sch_1):page275_i127@pure_quanta.q_cap_diffbus(chips)',
 PATH='I127',
 DRAWING='@T6G_MB_LIB.T6G(SCH_1):PAGE384',
 PIN_NAMES_ROTATE='TRUE',
 TOLERANCE='20%',
 MATERIAL='X6S',
 PHYS_PAGE='275',
 XY='(-7000,1075)',
 ROT='2',
 VER='2',
 PACK_TYPE='C0201',
 LOCATION='C6530',
 CDS_LIB='pure_quanta',
 CDS_PART_NAME='Q_CAP_DIFFBUS_C0201-DIFF BUS_0.22UF,6.3V,20%,X6S,SA',
 VOLTAGE='6.3V',
 PART_NUMBER='SP_CH4221MEE01',
 VALUE='DIFF BUS_0.22UF',
 PRIM_FILE='./archive_libs/logical/q_cap_diffbus/chips/chips.prt';

PART_NAME
 C6531 'Q_CAP_DIFFBUS_C0201-DIFF BUS_0.22UF,6.3V,20%,X6S,SA':;

SECTION_NUMBER 1
 '@T6G_MB_LIB.T6G(SCH_1):PAGE384_I129@PURE_QUANTA.Q_CAP_DIFFBUS(CHIPS)':
 C_PATH='@t6g_mb_lib.t6g(sch_1):page384_i129@pure_quanta.q_cap_diffbus(chips)',
 P_PATH='@t6g_mb_lib.t6g(sch_1):page275_i129@pure_quanta.q_cap_diffbus(chips)',
 PATH='I129',
 DRAWING='@T6G_MB_LIB.T6G(SCH_1):PAGE384',
 PIN_NAMES_ROTATE='TRUE',
 TOLERANCE='20%',
 MATERIAL='X6S',
 PHYS_PAGE='275',
 XY='(-7000,925)',
 ROT='2',
 VER='2',
 PACK_TYPE='C0201',
 LOCATION='C6531',
 CDS_LIB='pure_quanta',
 CDS_PART_NAME='Q_CAP_DIFFBUS_C0201-DIFF BUS_0.22UF,6.3V,20%,X6S,SA',
 VOLTAGE='6.3V',
 PART_NUMBER='SP_CH4221MEE01',
 VALUE='DIFF BUS_0.22UF',
 PRIM_FILE='./archive_libs/logical/q_cap_diffbus/chips/chips.prt';

PART_NAME
 C6532 'Q_CAP_DIFFBUS_C0201-DIFF BUS_0.22UF,6.3V,20%,X6S,SA':;

SECTION_NUMBER 1
 '@T6G_MB_LIB.T6G(SCH_1):PAGE384_I130@PURE_QUANTA.Q_CAP_DIFFBUS(CHIPS)':
 C_PATH='@t6g_mb_lib.t6g(sch_1):page384_i130@pure_quanta.q_cap_diffbus(chips)',
 P_PATH='@t6g_mb_lib.t6g(sch_1):page275_i130@pure_quanta.q_cap_diffbus(chips)',
 PATH='I130',
 DRAWING='@T6G_MB_LIB.T6G(SCH_1):PAGE384',
 PIN_NAMES_ROTATE='TRUE',
 TOLERANCE='20%',
 MATERIAL='X6S',
 PHYS_PAGE='275',
 XY='(-7000,875)',
 ROT='2',
 VER='2',
 PACK_TYPE='C0201',
 LOCATION='C6532',
 CDS_LIB='pure_quanta',
 CDS_PART_NAME='Q_CAP_DIFFBUS_C0201-DIFF BUS_0.22UF,6.3V,20%,X6S,SA',
 VOLTAGE='6.3V',
 PART_NUMBER='SP_CH4221MEE01',
 VALUE='DIFF BUS_0.22UF',
 PRIM_FILE='./archive_libs/logical/q_cap_diffbus/chips/chips.prt';

PART_NAME
 C6533 'Q_CAP_DIFFBUS_C0201-DIFF BUS_0.22UF,6.3V,20%,X6S,SA':;

SECTION_NUMBER 1
 '@T6G_MB_LIB.T6G(SCH_1):PAGE407_I46@PURE_QUANTA.Q_CAP_DIFFBUS(CHIPS)':
 C_PATH='@t6g_mb_lib.t6g(sch_1):page407_i46@pure_quanta.q_cap_diffbus(chips)',
 P_PATH='@t6g_mb_lib.t6g(sch_1):page286_i46@pure_quanta.q_cap_diffbus(chips)',
 PATH='I46',
 DRAWING='@T6G_MB_LIB.T6G(SCH_1):PAGE407',
 PIN_NAMES_ROTATE='TRUE',
 TOLERANCE='20%',
 MATERIAL='X6S',
 PHYS_PAGE='286',
 XY='(-2400,2200)',
 ROT='2',
 VER='2',
 PACK_TYPE='C0201',
 LOCATION='C6533',
 CDS_LIB='pure_quanta',
 CDS_PART_NAME='Q_CAP_DIFFBUS_C0201-DIFF BUS_0.22UF,6.3V,20%,X6S,SA',
 VOLTAGE='6.3V',
 PART_NUMBER='SP_CH4221MEE01',
 VALUE='DIFF BUS_0.22UF',
 PRIM_FILE='./archive_libs/logical/q_cap_diffbus/chips/chips.prt';

PART_NAME
 C6534 'Q_CAP_DIFFBUS_C0201-DIFF BUS_0.22UF,6.3V,20%,X6S,SA':;

SECTION_NUMBER 1
 '@T6G_MB_LIB.T6G(SCH_1):PAGE407_I47@PURE_QUANTA.Q_CAP_DIFFBUS(CHIPS)':
 C_PATH='@t6g_mb_lib.t6g(sch_1):page407_i47@pure_quanta.q_cap_diffbus(chips)',
 P_PATH='@t6g_mb_lib.t6g(sch_1):page286_i47@pure_quanta.q_cap_diffbus(chips)',
 PATH='I47',
 DRAWING='@T6G_MB_LIB.T6G(SCH_1):PAGE407',
 PIN_NAMES_ROTATE='TRUE',
 TOLERANCE='20%',
 MATERIAL='X6S',
 PHYS_PAGE='286',
 XY='(-2400,2150)',
 ROT='2',
 VER='2',
 PACK_TYPE='C0201',
 LOCATION='C6534',
 CDS_LIB='pure_quanta',
 CDS_PART_NAME='Q_CAP_DIFFBUS_C0201-DIFF BUS_0.22UF,6.3V,20%,X6S,SA',
 VOLTAGE='6.3V',
 PART_NUMBER='SP_CH4221MEE01',
 VALUE='DIFF BUS_0.22UF',
 PRIM_FILE='./archive_libs/logical/q_cap_diffbus/chips/chips.prt';

PART_NAME
 C6535 'Q_CAP_DIFFBUS_C0201-DIFF BUS_0.22UF,6.3V,20%,X6S,SA':;

SECTION_NUMBER 1
 '@T6G_MB_LIB.T6G(SCH_1):PAGE407_I45@PURE_QUANTA.Q_CAP_DIFFBUS(CHIPS)':
 C_PATH='@t6g_mb_lib.t6g(sch_1):page407_i45@pure_quanta.q_cap_diffbus(chips)',
 P_PATH='@t6g_mb_lib.t6g(sch_1):page286_i45@pure_quanta.q_cap_diffbus(chips)',
 PATH='I45',
 DRAWING='@T6G_MB_LIB.T6G(SCH_1):PAGE407',
 PIN_NAMES_ROTATE='TRUE',
 TOLERANCE='20%',
 MATERIAL='X6S',
 PHYS_PAGE='286',
 XY='(-2400,2000)',
 ROT='2',
 VER='2',
 PACK_TYPE='C0201',
 LOCATION='C6535',
 CDS_LIB='pure_quanta',
 CDS_PART_NAME='Q_CAP_DIFFBUS_C0201-DIFF BUS_0.22UF,6.3V,20%,X6S,SA',
 VOLTAGE='6.3V',
 PART_NUMBER='SP_CH4221MEE01',
 VALUE='DIFF BUS_0.22UF',
 PRIM_FILE='./archive_libs/logical/q_cap_diffbus/chips/chips.prt';

PART_NAME
 C6536 'Q_CAP_DIFFBUS_C0201-DIFF BUS_0.22UF,6.3V,20%,X6S,SA':;

SECTION_NUMBER 1
 '@T6G_MB_LIB.T6G(SCH_1):PAGE407_I44@PURE_QUANTA.Q_CAP_DIFFBUS(CHIPS)':
 C_PATH='@t6g_mb_lib.t6g(sch_1):page407_i44@pure_quanta.q_cap_diffbus(chips)',
 P_PATH='@t6g_mb_lib.t6g(sch_1):page286_i44@pure_quanta.q_cap_diffbus(chips)',
 PATH='I44',
 DRAWING='@T6G_MB_LIB.T6G(SCH_1):PAGE407',
 PIN_NAMES_ROTATE='TRUE',
 TOLERANCE='20%',
 MATERIAL='X6S',
 PHYS_PAGE='286',
 XY='(-2400,1950)',
 ROT='2',
 VER='2',
 PACK_TYPE='C0201',
 LOCATION='C6536',
 CDS_LIB='pure_quanta',
 CDS_PART_NAME='Q_CAP_DIFFBUS_C0201-DIFF BUS_0.22UF,6.3V,20%,X6S,SA',
 VOLTAGE='6.3V',
 PART_NUMBER='SP_CH4221MEE01',
 VALUE='DIFF BUS_0.22UF',
 PRIM_FILE='./archive_libs/logical/q_cap_diffbus/chips/chips.prt';

PART_NAME
 C6537 'Q_CAP_DIFFBUS_C0201-DIFF BUS_0.22UF,6.3V,20%,X6S,SA':;

SECTION_NUMBER 1
 '@T6G_MB_LIB.T6G(SCH_1):PAGE407_I27@PURE_QUANTA.Q_CAP_DIFFBUS(CHIPS)':
 C_PATH='@t6g_mb_lib.t6g(sch_1):page407_i27@pure_quanta.q_cap_diffbus(chips)',
 P_PATH='@t6g_mb_lib.t6g(sch_1):page286_i27@pure_quanta.q_cap_diffbus(chips)',
 PATH='I27',
 DRAWING='@T6G_MB_LIB.T6G(SCH_1):PAGE407',
 PIN_NAMES_ROTATE='TRUE',
 TOLERANCE='20%',
 MATERIAL='X6S',
 PHYS_PAGE='286',
 XY='(-2400,1800)',
 ROT='2',
 VER='2',
 PACK_TYPE='C0201',
 LOCATION='C6537',
 CDS_LIB='pure_quanta',
 CDS_PART_NAME='Q_CAP_DIFFBUS_C0201-DIFF BUS_0.22UF,6.3V,20%,X6S,SA',
 VOLTAGE='6.3V',
 PART_NUMBER='SP_CH4221MEE01',
 VALUE='DIFF BUS_0.22UF',
 PRIM_FILE='./archive_libs/logical/q_cap_diffbus/chips/chips.prt';

PART_NAME
 C6538 'Q_CAP_DIFFBUS_C0201-DIFF BUS_0.22UF,6.3V,20%,X6S,SA':;

SECTION_NUMBER 1
 '@T6G_MB_LIB.T6G(SCH_1):PAGE407_I26@PURE_QUANTA.Q_CAP_DIFFBUS(CHIPS)':
 C_PATH='@t6g_mb_lib.t6g(sch_1):page407_i26@pure_quanta.q_cap_diffbus(chips)',
 P_PATH='@t6g_mb_lib.t6g(sch_1):page286_i26@pure_quanta.q_cap_diffbus(chips)',
 PATH='I26',
 DRAWING='@T6G_MB_LIB.T6G(SCH_1):PAGE407',
 PIN_NAMES_ROTATE='TRUE',
 TOLERANCE='20%',
 MATERIAL='X6S',
 PHYS_PAGE='286',
 XY='(-2400,1750)',
 ROT='2',
 VER='2',
 PACK_TYPE='C0201',
 LOCATION='C6538',
 CDS_LIB='pure_quanta',
 CDS_PART_NAME='Q_CAP_DIFFBUS_C0201-DIFF BUS_0.22UF,6.3V,20%,X6S,SA',
 VOLTAGE='6.3V',
 PART_NUMBER='SP_CH4221MEE01',
 VALUE='DIFF BUS_0.22UF',
 PRIM_FILE='./archive_libs/logical/q_cap_diffbus/chips/chips.prt';

PART_NAME
 C6539 'Q_CAP_DIFFBUS_C0201-DIFF BUS_0.22UF,6.3V,20%,X6S,SA':;

SECTION_NUMBER 1
 '@T6G_MB_LIB.T6G(SCH_1):PAGE407_I25@PURE_QUANTA.Q_CAP_DIFFBUS(CHIPS)':
 C_PATH='@t6g_mb_lib.t6g(sch_1):page407_i25@pure_quanta.q_cap_diffbus(chips)',
 P_PATH='@t6g_mb_lib.t6g(sch_1):page286_i25@pure_quanta.q_cap_diffbus(chips)',
 PATH='I25',
 DRAWING='@T6G_MB_LIB.T6G(SCH_1):PAGE407',
 PIN_NAMES_ROTATE='TRUE',
 TOLERANCE='20%',
 MATERIAL='X6S',
 PHYS_PAGE='286',
 XY='(-2400,1600)',
 ROT='2',
 VER='2',
 PACK_TYPE='C0201',
 LOCATION='C6539',
 CDS_LIB='pure_quanta',
 CDS_PART_NAME='Q_CAP_DIFFBUS_C0201-DIFF BUS_0.22UF,6.3V,20%,X6S,SA',
 VOLTAGE='6.3V',
 PART_NUMBER='SP_CH4221MEE01',
 VALUE='DIFF BUS_0.22UF',
 PRIM_FILE='./archive_libs/logical/q_cap_diffbus/chips/chips.prt';

PART_NAME
 C6540 'Q_CAP_DIFFBUS_C0201-DIFF BUS_0.22UF,6.3V,20%,X6S,SA':;

SECTION_NUMBER 1
 '@T6G_MB_LIB.T6G(SCH_1):PAGE407_I24@PURE_QUANTA.Q_CAP_DIFFBUS(CHIPS)':
 C_PATH='@t6g_mb_lib.t6g(sch_1):page407_i24@pure_quanta.q_cap_diffbus(chips)',
 P_PATH='@t6g_mb_lib.t6g(sch_1):page286_i24@pure_quanta.q_cap_diffbus(chips)',
 PATH='I24',
 DRAWING='@T6G_MB_LIB.T6G(SCH_1):PAGE407',
 PIN_NAMES_ROTATE='TRUE',
 TOLERANCE='20%',
 MATERIAL='X6S',
 PHYS_PAGE='286',
 XY='(-2400,1550)',
 ROT='2',
 VER='2',
 PACK_TYPE='C0201',
 LOCATION='C6540',
 CDS_LIB='pure_quanta',
 CDS_PART_NAME='Q_CAP_DIFFBUS_C0201-DIFF BUS_0.22UF,6.3V,20%,X6S,SA',
 VOLTAGE='6.3V',
 PART_NUMBER='SP_CH4221MEE01',
 VALUE='DIFF BUS_0.22UF',
 PRIM_FILE='./archive_libs/logical/q_cap_diffbus/chips/chips.prt';

PART_NAME
 C6541 'Q_CAP_DIFFBUS_C0201-DIFF BUS_0.22UF,6.3V,20%,X6S,SA':;

SECTION_NUMBER 1
 '@T6G_MB_LIB.T6G(SCH_1):PAGE407_I22@PURE_QUANTA.Q_CAP_DIFFBUS(CHIPS)':
 C_PATH='@t6g_mb_lib.t6g(sch_1):page407_i22@pure_quanta.q_cap_diffbus(chips)',
 P_PATH='@t6g_mb_lib.t6g(sch_1):page286_i22@pure_quanta.q_cap_diffbus(chips)',
 PATH='I22',
 DRAWING='@T6G_MB_LIB.T6G(SCH_1):PAGE407',
 PIN_NAMES_ROTATE='TRUE',
 TOLERANCE='20%',
 MATERIAL='X6S',
 PHYS_PAGE='286',
 XY='(-2400,1400)',
 ROT='2',
 VER='2',
 PACK_TYPE='C0201',
 LOCATION='C6541',
 CDS_LIB='pure_quanta',
 CDS_PART_NAME='Q_CAP_DIFFBUS_C0201-DIFF BUS_0.22UF,6.3V,20%,X6S,SA',
 VOLTAGE='6.3V',
 PART_NUMBER='SP_CH4221MEE01',
 VALUE='DIFF BUS_0.22UF',
 PRIM_FILE='./archive_libs/logical/q_cap_diffbus/chips/chips.prt';

PART_NAME
 C6542 'Q_CAP_DIFFBUS_C0201-DIFF BUS_0.22UF,6.3V,20%,X6S,SA':;

SECTION_NUMBER 1
 '@T6G_MB_LIB.T6G(SCH_1):PAGE407_I23@PURE_QUANTA.Q_CAP_DIFFBUS(CHIPS)':
 C_PATH='@t6g_mb_lib.t6g(sch_1):page407_i23@pure_quanta.q_cap_diffbus(chips)',
 P_PATH='@t6g_mb_lib.t6g(sch_1):page286_i23@pure_quanta.q_cap_diffbus(chips)',
 PATH='I23',
 DRAWING='@T6G_MB_LIB.T6G(SCH_1):PAGE407',
 PIN_NAMES_ROTATE='TRUE',
 TOLERANCE='20%',
 MATERIAL='X6S',
 PHYS_PAGE='286',
 XY='(-2400,1350)',
 ROT='2',
 VER='2',
 PACK_TYPE='C0201',
 LOCATION='C6542',
 CDS_LIB='pure_quanta',
 CDS_PART_NAME='Q_CAP_DIFFBUS_C0201-DIFF BUS_0.22UF,6.3V,20%,X6S,SA',
 VOLTAGE='6.3V',
 PART_NUMBER='SP_CH4221MEE01',
 VALUE='DIFF BUS_0.22UF',
 PRIM_FILE='./archive_libs/logical/q_cap_diffbus/chips/chips.prt';

PART_NAME
 C6543 'Q_CAP_DIFFBUS_C0201-DIFF BUS_0.22UF,6.3V,20%,X6S,SA':;

SECTION_NUMBER 1
 '@T6G_MB_LIB.T6G(SCH_1):PAGE407_I20@PURE_QUANTA.Q_CAP_DIFFBUS(CHIPS)':
 C_PATH='@t6g_mb_lib.t6g(sch_1):page407_i20@pure_quanta.q_cap_diffbus(chips)',
 P_PATH='@t6g_mb_lib.t6g(sch_1):page286_i20@pure_quanta.q_cap_diffbus(chips)',
 PATH='I20',
 DRAWING='@T6G_MB_LIB.T6G(SCH_1):PAGE407',
 PIN_NAMES_ROTATE='TRUE',
 TOLERANCE='20%',
 MATERIAL='X6S',
 PHYS_PAGE='286',
 XY='(-2400,1200)',
 ROT='2',
 VER='2',
 PACK_TYPE='C0201',
 LOCATION='C6543',
 CDS_LIB='pure_quanta',
 CDS_PART_NAME='Q_CAP_DIFFBUS_C0201-DIFF BUS_0.22UF,6.3V,20%,X6S,SA',
 VOLTAGE='6.3V',
 PART_NUMBER='SP_CH4221MEE01',
 VALUE='DIFF BUS_0.22UF',
 PRIM_FILE='./archive_libs/logical/q_cap_diffbus/chips/chips.prt';

PART_NAME
 C6544 'Q_CAP_DIFFBUS_C0201-DIFF BUS_0.22UF,6.3V,20%,X6S,SA':;

SECTION_NUMBER 1
 '@T6G_MB_LIB.T6G(SCH_1):PAGE407_I21@PURE_QUANTA.Q_CAP_DIFFBUS(CHIPS)':
 C_PATH='@t6g_mb_lib.t6g(sch_1):page407_i21@pure_quanta.q_cap_diffbus(chips)',
 P_PATH='@t6g_mb_lib.t6g(sch_1):page286_i21@pure_quanta.q_cap_diffbus(chips)',
 PATH='I21',
 DRAWING='@T6G_MB_LIB.T6G(SCH_1):PAGE407',
 PIN_NAMES_ROTATE='TRUE',
 TOLERANCE='20%',
 MATERIAL='X6S',
 PHYS_PAGE='286',
 XY='(-2400,1150)',
 ROT='2',
 VER='2',
 PACK_TYPE='C0201',
 LOCATION='C6544',
 CDS_LIB='pure_quanta',
 CDS_PART_NAME='Q_CAP_DIFFBUS_C0201-DIFF BUS_0.22UF,6.3V,20%,X6S,SA',
 VOLTAGE='6.3V',
 PART_NUMBER='SP_CH4221MEE01',
 VALUE='DIFF BUS_0.22UF',
 PRIM_FILE='./archive_libs/logical/q_cap_diffbus/chips/chips.prt';

PART_NAME
 C6545 'Q_CAP_DIFFBUS_C0201-DIFF BUS_0.22UF,6.3V,20%,X6S,SA':;

SECTION_NUMBER 1
 '@T6G_MB_LIB.T6G(SCH_1):PAGE407_I18@PURE_QUANTA.Q_CAP_DIFFBUS(CHIPS)':
 C_PATH='@t6g_mb_lib.t6g(sch_1):page407_i18@pure_quanta.q_cap_diffbus(chips)',
 P_PATH='@t6g_mb_lib.t6g(sch_1):page286_i18@pure_quanta.q_cap_diffbus(chips)',
 PATH='I18',
 DRAWING='@T6G_MB_LIB.T6G(SCH_1):PAGE407',
 PIN_NAMES_ROTATE='TRUE',
 TOLERANCE='20%',
 MATERIAL='X6S',
 PHYS_PAGE='286',
 XY='(-2400,1000)',
 ROT='2',
 VER='2',
 PACK_TYPE='C0201',
 LOCATION='C6545',
 CDS_LIB='pure_quanta',
 CDS_PART_NAME='Q_CAP_DIFFBUS_C0201-DIFF BUS_0.22UF,6.3V,20%,X6S,SA',
 VOLTAGE='6.3V',
 PART_NUMBER='SP_CH4221MEE01',
 VALUE='DIFF BUS_0.22UF',
 PRIM_FILE='./archive_libs/logical/q_cap_diffbus/chips/chips.prt';

PART_NAME
 C6546 'Q_CAP_DIFFBUS_C0201-DIFF BUS_0.22UF,6.3V,20%,X6S,SA':;

SECTION_NUMBER 1
 '@T6G_MB_LIB.T6G(SCH_1):PAGE407_I19@PURE_QUANTA.Q_CAP_DIFFBUS(CHIPS)':
 C_PATH='@t6g_mb_lib.t6g(sch_1):page407_i19@pure_quanta.q_cap_diffbus(chips)',
 P_PATH='@t6g_mb_lib.t6g(sch_1):page286_i19@pure_quanta.q_cap_diffbus(chips)',
 PATH='I19',
 DRAWING='@T6G_MB_LIB.T6G(SCH_1):PAGE407',
 PIN_NAMES_ROTATE='TRUE',
 TOLERANCE='20%',
 MATERIAL='X6S',
 PHYS_PAGE='286',
 XY='(-2400,950)',
 ROT='2',
 VER='2',
 PACK_TYPE='C0201',
 LOCATION='C6546',
 CDS_LIB='pure_quanta',
 CDS_PART_NAME='Q_CAP_DIFFBUS_C0201-DIFF BUS_0.22UF,6.3V,20%,X6S,SA',
 VOLTAGE='6.3V',
 PART_NUMBER='SP_CH4221MEE01',
 VALUE='DIFF BUS_0.22UF',
 PRIM_FILE='./archive_libs/logical/q_cap_diffbus/chips/chips.prt';

PART_NAME
 C6547 'Q_CAP_DIFFBUS_C0201-DIFF BUS_0.22UF,6.3V,20%,X6S,SA':;

SECTION_NUMBER 1
 '@T6G_MB_LIB.T6G(SCH_1):PAGE407_I16@PURE_QUANTA.Q_CAP_DIFFBUS(CHIPS)':
 C_PATH='@t6g_mb_lib.t6g(sch_1):page407_i16@pure_quanta.q_cap_diffbus(chips)',
 P_PATH='@t6g_mb_lib.t6g(sch_1):page286_i16@pure_quanta.q_cap_diffbus(chips)',
 PATH='I16',
 DRAWING='@T6G_MB_LIB.T6G(SCH_1):PAGE407',
 PIN_NAMES_ROTATE='TRUE',
 TOLERANCE='20%',
 MATERIAL='X6S',
 PHYS_PAGE='286',
 XY='(-2400,800)',
 ROT='2',
 VER='2',
 PACK_TYPE='C0201',
 LOCATION='C6547',
 CDS_LIB='pure_quanta',
 CDS_PART_NAME='Q_CAP_DIFFBUS_C0201-DIFF BUS_0.22UF,6.3V,20%,X6S,SA',
 VOLTAGE='6.3V',
 PART_NUMBER='SP_CH4221MEE01',
 VALUE='DIFF BUS_0.22UF',
 PRIM_FILE='./archive_libs/logical/q_cap_diffbus/chips/chips.prt';

PART_NAME
 C6548 'Q_CAP_DIFFBUS_C0201-DIFF BUS_0.22UF,6.3V,20%,X6S,SA':;

SECTION_NUMBER 1
 '@T6G_MB_LIB.T6G(SCH_1):PAGE407_I15@PURE_QUANTA.Q_CAP_DIFFBUS(CHIPS)':
 C_PATH='@t6g_mb_lib.t6g(sch_1):page407_i15@pure_quanta.q_cap_diffbus(chips)',
 P_PATH='@t6g_mb_lib.t6g(sch_1):page286_i15@pure_quanta.q_cap_diffbus(chips)',
 PATH='I15',
 DRAWING='@T6G_MB_LIB.T6G(SCH_1):PAGE407',
 PIN_NAMES_ROTATE='TRUE',
 TOLERANCE='20%',
 MATERIAL='X6S',
 PHYS_PAGE='286',
 XY='(-2400,750)',
 ROT='2',
 VER='2',
 PACK_TYPE='C0201',
 LOCATION='C6548',
 CDS_LIB='pure_quanta',
 CDS_PART_NAME='Q_CAP_DIFFBUS_C0201-DIFF BUS_0.22UF,6.3V,20%,X6S,SA',
 VOLTAGE='6.3V',
 PART_NUMBER='SP_CH4221MEE01',
 VALUE='DIFF BUS_0.22UF',
 PRIM_FILE='./archive_libs/logical/q_cap_diffbus/chips/chips.prt';

PART_NAME
 C6549 'Q_CAP_DIFFBUS_C0201-DIFF BUS_0.22UF,6.3V,20%,X6S,SA':;

SECTION_NUMBER 1
 '@T6G_MB_LIB.T6G(SCH_1):PAGE407_I105@PURE_QUANTA.Q_CAP_DIFFBUS(CHIPS)':
 C_PATH='@t6g_mb_lib.t6g(sch_1):page407_i105@pure_quanta.q_cap_diffbus(chips)',
 P_PATH='@t6g_mb_lib.t6g(sch_1):page286_i105@pure_quanta.q_cap_diffbus(chips)',
 PATH='I105',
 DRAWING='@T6G_MB_LIB.T6G(SCH_1):PAGE407',
 PIN_NAMES_ROTATE='TRUE',
 TOLERANCE='20%',
 MATERIAL='X6S',
 PHYS_PAGE='286',
 XY='(-6925,2200)',
 ROT='2',
 VER='2',
 PACK_TYPE='C0201',
 LOCATION='C6549',
 CDS_LIB='pure_quanta',
 CDS_PART_NAME='Q_CAP_DIFFBUS_C0201-DIFF BUS_0.22UF,6.3V,20%,X6S,SA',
 VOLTAGE='6.3V',
 PART_NUMBER='SP_CH4221MEE01',
 VALUE='DIFF BUS_0.22UF',
 PRIM_FILE='./archive_libs/logical/q_cap_diffbus/chips/chips.prt';

PART_NAME
 C6550 'Q_CAP_DIFFBUS_C0201-DIFF BUS_0.22UF,6.3V,20%,X6S,SA':;

SECTION_NUMBER 1
 '@T6G_MB_LIB.T6G(SCH_1):PAGE407_I104@PURE_QUANTA.Q_CAP_DIFFBUS(CHIPS)':
 C_PATH='@t6g_mb_lib.t6g(sch_1):page407_i104@pure_quanta.q_cap_diffbus(chips)',
 P_PATH='@t6g_mb_lib.t6g(sch_1):page286_i104@pure_quanta.q_cap_diffbus(chips)',
 PATH='I104',
 DRAWING='@T6G_MB_LIB.T6G(SCH_1):PAGE407',
 PIN_NAMES_ROTATE='TRUE',
 TOLERANCE='20%',
 MATERIAL='X6S',
 PHYS_PAGE='286',
 XY='(-6925,2150)',
 ROT='2',
 VER='2',
 PACK_TYPE='C0201',
 LOCATION='C6550',
 CDS_LIB='pure_quanta',
 CDS_PART_NAME='Q_CAP_DIFFBUS_C0201-DIFF BUS_0.22UF,6.3V,20%,X6S,SA',
 VOLTAGE='6.3V',
 PART_NUMBER='SP_CH4221MEE01',
 VALUE='DIFF BUS_0.22UF',
 PRIM_FILE='./archive_libs/logical/q_cap_diffbus/chips/chips.prt';

PART_NAME
 C6551 'Q_CAP_DIFFBUS_C0201-DIFF BUS_0.22UF,6.3V,20%,X6S,SA':;

SECTION_NUMBER 1
 '@T6G_MB_LIB.T6G(SCH_1):PAGE407_I102@PURE_QUANTA.Q_CAP_DIFFBUS(CHIPS)':
 C_PATH='@t6g_mb_lib.t6g(sch_1):page407_i102@pure_quanta.q_cap_diffbus(chips)',
 P_PATH='@t6g_mb_lib.t6g(sch_1):page286_i102@pure_quanta.q_cap_diffbus(chips)',
 PATH='I102',
 DRAWING='@T6G_MB_LIB.T6G(SCH_1):PAGE407',
 PIN_NAMES_ROTATE='TRUE',
 TOLERANCE='20%',
 MATERIAL='X6S',
 PHYS_PAGE='286',
 XY='(-6925,2000)',
 ROT='2',
 VER='2',
 PACK_TYPE='C0201',
 LOCATION='C6551',
 CDS_LIB='pure_quanta',
 CDS_PART_NAME='Q_CAP_DIFFBUS_C0201-DIFF BUS_0.22UF,6.3V,20%,X6S,SA',
 VOLTAGE='6.3V',
 PART_NUMBER='SP_CH4221MEE01',
 VALUE='DIFF BUS_0.22UF',
 PRIM_FILE='./archive_libs/logical/q_cap_diffbus/chips/chips.prt';

PART_NAME
 C6552 'Q_CAP_DIFFBUS_C0201-DIFF BUS_0.22UF,6.3V,20%,X6S,SA':;

SECTION_NUMBER 1
 '@T6G_MB_LIB.T6G(SCH_1):PAGE407_I103@PURE_QUANTA.Q_CAP_DIFFBUS(CHIPS)':
 C_PATH='@t6g_mb_lib.t6g(sch_1):page407_i103@pure_quanta.q_cap_diffbus(chips)',
 P_PATH='@t6g_mb_lib.t6g(sch_1):page286_i103@pure_quanta.q_cap_diffbus(chips)',
 PATH='I103',
 DRAWING='@T6G_MB_LIB.T6G(SCH_1):PAGE407',
 PIN_NAMES_ROTATE='TRUE',
 TOLERANCE='20%',
 MATERIAL='X6S',
 PHYS_PAGE='286',
 XY='(-6925,1950)',
 ROT='2',
 VER='2',
 PACK_TYPE='C0201',
 LOCATION='C6552',
 CDS_LIB='pure_quanta',
 CDS_PART_NAME='Q_CAP_DIFFBUS_C0201-DIFF BUS_0.22UF,6.3V,20%,X6S,SA',
 VOLTAGE='6.3V',
 PART_NUMBER='SP_CH4221MEE01',
 VALUE='DIFF BUS_0.22UF',
 PRIM_FILE='./archive_libs/logical/q_cap_diffbus/chips/chips.prt';

PART_NAME
 C6553 'Q_CAP_DIFFBUS_C0201-DIFF BUS_0.22UF,6.3V,20%,X6S,SA':;

SECTION_NUMBER 1
 '@T6G_MB_LIB.T6G(SCH_1):PAGE407_I96@PURE_QUANTA.Q_CAP_DIFFBUS(CHIPS)':
 C_PATH='@t6g_mb_lib.t6g(sch_1):page407_i96@pure_quanta.q_cap_diffbus(chips)',
 P_PATH='@t6g_mb_lib.t6g(sch_1):page286_i96@pure_quanta.q_cap_diffbus(chips)',
 PATH='I96',
 DRAWING='@T6G_MB_LIB.T6G(SCH_1):PAGE407',
 PIN_NAMES_ROTATE='TRUE',
 TOLERANCE='20%',
 MATERIAL='X6S',
 PHYS_PAGE='286',
 XY='(-6925,1800)',
 ROT='2',
 VER='2',
 PACK_TYPE='C0201',
 LOCATION='C6553',
 CDS_LIB='pure_quanta',
 CDS_PART_NAME='Q_CAP_DIFFBUS_C0201-DIFF BUS_0.22UF,6.3V,20%,X6S,SA',
 VOLTAGE='6.3V',
 PART_NUMBER='SP_CH4221MEE01',
 VALUE='DIFF BUS_0.22UF',
 PRIM_FILE='./archive_libs/logical/q_cap_diffbus/chips/chips.prt';

PART_NAME
 C6554 'Q_CAP_DIFFBUS_C0201-DIFF BUS_0.22UF,6.3V,20%,X6S,SA':;

SECTION_NUMBER 1
 '@T6G_MB_LIB.T6G(SCH_1):PAGE407_I97@PURE_QUANTA.Q_CAP_DIFFBUS(CHIPS)':
 C_PATH='@t6g_mb_lib.t6g(sch_1):page407_i97@pure_quanta.q_cap_diffbus(chips)',
 P_PATH='@t6g_mb_lib.t6g(sch_1):page286_i97@pure_quanta.q_cap_diffbus(chips)',
 PATH='I97',
 DRAWING='@T6G_MB_LIB.T6G(SCH_1):PAGE407',
 PIN_NAMES_ROTATE='TRUE',
 TOLERANCE='20%',
 MATERIAL='X6S',
 PHYS_PAGE='286',
 XY='(-6925,1750)',
 ROT='2',
 VER='2',
 PACK_TYPE='C0201',
 LOCATION='C6554',
 CDS_LIB='pure_quanta',
 CDS_PART_NAME='Q_CAP_DIFFBUS_C0201-DIFF BUS_0.22UF,6.3V,20%,X6S,SA',
 VOLTAGE='6.3V',
 PART_NUMBER='SP_CH4221MEE01',
 VALUE='DIFF BUS_0.22UF',
 PRIM_FILE='./archive_libs/logical/q_cap_diffbus/chips/chips.prt';

PART_NAME
 C6555 'Q_CAP_DIFFBUS_C0201-DIFF BUS_0.22UF,6.3V,20%,X6S,SA':;

SECTION_NUMBER 1
 '@T6G_MB_LIB.T6G(SCH_1):PAGE407_I95@PURE_QUANTA.Q_CAP_DIFFBUS(CHIPS)':
 C_PATH='@t6g_mb_lib.t6g(sch_1):page407_i95@pure_quanta.q_cap_diffbus(chips)',
 P_PATH='@t6g_mb_lib.t6g(sch_1):page286_i95@pure_quanta.q_cap_diffbus(chips)',
 PATH='I95',
 DRAWING='@T6G_MB_LIB.T6G(SCH_1):PAGE407',
 PIN_NAMES_ROTATE='TRUE',
 TOLERANCE='20%',
 MATERIAL='X6S',
 PHYS_PAGE='286',
 XY='(-6925,1600)',
 ROT='2',
 VER='2',
 PACK_TYPE='C0201',
 LOCATION='C6555',
 CDS_LIB='pure_quanta',
 CDS_PART_NAME='Q_CAP_DIFFBUS_C0201-DIFF BUS_0.22UF,6.3V,20%,X6S,SA',
 VOLTAGE='6.3V',
 PART_NUMBER='SP_CH4221MEE01',
 VALUE='DIFF BUS_0.22UF',
 PRIM_FILE='./archive_libs/logical/q_cap_diffbus/chips/chips.prt';

PART_NAME
 C6556 'Q_CAP_DIFFBUS_C0201-DIFF BUS_0.22UF,6.3V,20%,X6S,SA':;

SECTION_NUMBER 1
 '@T6G_MB_LIB.T6G(SCH_1):PAGE407_I94@PURE_QUANTA.Q_CAP_DIFFBUS(CHIPS)':
 C_PATH='@t6g_mb_lib.t6g(sch_1):page407_i94@pure_quanta.q_cap_diffbus(chips)',
 P_PATH='@t6g_mb_lib.t6g(sch_1):page286_i94@pure_quanta.q_cap_diffbus(chips)',
 PATH='I94',
 DRAWING='@T6G_MB_LIB.T6G(SCH_1):PAGE407',
 PIN_NAMES_ROTATE='TRUE',
 TOLERANCE='20%',
 MATERIAL='X6S',
 PHYS_PAGE='286',
 XY='(-6925,1550)',
 ROT='2',
 VER='2',
 PACK_TYPE='C0201',
 LOCATION='C6556',
 CDS_LIB='pure_quanta',
 CDS_PART_NAME='Q_CAP_DIFFBUS_C0201-DIFF BUS_0.22UF,6.3V,20%,X6S,SA',
 VOLTAGE='6.3V',
 PART_NUMBER='SP_CH4221MEE01',
 VALUE='DIFF BUS_0.22UF',
 PRIM_FILE='./archive_libs/logical/q_cap_diffbus/chips/chips.prt';

PART_NAME
 C6557 'Q_CAP_DIFFBUS_C0201-DIFF BUS_0.22UF,6.3V,20%,X6S,SA':;

SECTION_NUMBER 1
 '@T6G_MB_LIB.T6G(SCH_1):PAGE407_I93@PURE_QUANTA.Q_CAP_DIFFBUS(CHIPS)':
 C_PATH='@t6g_mb_lib.t6g(sch_1):page407_i93@pure_quanta.q_cap_diffbus(chips)',
 P_PATH='@t6g_mb_lib.t6g(sch_1):page286_i93@pure_quanta.q_cap_diffbus(chips)',
 PATH='I93',
 DRAWING='@T6G_MB_LIB.T6G(SCH_1):PAGE407',
 PIN_NAMES_ROTATE='TRUE',
 TOLERANCE='20%',
 MATERIAL='X6S',
 PHYS_PAGE='286',
 XY='(-6925,1400)',
 ROT='2',
 VER='2',
 PACK_TYPE='C0201',
 LOCATION='C6557',
 CDS_LIB='pure_quanta',
 CDS_PART_NAME='Q_CAP_DIFFBUS_C0201-DIFF BUS_0.22UF,6.3V,20%,X6S,SA',
 VOLTAGE='6.3V',
 PART_NUMBER='SP_CH4221MEE01',
 VALUE='DIFF BUS_0.22UF',
 PRIM_FILE='./archive_libs/logical/q_cap_diffbus/chips/chips.prt';

PART_NAME
 C6558 'Q_CAP_DIFFBUS_C0201-DIFF BUS_0.22UF,6.3V,20%,X6S,SA':;

SECTION_NUMBER 1
 '@T6G_MB_LIB.T6G(SCH_1):PAGE407_I92@PURE_QUANTA.Q_CAP_DIFFBUS(CHIPS)':
 C_PATH='@t6g_mb_lib.t6g(sch_1):page407_i92@pure_quanta.q_cap_diffbus(chips)',
 P_PATH='@t6g_mb_lib.t6g(sch_1):page286_i92@pure_quanta.q_cap_diffbus(chips)',
 PATH='I92',
 DRAWING='@T6G_MB_LIB.T6G(SCH_1):PAGE407',
 PIN_NAMES_ROTATE='TRUE',
 TOLERANCE='20%',
 MATERIAL='X6S',
 PHYS_PAGE='286',
 XY='(-6925,1350)',
 ROT='2',
 VER='2',
 PACK_TYPE='C0201',
 LOCATION='C6558',
 CDS_LIB='pure_quanta',
 CDS_PART_NAME='Q_CAP_DIFFBUS_C0201-DIFF BUS_0.22UF,6.3V,20%,X6S,SA',
 VOLTAGE='6.3V',
 PART_NUMBER='SP_CH4221MEE01',
 VALUE='DIFF BUS_0.22UF',
 PRIM_FILE='./archive_libs/logical/q_cap_diffbus/chips/chips.prt';

PART_NAME
 C6559 'Q_CAP_DIFFBUS_C0201-DIFF BUS_0.22UF,6.3V,20%,X6S,SA':;

SECTION_NUMBER 1
 '@T6G_MB_LIB.T6G(SCH_1):PAGE407_I91@PURE_QUANTA.Q_CAP_DIFFBUS(CHIPS)':
 C_PATH='@t6g_mb_lib.t6g(sch_1):page407_i91@pure_quanta.q_cap_diffbus(chips)',
 P_PATH='@t6g_mb_lib.t6g(sch_1):page286_i91@pure_quanta.q_cap_diffbus(chips)',
 PATH='I91',
 DRAWING='@T6G_MB_LIB.T6G(SCH_1):PAGE407',
 PIN_NAMES_ROTATE='TRUE',
 TOLERANCE='20%',
 MATERIAL='X6S',
 PHYS_PAGE='286',
 XY='(-6925,1200)',
 ROT='2',
 VER='2',
 PACK_TYPE='C0201',
 LOCATION='C6559',
 CDS_LIB='pure_quanta',
 CDS_PART_NAME='Q_CAP_DIFFBUS_C0201-DIFF BUS_0.22UF,6.3V,20%,X6S,SA',
 VOLTAGE='6.3V',
 PART_NUMBER='SP_CH4221MEE01',
 VALUE='DIFF BUS_0.22UF',
 PRIM_FILE='./archive_libs/logical/q_cap_diffbus/chips/chips.prt';

PART_NAME
 C6560 'Q_CAP_DIFFBUS_C0201-DIFF BUS_0.22UF,6.3V,20%,X6S,SA':;

SECTION_NUMBER 1
 '@T6G_MB_LIB.T6G(SCH_1):PAGE407_I90@PURE_QUANTA.Q_CAP_DIFFBUS(CHIPS)':
 C_PATH='@t6g_mb_lib.t6g(sch_1):page407_i90@pure_quanta.q_cap_diffbus(chips)',
 P_PATH='@t6g_mb_lib.t6g(sch_1):page286_i90@pure_quanta.q_cap_diffbus(chips)',
 PATH='I90',
 DRAWING='@T6G_MB_LIB.T6G(SCH_1):PAGE407',
 PIN_NAMES_ROTATE='TRUE',
 TOLERANCE='20%',
 MATERIAL='X6S',
 PHYS_PAGE='286',
 XY='(-6925,1150)',
 ROT='2',
 VER='2',
 PACK_TYPE='C0201',
 LOCATION='C6560',
 CDS_LIB='pure_quanta',
 CDS_PART_NAME='Q_CAP_DIFFBUS_C0201-DIFF BUS_0.22UF,6.3V,20%,X6S,SA',
 VOLTAGE='6.3V',
 PART_NUMBER='SP_CH4221MEE01',
 VALUE='DIFF BUS_0.22UF',
 PRIM_FILE='./archive_libs/logical/q_cap_diffbus/chips/chips.prt';

PART_NAME
 C6561 'Q_CAP_DIFFBUS_C0201-DIFF BUS_0.22UF,6.3V,20%,X6S,SA':;

SECTION_NUMBER 1
 '@T6G_MB_LIB.T6G(SCH_1):PAGE407_I89@PURE_QUANTA.Q_CAP_DIFFBUS(CHIPS)':
 C_PATH='@t6g_mb_lib.t6g(sch_1):page407_i89@pure_quanta.q_cap_diffbus(chips)',
 P_PATH='@t6g_mb_lib.t6g(sch_1):page286_i89@pure_quanta.q_cap_diffbus(chips)',
 PATH='I89',
 DRAWING='@T6G_MB_LIB.T6G(SCH_1):PAGE407',
 PIN_NAMES_ROTATE='TRUE',
 TOLERANCE='20%',
 MATERIAL='X6S',
 PHYS_PAGE='286',
 XY='(-6925,1000)',
 ROT='2',
 VER='2',
 PACK_TYPE='C0201',
 LOCATION='C6561',
 CDS_LIB='pure_quanta',
 CDS_PART_NAME='Q_CAP_DIFFBUS_C0201-DIFF BUS_0.22UF,6.3V,20%,X6S,SA',
 VOLTAGE='6.3V',
 PART_NUMBER='SP_CH4221MEE01',
 VALUE='DIFF BUS_0.22UF',
 PRIM_FILE='./archive_libs/logical/q_cap_diffbus/chips/chips.prt';

PART_NAME
 C6562 'Q_CAP_DIFFBUS_C0201-DIFF BUS_0.22UF,6.3V,20%,X6S,SA':;

SECTION_NUMBER 1
 '@T6G_MB_LIB.T6G(SCH_1):PAGE407_I88@PURE_QUANTA.Q_CAP_DIFFBUS(CHIPS)':
 C_PATH='@t6g_mb_lib.t6g(sch_1):page407_i88@pure_quanta.q_cap_diffbus(chips)',
 P_PATH='@t6g_mb_lib.t6g(sch_1):page286_i88@pure_quanta.q_cap_diffbus(chips)',
 PATH='I88',
 DRAWING='@T6G_MB_LIB.T6G(SCH_1):PAGE407',
 PIN_NAMES_ROTATE='TRUE',
 TOLERANCE='20%',
 MATERIAL='X6S',
 PHYS_PAGE='286',
 XY='(-6925,950)',
 ROT='2',
 VER='2',
 PACK_TYPE='C0201',
 LOCATION='C6562',
 CDS_LIB='pure_quanta',
 CDS_PART_NAME='Q_CAP_DIFFBUS_C0201-DIFF BUS_0.22UF,6.3V,20%,X6S,SA',
 VOLTAGE='6.3V',
 PART_NUMBER='SP_CH4221MEE01',
 VALUE='DIFF BUS_0.22UF',
 PRIM_FILE='./archive_libs/logical/q_cap_diffbus/chips/chips.prt';

PART_NAME
 C6563 'Q_CAP_DIFFBUS_C0201-DIFF BUS_0.22UF,6.3V,20%,X6S,SA':;

SECTION_NUMBER 1
 '@T6G_MB_LIB.T6G(SCH_1):PAGE407_I87@PURE_QUANTA.Q_CAP_DIFFBUS(CHIPS)':
 C_PATH='@t6g_mb_lib.t6g(sch_1):page407_i87@pure_quanta.q_cap_diffbus(chips)',
 P_PATH='@t6g_mb_lib.t6g(sch_1):page286_i87@pure_quanta.q_cap_diffbus(chips)',
 PATH='I87',
 DRAWING='@T6G_MB_LIB.T6G(SCH_1):PAGE407',
 PIN_NAMES_ROTATE='TRUE',
 TOLERANCE='20%',
 MATERIAL='X6S',
 PHYS_PAGE='286',
 XY='(-6925,800)',
 ROT='2',
 VER='2',
 PACK_TYPE='C0201',
 LOCATION='C6563',
 CDS_LIB='pure_quanta',
 CDS_PART_NAME='Q_CAP_DIFFBUS_C0201-DIFF BUS_0.22UF,6.3V,20%,X6S,SA',
 VOLTAGE='6.3V',
 PART_NUMBER='SP_CH4221MEE01',
 VALUE='DIFF BUS_0.22UF',
 PRIM_FILE='./archive_libs/logical/q_cap_diffbus/chips/chips.prt';

PART_NAME
 C6564 'Q_CAP_DIFFBUS_C0201-DIFF BUS_0.22UF,6.3V,20%,X6S,SA':;

SECTION_NUMBER 1
 '@T6G_MB_LIB.T6G(SCH_1):PAGE407_I86@PURE_QUANTA.Q_CAP_DIFFBUS(CHIPS)':
 C_PATH='@t6g_mb_lib.t6g(sch_1):page407_i86@pure_quanta.q_cap_diffbus(chips)',
 P_PATH='@t6g_mb_lib.t6g(sch_1):page286_i86@pure_quanta.q_cap_diffbus(chips)',
 PATH='I86',
 DRAWING='@T6G_MB_LIB.T6G(SCH_1):PAGE407',
 PIN_NAMES_ROTATE='TRUE',
 TOLERANCE='20%',
 MATERIAL='X6S',
 PHYS_PAGE='286',
 XY='(-6925,750)',
 ROT='2',
 VER='2',
 PACK_TYPE='C0201',
 LOCATION='C6564',
 CDS_LIB='pure_quanta',
 CDS_PART_NAME='Q_CAP_DIFFBUS_C0201-DIFF BUS_0.22UF,6.3V,20%,X6S,SA',
 VOLTAGE='6.3V',
 PART_NUMBER='SP_CH4221MEE01',
 VALUE='DIFF BUS_0.22UF',
 PRIM_FILE='./archive_libs/logical/q_cap_diffbus/chips/chips.prt';

PART_NAME
 C6565 'Q_CAP_DIFFBUS_C0201-DIFF BUS_0.22UF,6.3V,20%,X6S,SA':;

SECTION_NUMBER 1
 '@T6G_MB_LIB.T6G(SCH_1):PAGE418_I49@PURE_QUANTA.Q_CAP_DIFFBUS(CHIPS)':
 C_PATH='@t6g_mb_lib.t6g(sch_1):page418_i49@pure_quanta.q_cap_diffbus(chips)',
 P_PATH='@t6g_mb_lib.t6g(sch_1):page297_i49@pure_quanta.q_cap_diffbus(chips)',
 PATH='I49',
 DRAWING='@T6G_MB_LIB.T6G(SCH_1):PAGE418',
 PIN_NAMES_ROTATE='TRUE',
 TOLERANCE='20%',
 MATERIAL='X6S',
 PHYS_PAGE='297',
 XY='(-2275,1950)',
 ROT='2',
 VER='2',
 PACK_TYPE='C0201',
 LOCATION='C6565',
 CDS_LIB='pure_quanta',
 CDS_PART_NAME='Q_CAP_DIFFBUS_C0201-DIFF BUS_0.22UF,6.3V,20%,X6S,SA',
 VOLTAGE='6.3V',
 PART_NUMBER='SP_CH4221MEE01',
 VALUE='DIFF BUS_0.22UF',
 PRIM_FILE='./archive_libs/logical/q_cap_diffbus/chips/chips.prt';

PART_NAME
 C6566 'Q_CAP_DIFFBUS_C0201-DIFF BUS_0.22UF,6.3V,20%,X6S,SA':;

SECTION_NUMBER 1
 '@T6G_MB_LIB.T6G(SCH_1):PAGE418_I48@PURE_QUANTA.Q_CAP_DIFFBUS(CHIPS)':
 C_PATH='@t6g_mb_lib.t6g(sch_1):page418_i48@pure_quanta.q_cap_diffbus(chips)',
 P_PATH='@t6g_mb_lib.t6g(sch_1):page297_i48@pure_quanta.q_cap_diffbus(chips)',
 PATH='I48',
 DRAWING='@T6G_MB_LIB.T6G(SCH_1):PAGE418',
 PIN_NAMES_ROTATE='TRUE',
 TOLERANCE='20%',
 MATERIAL='X6S',
 PHYS_PAGE='297',
 XY='(-2275,1900)',
 ROT='2',
 VER='2',
 PACK_TYPE='C0201',
 LOCATION='C6566',
 CDS_LIB='pure_quanta',
 CDS_PART_NAME='Q_CAP_DIFFBUS_C0201-DIFF BUS_0.22UF,6.3V,20%,X6S,SA',
 VOLTAGE='6.3V',
 PART_NUMBER='SP_CH4221MEE01',
 VALUE='DIFF BUS_0.22UF',
 PRIM_FILE='./archive_libs/logical/q_cap_diffbus/chips/chips.prt';

PART_NAME
 C6567 'Q_CAP_DIFFBUS_C0201-DIFF BUS_0.22UF,6.3V,20%,X6S,SA':;

SECTION_NUMBER 1
 '@T6G_MB_LIB.T6G(SCH_1):PAGE418_I32@PURE_QUANTA.Q_CAP_DIFFBUS(CHIPS)':
 C_PATH='@t6g_mb_lib.t6g(sch_1):page418_i32@pure_quanta.q_cap_diffbus(chips)',
 P_PATH='@t6g_mb_lib.t6g(sch_1):page297_i32@pure_quanta.q_cap_diffbus(chips)',
 PATH='I32',
 DRAWING='@T6G_MB_LIB.T6G(SCH_1):PAGE418',
 PIN_NAMES_ROTATE='TRUE',
 TOLERANCE='20%',
 MATERIAL='X6S',
 PHYS_PAGE='297',
 XY='(-2275,1750)',
 ROT='2',
 VER='2',
 PACK_TYPE='C0201',
 LOCATION='C6567',
 CDS_LIB='pure_quanta',
 CDS_PART_NAME='Q_CAP_DIFFBUS_C0201-DIFF BUS_0.22UF,6.3V,20%,X6S,SA',
 VOLTAGE='6.3V',
 PART_NUMBER='SP_CH4221MEE01',
 VALUE='DIFF BUS_0.22UF',
 PRIM_FILE='./archive_libs/logical/q_cap_diffbus/chips/chips.prt';

PART_NAME
 C6568 'Q_CAP_DIFFBUS_C0201-DIFF BUS_0.22UF,6.3V,20%,X6S,SA':;

SECTION_NUMBER 1
 '@T6G_MB_LIB.T6G(SCH_1):PAGE418_I33@PURE_QUANTA.Q_CAP_DIFFBUS(CHIPS)':
 C_PATH='@t6g_mb_lib.t6g(sch_1):page418_i33@pure_quanta.q_cap_diffbus(chips)',
 P_PATH='@t6g_mb_lib.t6g(sch_1):page297_i33@pure_quanta.q_cap_diffbus(chips)',
 PATH='I33',
 DRAWING='@T6G_MB_LIB.T6G(SCH_1):PAGE418',
 PIN_NAMES_ROTATE='TRUE',
 TOLERANCE='20%',
 MATERIAL='X6S',
 PHYS_PAGE='297',
 XY='(-2275,1700)',
 ROT='2',
 VER='2',
 PACK_TYPE='C0201',
 LOCATION='C6568',
 CDS_LIB='pure_quanta',
 CDS_PART_NAME='Q_CAP_DIFFBUS_C0201-DIFF BUS_0.22UF,6.3V,20%,X6S,SA',
 VOLTAGE='6.3V',
 PART_NUMBER='SP_CH4221MEE01',
 VALUE='DIFF BUS_0.22UF',
 PRIM_FILE='./archive_libs/logical/q_cap_diffbus/chips/chips.prt';

PART_NAME
 C6569 'Q_CAP_DIFFBUS_C0201-DIFF BUS_0.22UF,6.3V,20%,X6S,SA':;

SECTION_NUMBER 1
 '@T6G_MB_LIB.T6G(SCH_1):PAGE418_I34@PURE_QUANTA.Q_CAP_DIFFBUS(CHIPS)':
 C_PATH='@t6g_mb_lib.t6g(sch_1):page418_i34@pure_quanta.q_cap_diffbus(chips)',
 P_PATH='@t6g_mb_lib.t6g(sch_1):page297_i34@pure_quanta.q_cap_diffbus(chips)',
 PATH='I34',
 DRAWING='@T6G_MB_LIB.T6G(SCH_1):PAGE418',
 PIN_NAMES_ROTATE='TRUE',
 TOLERANCE='20%',
 MATERIAL='X6S',
 PHYS_PAGE='297',
 XY='(-2275,1550)',
 ROT='2',
 VER='2',
 PACK_TYPE='C0201',
 LOCATION='C6569',
 CDS_LIB='pure_quanta',
 CDS_PART_NAME='Q_CAP_DIFFBUS_C0201-DIFF BUS_0.22UF,6.3V,20%,X6S,SA',
 VOLTAGE='6.3V',
 PART_NUMBER='SP_CH4221MEE01',
 VALUE='DIFF BUS_0.22UF',
 PRIM_FILE='./archive_libs/logical/q_cap_diffbus/chips/chips.prt';

PART_NAME
 C6570 'Q_CAP_DIFFBUS_C0201-DIFF BUS_0.22UF,6.3V,20%,X6S,SA':;

SECTION_NUMBER 1
 '@T6G_MB_LIB.T6G(SCH_1):PAGE418_I31@PURE_QUANTA.Q_CAP_DIFFBUS(CHIPS)':
 C_PATH='@t6g_mb_lib.t6g(sch_1):page418_i31@pure_quanta.q_cap_diffbus(chips)',
 P_PATH='@t6g_mb_lib.t6g(sch_1):page297_i31@pure_quanta.q_cap_diffbus(chips)',
 PATH='I31',
 DRAWING='@T6G_MB_LIB.T6G(SCH_1):PAGE418',
 PIN_NAMES_ROTATE='TRUE',
 TOLERANCE='20%',
 MATERIAL='X6S',
 PHYS_PAGE='297',
 XY='(-2275,1500)',
 ROT='2',
 VER='2',
 PACK_TYPE='C0201',
 LOCATION='C6570',
 CDS_LIB='pure_quanta',
 CDS_PART_NAME='Q_CAP_DIFFBUS_C0201-DIFF BUS_0.22UF,6.3V,20%,X6S,SA',
 VOLTAGE='6.3V',
 PART_NUMBER='SP_CH4221MEE01',
 VALUE='DIFF BUS_0.22UF',
 PRIM_FILE='./archive_libs/logical/q_cap_diffbus/chips/chips.prt';

PART_NAME
 C6571 'Q_CAP_DIFFBUS_C0201-DIFF BUS_0.22UF,6.3V,20%,X6S,SA':;

SECTION_NUMBER 1
 '@T6G_MB_LIB.T6G(SCH_1):PAGE418_I30@PURE_QUANTA.Q_CAP_DIFFBUS(CHIPS)':
 C_PATH='@t6g_mb_lib.t6g(sch_1):page418_i30@pure_quanta.q_cap_diffbus(chips)',
 P_PATH='@t6g_mb_lib.t6g(sch_1):page297_i30@pure_quanta.q_cap_diffbus(chips)',
 PATH='I30',
 DRAWING='@T6G_MB_LIB.T6G(SCH_1):PAGE418',
 PIN_NAMES_ROTATE='TRUE',
 TOLERANCE='20%',
 MATERIAL='X6S',
 PHYS_PAGE='297',
 XY='(-2275,1350)',
 ROT='2',
 VER='2',
 PACK_TYPE='C0201',
 LOCATION='C6571',
 CDS_LIB='pure_quanta',
 CDS_PART_NAME='Q_CAP_DIFFBUS_C0201-DIFF BUS_0.22UF,6.3V,20%,X6S,SA',
 VOLTAGE='6.3V',
 PART_NUMBER='SP_CH4221MEE01',
 VALUE='DIFF BUS_0.22UF',
 PRIM_FILE='./archive_libs/logical/q_cap_diffbus/chips/chips.prt';

PART_NAME
 C6572 'Q_CAP_DIFFBUS_C0201-DIFF BUS_0.22UF,6.3V,20%,X6S,SA':;

SECTION_NUMBER 1
 '@T6G_MB_LIB.T6G(SCH_1):PAGE418_I29@PURE_QUANTA.Q_CAP_DIFFBUS(CHIPS)':
 C_PATH='@t6g_mb_lib.t6g(sch_1):page418_i29@pure_quanta.q_cap_diffbus(chips)',
 P_PATH='@t6g_mb_lib.t6g(sch_1):page297_i29@pure_quanta.q_cap_diffbus(chips)',
 PATH='I29',
 DRAWING='@T6G_MB_LIB.T6G(SCH_1):PAGE418',
 PIN_NAMES_ROTATE='TRUE',
 TOLERANCE='20%',
 MATERIAL='X6S',
 PHYS_PAGE='297',
 XY='(-2275,1300)',
 ROT='2',
 VER='2',
 PACK_TYPE='C0201',
 LOCATION='C6572',
 CDS_LIB='pure_quanta',
 CDS_PART_NAME='Q_CAP_DIFFBUS_C0201-DIFF BUS_0.22UF,6.3V,20%,X6S,SA',
 VOLTAGE='6.3V',
 PART_NUMBER='SP_CH4221MEE01',
 VALUE='DIFF BUS_0.22UF',
 PRIM_FILE='./archive_libs/logical/q_cap_diffbus/chips/chips.prt';

PART_NAME
 C6573 'Q_CAP_DIFFBUS_C0201-DIFF BUS_0.22UF,6.3V,20%,X6S,SA':;

SECTION_NUMBER 1
 '@T6G_MB_LIB.T6G(SCH_1):PAGE418_I27@PURE_QUANTA.Q_CAP_DIFFBUS(CHIPS)':
 C_PATH='@t6g_mb_lib.t6g(sch_1):page418_i27@pure_quanta.q_cap_diffbus(chips)',
 P_PATH='@t6g_mb_lib.t6g(sch_1):page297_i27@pure_quanta.q_cap_diffbus(chips)',
 PATH='I27',
 DRAWING='@T6G_MB_LIB.T6G(SCH_1):PAGE418',
 PIN_NAMES_ROTATE='TRUE',
 TOLERANCE='20%',
 MATERIAL='X6S',
 PHYS_PAGE='297',
 XY='(-2275,1150)',
 ROT='2',
 VER='2',
 PACK_TYPE='C0201',
 LOCATION='C6573',
 CDS_LIB='pure_quanta',
 CDS_PART_NAME='Q_CAP_DIFFBUS_C0201-DIFF BUS_0.22UF,6.3V,20%,X6S,SA',
 VOLTAGE='6.3V',
 PART_NUMBER='SP_CH4221MEE01',
 VALUE='DIFF BUS_0.22UF',
 PRIM_FILE='./archive_libs/logical/q_cap_diffbus/chips/chips.prt';

PART_NAME
 C6574 'Q_CAP_DIFFBUS_C0201-DIFF BUS_0.22UF,6.3V,20%,X6S,SA':;

SECTION_NUMBER 1
 '@T6G_MB_LIB.T6G(SCH_1):PAGE418_I28@PURE_QUANTA.Q_CAP_DIFFBUS(CHIPS)':
 C_PATH='@t6g_mb_lib.t6g(sch_1):page418_i28@pure_quanta.q_cap_diffbus(chips)',
 P_PATH='@t6g_mb_lib.t6g(sch_1):page297_i28@pure_quanta.q_cap_diffbus(chips)',
 PATH='I28',
 DRAWING='@T6G_MB_LIB.T6G(SCH_1):PAGE418',
 PIN_NAMES_ROTATE='TRUE',
 TOLERANCE='20%',
 MATERIAL='X6S',
 PHYS_PAGE='297',
 XY='(-2275,1100)',
 ROT='2',
 VER='2',
 PACK_TYPE='C0201',
 LOCATION='C6574',
 CDS_LIB='pure_quanta',
 CDS_PART_NAME='Q_CAP_DIFFBUS_C0201-DIFF BUS_0.22UF,6.3V,20%,X6S,SA',
 VOLTAGE='6.3V',
 PART_NUMBER='SP_CH4221MEE01',
 VALUE='DIFF BUS_0.22UF',
 PRIM_FILE='./archive_libs/logical/q_cap_diffbus/chips/chips.prt';

PART_NAME
 C6575 'Q_CAP_DIFFBUS_C0201-DIFF BUS_0.22UF,6.3V,20%,X6S,SA':;

SECTION_NUMBER 1
 '@T6G_MB_LIB.T6G(SCH_1):PAGE418_I25@PURE_QUANTA.Q_CAP_DIFFBUS(CHIPS)':
 C_PATH='@t6g_mb_lib.t6g(sch_1):page418_i25@pure_quanta.q_cap_diffbus(chips)',
 P_PATH='@t6g_mb_lib.t6g(sch_1):page297_i25@pure_quanta.q_cap_diffbus(chips)',
 PATH='I25',
 DRAWING='@T6G_MB_LIB.T6G(SCH_1):PAGE418',
 PIN_NAMES_ROTATE='TRUE',
 TOLERANCE='20%',
 MATERIAL='X6S',
 PHYS_PAGE='297',
 XY='(-2275,950)',
 ROT='2',
 VER='2',
 PACK_TYPE='C0201',
 LOCATION='C6575',
 CDS_LIB='pure_quanta',
 CDS_PART_NAME='Q_CAP_DIFFBUS_C0201-DIFF BUS_0.22UF,6.3V,20%,X6S,SA',
 VOLTAGE='6.3V',
 PART_NUMBER='SP_CH4221MEE01',
 VALUE='DIFF BUS_0.22UF',
 PRIM_FILE='./archive_libs/logical/q_cap_diffbus/chips/chips.prt';

PART_NAME
 C6576 'Q_CAP_DIFFBUS_C0201-DIFF BUS_0.22UF,6.3V,20%,X6S,SA':;

SECTION_NUMBER 1
 '@T6G_MB_LIB.T6G(SCH_1):PAGE418_I26@PURE_QUANTA.Q_CAP_DIFFBUS(CHIPS)':
 C_PATH='@t6g_mb_lib.t6g(sch_1):page418_i26@pure_quanta.q_cap_diffbus(chips)',
 P_PATH='@t6g_mb_lib.t6g(sch_1):page297_i26@pure_quanta.q_cap_diffbus(chips)',
 PATH='I26',
 DRAWING='@T6G_MB_LIB.T6G(SCH_1):PAGE418',
 PIN_NAMES_ROTATE='TRUE',
 TOLERANCE='20%',
 MATERIAL='X6S',
 PHYS_PAGE='297',
 XY='(-2275,900)',
 ROT='2',
 VER='2',
 PACK_TYPE='C0201',
 LOCATION='C6576',
 CDS_LIB='pure_quanta',
 CDS_PART_NAME='Q_CAP_DIFFBUS_C0201-DIFF BUS_0.22UF,6.3V,20%,X6S,SA',
 VOLTAGE='6.3V',
 PART_NUMBER='SP_CH4221MEE01',
 VALUE='DIFF BUS_0.22UF',
 PRIM_FILE='./archive_libs/logical/q_cap_diffbus/chips/chips.prt';

PART_NAME
 C6577 'Q_CAP_DIFFBUS_C0201-DIFF BUS_0.22UF,6.3V,20%,X6S,SA':;

SECTION_NUMBER 1
 '@T6G_MB_LIB.T6G(SCH_1):PAGE418_I19@PURE_QUANTA.Q_CAP_DIFFBUS(CHIPS)':
 C_PATH='@t6g_mb_lib.t6g(sch_1):page418_i19@pure_quanta.q_cap_diffbus(chips)',
 P_PATH='@t6g_mb_lib.t6g(sch_1):page297_i19@pure_quanta.q_cap_diffbus(chips)',
 PATH='I19',
 DRAWING='@T6G_MB_LIB.T6G(SCH_1):PAGE418',
 PIN_NAMES_ROTATE='TRUE',
 TOLERANCE='20%',
 MATERIAL='X6S',
 PHYS_PAGE='297',
 XY='(-2275,750)',
 ROT='2',
 VER='2',
 PACK_TYPE='C0201',
 LOCATION='C6577',
 CDS_LIB='pure_quanta',
 CDS_PART_NAME='Q_CAP_DIFFBUS_C0201-DIFF BUS_0.22UF,6.3V,20%,X6S,SA',
 VOLTAGE='6.3V',
 PART_NUMBER='SP_CH4221MEE01',
 VALUE='DIFF BUS_0.22UF',
 PRIM_FILE='./archive_libs/logical/q_cap_diffbus/chips/chips.prt';

PART_NAME
 C6578 'Q_CAP_DIFFBUS_C0201-DIFF BUS_0.22UF,6.3V,20%,X6S,SA':;

SECTION_NUMBER 1
 '@T6G_MB_LIB.T6G(SCH_1):PAGE418_I20@PURE_QUANTA.Q_CAP_DIFFBUS(CHIPS)':
 C_PATH='@t6g_mb_lib.t6g(sch_1):page418_i20@pure_quanta.q_cap_diffbus(chips)',
 P_PATH='@t6g_mb_lib.t6g(sch_1):page297_i20@pure_quanta.q_cap_diffbus(chips)',
 PATH='I20',
 DRAWING='@T6G_MB_LIB.T6G(SCH_1):PAGE418',
 PIN_NAMES_ROTATE='TRUE',
 TOLERANCE='20%',
 MATERIAL='X6S',
 PHYS_PAGE='297',
 XY='(-2275,700)',
 ROT='2',
 VER='2',
 PACK_TYPE='C0201',
 LOCATION='C6578',
 CDS_LIB='pure_quanta',
 CDS_PART_NAME='Q_CAP_DIFFBUS_C0201-DIFF BUS_0.22UF,6.3V,20%,X6S,SA',
 VOLTAGE='6.3V',
 PART_NUMBER='SP_CH4221MEE01',
 VALUE='DIFF BUS_0.22UF',
 PRIM_FILE='./archive_libs/logical/q_cap_diffbus/chips/chips.prt';

PART_NAME
 C6579 'Q_CAP_DIFFBUS_C0201-DIFF BUS_0.22UF,6.3V,20%,X6S,SA':;

SECTION_NUMBER 1
 '@T6G_MB_LIB.T6G(SCH_1):PAGE418_I18@PURE_QUANTA.Q_CAP_DIFFBUS(CHIPS)':
 C_PATH='@t6g_mb_lib.t6g(sch_1):page418_i18@pure_quanta.q_cap_diffbus(chips)',
 P_PATH='@t6g_mb_lib.t6g(sch_1):page297_i18@pure_quanta.q_cap_diffbus(chips)',
 PATH='I18',
 DRAWING='@T6G_MB_LIB.T6G(SCH_1):PAGE418',
 PIN_NAMES_ROTATE='TRUE',
 TOLERANCE='20%',
 MATERIAL='X6S',
 PHYS_PAGE='297',
 XY='(-2275,550)',
 ROT='2',
 VER='2',
 PACK_TYPE='C0201',
 LOCATION='C6579',
 CDS_LIB='pure_quanta',
 CDS_PART_NAME='Q_CAP_DIFFBUS_C0201-DIFF BUS_0.22UF,6.3V,20%,X6S,SA',
 VOLTAGE='6.3V',
 PART_NUMBER='SP_CH4221MEE01',
 VALUE='DIFF BUS_0.22UF',
 PRIM_FILE='./archive_libs/logical/q_cap_diffbus/chips/chips.prt';

PART_NAME
 C6580 'Q_CAP_DIFFBUS_C0201-DIFF BUS_0.22UF,6.3V,20%,X6S,SA':;

SECTION_NUMBER 1
 '@T6G_MB_LIB.T6G(SCH_1):PAGE418_I17@PURE_QUANTA.Q_CAP_DIFFBUS(CHIPS)':
 C_PATH='@t6g_mb_lib.t6g(sch_1):page418_i17@pure_quanta.q_cap_diffbus(chips)',
 P_PATH='@t6g_mb_lib.t6g(sch_1):page297_i17@pure_quanta.q_cap_diffbus(chips)',
 PATH='I17',
 DRAWING='@T6G_MB_LIB.T6G(SCH_1):PAGE418',
 PIN_NAMES_ROTATE='TRUE',
 TOLERANCE='20%',
 MATERIAL='X6S',
 PHYS_PAGE='297',
 XY='(-2275,500)',
 ROT='2',
 VER='2',
 PACK_TYPE='C0201',
 LOCATION='C6580',
 CDS_LIB='pure_quanta',
 CDS_PART_NAME='Q_CAP_DIFFBUS_C0201-DIFF BUS_0.22UF,6.3V,20%,X6S,SA',
 VOLTAGE='6.3V',
 PART_NUMBER='SP_CH4221MEE01',
 VALUE='DIFF BUS_0.22UF',
 PRIM_FILE='./archive_libs/logical/q_cap_diffbus/chips/chips.prt';

PART_NAME
 C6581 'Q_CAP_DIFFBUS_C0201-DIFF BUS_0.22UF,6.3V,20%,X6S,SA':;

SECTION_NUMBER 1
 '@T6G_MB_LIB.T6G(SCH_1):PAGE418_I104@PURE_QUANTA.Q_CAP_DIFFBUS(CHIPS)':
 C_PATH='@t6g_mb_lib.t6g(sch_1):page418_i104@pure_quanta.q_cap_diffbus(chips)',
 P_PATH='@t6g_mb_lib.t6g(sch_1):page297_i104@pure_quanta.q_cap_diffbus(chips)',
 PATH='I104',
 DRAWING='@T6G_MB_LIB.T6G(SCH_1):PAGE418',
 PIN_NAMES_ROTATE='TRUE',
 TOLERANCE='20%',
 MATERIAL='X6S',
 PHYS_PAGE='297',
 XY='(-7125,2025)',
 ROT='2',
 VER='2',
 PACK_TYPE='C0201',
 LOCATION='C6581',
 CDS_LIB='pure_quanta',
 CDS_PART_NAME='Q_CAP_DIFFBUS_C0201-DIFF BUS_0.22UF,6.3V,20%,X6S,SA',
 VOLTAGE='6.3V',
 PART_NUMBER='SP_CH4221MEE01',
 VALUE='DIFF BUS_0.22UF',
 PRIM_FILE='./archive_libs/logical/q_cap_diffbus/chips/chips.prt';

PART_NAME
 C6582 'Q_CAP_DIFFBUS_C0201-DIFF BUS_0.22UF,6.3V,20%,X6S,SA':;

SECTION_NUMBER 1
 '@T6G_MB_LIB.T6G(SCH_1):PAGE418_I105@PURE_QUANTA.Q_CAP_DIFFBUS(CHIPS)':
 C_PATH='@t6g_mb_lib.t6g(sch_1):page418_i105@pure_quanta.q_cap_diffbus(chips)',
 P_PATH='@t6g_mb_lib.t6g(sch_1):page297_i105@pure_quanta.q_cap_diffbus(chips)',
 PATH='I105',
 DRAWING='@T6G_MB_LIB.T6G(SCH_1):PAGE418',
 PIN_NAMES_ROTATE='TRUE',
 TOLERANCE='20%',
 MATERIAL='X6S',
 PHYS_PAGE='297',
 XY='(-7125,1975)',
 ROT='2',
 VER='2',
 PACK_TYPE='C0201',
 LOCATION='C6582',
 CDS_LIB='pure_quanta',
 CDS_PART_NAME='Q_CAP_DIFFBUS_C0201-DIFF BUS_0.22UF,6.3V,20%,X6S,SA',
 VOLTAGE='6.3V',
 PART_NUMBER='SP_CH4221MEE01',
 VALUE='DIFF BUS_0.22UF',
 PRIM_FILE='./archive_libs/logical/q_cap_diffbus/chips/chips.prt';

PART_NAME
 C6583 'Q_CAP_DIFFBUS_C0201-DIFF BUS_0.22UF,6.3V,20%,X6S,SA':;

SECTION_NUMBER 1
 '@T6G_MB_LIB.T6G(SCH_1):PAGE418_I101@PURE_QUANTA.Q_CAP_DIFFBUS(CHIPS)':
 C_PATH='@t6g_mb_lib.t6g(sch_1):page418_i101@pure_quanta.q_cap_diffbus(chips)',
 P_PATH='@t6g_mb_lib.t6g(sch_1):page297_i101@pure_quanta.q_cap_diffbus(chips)',
 PATH='I101',
 DRAWING='@T6G_MB_LIB.T6G(SCH_1):PAGE418',
 PIN_NAMES_ROTATE='TRUE',
 TOLERANCE='20%',
 MATERIAL='X6S',
 PHYS_PAGE='297',
 XY='(-7125,1825)',
 ROT='2',
 VER='2',
 PACK_TYPE='C0201',
 LOCATION='C6583',
 CDS_LIB='pure_quanta',
 CDS_PART_NAME='Q_CAP_DIFFBUS_C0201-DIFF BUS_0.22UF,6.3V,20%,X6S,SA',
 VOLTAGE='6.3V',
 PART_NUMBER='SP_CH4221MEE01',
 VALUE='DIFF BUS_0.22UF',
 PRIM_FILE='./archive_libs/logical/q_cap_diffbus/chips/chips.prt';

PART_NAME
 C6584 'Q_CAP_DIFFBUS_C0201-DIFF BUS_0.22UF,6.3V,20%,X6S,SA':;

SECTION_NUMBER 1
 '@T6G_MB_LIB.T6G(SCH_1):PAGE418_I100@PURE_QUANTA.Q_CAP_DIFFBUS(CHIPS)':
 C_PATH='@t6g_mb_lib.t6g(sch_1):page418_i100@pure_quanta.q_cap_diffbus(chips)',
 P_PATH='@t6g_mb_lib.t6g(sch_1):page297_i100@pure_quanta.q_cap_diffbus(chips)',
 PATH='I100',
 DRAWING='@T6G_MB_LIB.T6G(SCH_1):PAGE418',
 PIN_NAMES_ROTATE='TRUE',
 TOLERANCE='20%',
 MATERIAL='X6S',
 PHYS_PAGE='297',
 XY='(-7125,1775)',
 ROT='2',
 VER='2',
 PACK_TYPE='C0201',
 LOCATION='C6584',
 CDS_LIB='pure_quanta',
 CDS_PART_NAME='Q_CAP_DIFFBUS_C0201-DIFF BUS_0.22UF,6.3V,20%,X6S,SA',
 VOLTAGE='6.3V',
 PART_NUMBER='SP_CH4221MEE01',
 VALUE='DIFF BUS_0.22UF',
 PRIM_FILE='./archive_libs/logical/q_cap_diffbus/chips/chips.prt';

PART_NAME
 C6585 'Q_CAP_DIFFBUS_C0201-DIFF BUS_0.22UF,6.3V,20%,X6S,SA':;

SECTION_NUMBER 1
 '@T6G_MB_LIB.T6G(SCH_1):PAGE418_I99@PURE_QUANTA.Q_CAP_DIFFBUS(CHIPS)':
 C_PATH='@t6g_mb_lib.t6g(sch_1):page418_i99@pure_quanta.q_cap_diffbus(chips)',
 P_PATH='@t6g_mb_lib.t6g(sch_1):page297_i99@pure_quanta.q_cap_diffbus(chips)',
 PATH='I99',
 DRAWING='@T6G_MB_LIB.T6G(SCH_1):PAGE418',
 PIN_NAMES_ROTATE='TRUE',
 TOLERANCE='20%',
 MATERIAL='X6S',
 PHYS_PAGE='297',
 XY='(-7125,1625)',
 ROT='2',
 VER='2',
 PACK_TYPE='C0201',
 LOCATION='C6585',
 CDS_LIB='pure_quanta',
 CDS_PART_NAME='Q_CAP_DIFFBUS_C0201-DIFF BUS_0.22UF,6.3V,20%,X6S,SA',
 VOLTAGE='6.3V',
 PART_NUMBER='SP_CH4221MEE01',
 VALUE='DIFF BUS_0.22UF',
 PRIM_FILE='./archive_libs/logical/q_cap_diffbus/chips/chips.prt';

PART_NAME
 C6586 'Q_CAP_DIFFBUS_C0201-DIFF BUS_0.22UF,6.3V,20%,X6S,SA':;

SECTION_NUMBER 1
 '@T6G_MB_LIB.T6G(SCH_1):PAGE418_I98@PURE_QUANTA.Q_CAP_DIFFBUS(CHIPS)':
 C_PATH='@t6g_mb_lib.t6g(sch_1):page418_i98@pure_quanta.q_cap_diffbus(chips)',
 P_PATH='@t6g_mb_lib.t6g(sch_1):page297_i98@pure_quanta.q_cap_diffbus(chips)',
 PATH='I98',
 DRAWING='@T6G_MB_LIB.T6G(SCH_1):PAGE418',
 PIN_NAMES_ROTATE='TRUE',
 TOLERANCE='20%',
 MATERIAL='X6S',
 PHYS_PAGE='297',
 XY='(-7125,1575)',
 ROT='2',
 VER='2',
 PACK_TYPE='C0201',
 LOCATION='C6586',
 CDS_LIB='pure_quanta',
 CDS_PART_NAME='Q_CAP_DIFFBUS_C0201-DIFF BUS_0.22UF,6.3V,20%,X6S,SA',
 VOLTAGE='6.3V',
 PART_NUMBER='SP_CH4221MEE01',
 VALUE='DIFF BUS_0.22UF',
 PRIM_FILE='./archive_libs/logical/q_cap_diffbus/chips/chips.prt';

PART_NAME
 C6587 'Q_CAP_DIFFBUS_C0201-DIFF BUS_0.22UF,6.3V,20%,X6S,SA':;

SECTION_NUMBER 1
 '@T6G_MB_LIB.T6G(SCH_1):PAGE418_I97@PURE_QUANTA.Q_CAP_DIFFBUS(CHIPS)':
 C_PATH='@t6g_mb_lib.t6g(sch_1):page418_i97@pure_quanta.q_cap_diffbus(chips)',
 P_PATH='@t6g_mb_lib.t6g(sch_1):page297_i97@pure_quanta.q_cap_diffbus(chips)',
 PATH='I97',
 DRAWING='@T6G_MB_LIB.T6G(SCH_1):PAGE418',
 PIN_NAMES_ROTATE='TRUE',
 TOLERANCE='20%',
 MATERIAL='X6S',
 PHYS_PAGE='297',
 XY='(-7125,1425)',
 ROT='2',
 VER='2',
 PACK_TYPE='C0201',
 LOCATION='C6587',
 CDS_LIB='pure_quanta',
 CDS_PART_NAME='Q_CAP_DIFFBUS_C0201-DIFF BUS_0.22UF,6.3V,20%,X6S,SA',
 VOLTAGE='6.3V',
 PART_NUMBER='SP_CH4221MEE01',
 VALUE='DIFF BUS_0.22UF',
 PRIM_FILE='./archive_libs/logical/q_cap_diffbus/chips/chips.prt';

PART_NAME
 C6588 'Q_CAP_DIFFBUS_C0201-DIFF BUS_0.22UF,6.3V,20%,X6S,SA':;

SECTION_NUMBER 1
 '@T6G_MB_LIB.T6G(SCH_1):PAGE418_I96@PURE_QUANTA.Q_CAP_DIFFBUS(CHIPS)':
 C_PATH='@t6g_mb_lib.t6g(sch_1):page418_i96@pure_quanta.q_cap_diffbus(chips)',
 P_PATH='@t6g_mb_lib.t6g(sch_1):page297_i96@pure_quanta.q_cap_diffbus(chips)',
 PATH='I96',
 DRAWING='@T6G_MB_LIB.T6G(SCH_1):PAGE418',
 PIN_NAMES_ROTATE='TRUE',
 TOLERANCE='20%',
 MATERIAL='X6S',
 PHYS_PAGE='297',
 XY='(-7125,1375)',
 ROT='2',
 VER='2',
 PACK_TYPE='C0201',
 LOCATION='C6588',
 CDS_LIB='pure_quanta',
 CDS_PART_NAME='Q_CAP_DIFFBUS_C0201-DIFF BUS_0.22UF,6.3V,20%,X6S,SA',
 VOLTAGE='6.3V',
 PART_NUMBER='SP_CH4221MEE01',
 VALUE='DIFF BUS_0.22UF',
 PRIM_FILE='./archive_libs/logical/q_cap_diffbus/chips/chips.prt';

PART_NAME
 C6589 'Q_CAP_DIFFBUS_C0201-DIFF BUS_0.22UF,6.3V,20%,X6S,SA':;

SECTION_NUMBER 1
 '@T6G_MB_LIB.T6G(SCH_1):PAGE418_I95@PURE_QUANTA.Q_CAP_DIFFBUS(CHIPS)':
 C_PATH='@t6g_mb_lib.t6g(sch_1):page418_i95@pure_quanta.q_cap_diffbus(chips)',
 P_PATH='@t6g_mb_lib.t6g(sch_1):page297_i95@pure_quanta.q_cap_diffbus(chips)',
 PATH='I95',
 DRAWING='@T6G_MB_LIB.T6G(SCH_1):PAGE418',
 PIN_NAMES_ROTATE='TRUE',
 TOLERANCE='20%',
 MATERIAL='X6S',
 PHYS_PAGE='297',
 XY='(-7125,1225)',
 ROT='2',
 VER='2',
 PACK_TYPE='C0201',
 LOCATION='C6589',
 CDS_LIB='pure_quanta',
 CDS_PART_NAME='Q_CAP_DIFFBUS_C0201-DIFF BUS_0.22UF,6.3V,20%,X6S,SA',
 VOLTAGE='6.3V',
 PART_NUMBER='SP_CH4221MEE01',
 VALUE='DIFF BUS_0.22UF',
 PRIM_FILE='./archive_libs/logical/q_cap_diffbus/chips/chips.prt';

PART_NAME
 C6590 'Q_CAP_DIFFBUS_C0201-DIFF BUS_0.22UF,6.3V,20%,X6S,SA':;

SECTION_NUMBER 1
 '@T6G_MB_LIB.T6G(SCH_1):PAGE418_I94@PURE_QUANTA.Q_CAP_DIFFBUS(CHIPS)':
 C_PATH='@t6g_mb_lib.t6g(sch_1):page418_i94@pure_quanta.q_cap_diffbus(chips)',
 P_PATH='@t6g_mb_lib.t6g(sch_1):page297_i94@pure_quanta.q_cap_diffbus(chips)',
 PATH='I94',
 DRAWING='@T6G_MB_LIB.T6G(SCH_1):PAGE418',
 PIN_NAMES_ROTATE='TRUE',
 TOLERANCE='20%',
 MATERIAL='X6S',
 PHYS_PAGE='297',
 XY='(-7125,1175)',
 ROT='2',
 VER='2',
 PACK_TYPE='C0201',
 LOCATION='C6590',
 CDS_LIB='pure_quanta',
 CDS_PART_NAME='Q_CAP_DIFFBUS_C0201-DIFF BUS_0.22UF,6.3V,20%,X6S,SA',
 VOLTAGE='6.3V',
 PART_NUMBER='SP_CH4221MEE01',
 VALUE='DIFF BUS_0.22UF',
 PRIM_FILE='./archive_libs/logical/q_cap_diffbus/chips/chips.prt';

PART_NAME
 C6591 'Q_CAP_DIFFBUS_C0201-DIFF BUS_0.22UF,6.3V,20%,X6S,SA':;

SECTION_NUMBER 1
 '@T6G_MB_LIB.T6G(SCH_1):PAGE418_I93@PURE_QUANTA.Q_CAP_DIFFBUS(CHIPS)':
 C_PATH='@t6g_mb_lib.t6g(sch_1):page418_i93@pure_quanta.q_cap_diffbus(chips)',
 P_PATH='@t6g_mb_lib.t6g(sch_1):page297_i93@pure_quanta.q_cap_diffbus(chips)',
 PATH='I93',
 DRAWING='@T6G_MB_LIB.T6G(SCH_1):PAGE418',
 PIN_NAMES_ROTATE='TRUE',
 TOLERANCE='20%',
 MATERIAL='X6S',
 PHYS_PAGE='297',
 XY='(-7125,1025)',
 ROT='2',
 VER='2',
 PACK_TYPE='C0201',
 LOCATION='C6591',
 CDS_LIB='pure_quanta',
 CDS_PART_NAME='Q_CAP_DIFFBUS_C0201-DIFF BUS_0.22UF,6.3V,20%,X6S,SA',
 VOLTAGE='6.3V',
 PART_NUMBER='SP_CH4221MEE01',
 VALUE='DIFF BUS_0.22UF',
 PRIM_FILE='./archive_libs/logical/q_cap_diffbus/chips/chips.prt';

PART_NAME
 C6592 'Q_CAP_DIFFBUS_C0201-DIFF BUS_0.22UF,6.3V,20%,X6S,SA':;

SECTION_NUMBER 1
 '@T6G_MB_LIB.T6G(SCH_1):PAGE418_I92@PURE_QUANTA.Q_CAP_DIFFBUS(CHIPS)':
 C_PATH='@t6g_mb_lib.t6g(sch_1):page418_i92@pure_quanta.q_cap_diffbus(chips)',
 P_PATH='@t6g_mb_lib.t6g(sch_1):page297_i92@pure_quanta.q_cap_diffbus(chips)',
 PATH='I92',
 DRAWING='@T6G_MB_LIB.T6G(SCH_1):PAGE418',
 PIN_NAMES_ROTATE='TRUE',
 TOLERANCE='20%',
 MATERIAL='X6S',
 PHYS_PAGE='297',
 XY='(-7125,975)',
 ROT='2',
 VER='2',
 PACK_TYPE='C0201',
 LOCATION='C6592',
 CDS_LIB='pure_quanta',
 CDS_PART_NAME='Q_CAP_DIFFBUS_C0201-DIFF BUS_0.22UF,6.3V,20%,X6S,SA',
 VOLTAGE='6.3V',
 PART_NUMBER='SP_CH4221MEE01',
 VALUE='DIFF BUS_0.22UF',
 PRIM_FILE='./archive_libs/logical/q_cap_diffbus/chips/chips.prt';

PART_NAME
 C6593 'Q_CAP_DIFFBUS_C0201-DIFF BUS_0.22UF,6.3V,20%,X6S,SA':;

SECTION_NUMBER 1
 '@T6G_MB_LIB.T6G(SCH_1):PAGE418_I91@PURE_QUANTA.Q_CAP_DIFFBUS(CHIPS)':
 C_PATH='@t6g_mb_lib.t6g(sch_1):page418_i91@pure_quanta.q_cap_diffbus(chips)',
 P_PATH='@t6g_mb_lib.t6g(sch_1):page297_i91@pure_quanta.q_cap_diffbus(chips)',
 PATH='I91',
 DRAWING='@T6G_MB_LIB.T6G(SCH_1):PAGE418',
 PIN_NAMES_ROTATE='TRUE',
 TOLERANCE='20%',
 MATERIAL='X6S',
 PHYS_PAGE='297',
 XY='(-7125,825)',
 ROT='2',
 VER='2',
 PACK_TYPE='C0201',
 LOCATION='C6593',
 CDS_LIB='pure_quanta',
 CDS_PART_NAME='Q_CAP_DIFFBUS_C0201-DIFF BUS_0.22UF,6.3V,20%,X6S,SA',
 VOLTAGE='6.3V',
 PART_NUMBER='SP_CH4221MEE01',
 VALUE='DIFF BUS_0.22UF',
 PRIM_FILE='./archive_libs/logical/q_cap_diffbus/chips/chips.prt';

PART_NAME
 C6594 'Q_CAP_DIFFBUS_C0201-DIFF BUS_0.22UF,6.3V,20%,X6S,SA':;

SECTION_NUMBER 1
 '@T6G_MB_LIB.T6G(SCH_1):PAGE418_I90@PURE_QUANTA.Q_CAP_DIFFBUS(CHIPS)':
 C_PATH='@t6g_mb_lib.t6g(sch_1):page418_i90@pure_quanta.q_cap_diffbus(chips)',
 P_PATH='@t6g_mb_lib.t6g(sch_1):page297_i90@pure_quanta.q_cap_diffbus(chips)',
 PATH='I90',
 DRAWING='@T6G_MB_LIB.T6G(SCH_1):PAGE418',
 PIN_NAMES_ROTATE='TRUE',
 TOLERANCE='20%',
 MATERIAL='X6S',
 PHYS_PAGE='297',
 XY='(-7125,775)',
 ROT='2',
 VER='2',
 PACK_TYPE='C0201',
 LOCATION='C6594',
 CDS_LIB='pure_quanta',
 CDS_PART_NAME='Q_CAP_DIFFBUS_C0201-DIFF BUS_0.22UF,6.3V,20%,X6S,SA',
 VOLTAGE='6.3V',
 PART_NUMBER='SP_CH4221MEE01',
 VALUE='DIFF BUS_0.22UF',
 PRIM_FILE='./archive_libs/logical/q_cap_diffbus/chips/chips.prt';

PART_NAME
 C6595 'Q_CAP_DIFFBUS_C0201-DIFF BUS_0.22UF,6.3V,20%,X6S,SA':;

SECTION_NUMBER 1
 '@T6G_MB_LIB.T6G(SCH_1):PAGE418_I89@PURE_QUANTA.Q_CAP_DIFFBUS(CHIPS)':
 C_PATH='@t6g_mb_lib.t6g(sch_1):page418_i89@pure_quanta.q_cap_diffbus(chips)',
 P_PATH='@t6g_mb_lib.t6g(sch_1):page297_i89@pure_quanta.q_cap_diffbus(chips)',
 PATH='I89',
 DRAWING='@T6G_MB_LIB.T6G(SCH_1):PAGE418',
 PIN_NAMES_ROTATE='TRUE',
 TOLERANCE='20%',
 MATERIAL='X6S',
 PHYS_PAGE='297',
 XY='(-7125,625)',
 ROT='2',
 VER='2',
 PACK_TYPE='C0201',
 LOCATION='C6595',
 CDS_LIB='pure_quanta',
 CDS_PART_NAME='Q_CAP_DIFFBUS_C0201-DIFF BUS_0.22UF,6.3V,20%,X6S,SA',
 VOLTAGE='6.3V',
 PART_NUMBER='SP_CH4221MEE01',
 VALUE='DIFF BUS_0.22UF',
 PRIM_FILE='./archive_libs/logical/q_cap_diffbus/chips/chips.prt';

PART_NAME
 C6596 'Q_CAP_DIFFBUS_C0201-DIFF BUS_0.22UF,6.3V,20%,X6S,SA':;

SECTION_NUMBER 1
 '@T6G_MB_LIB.T6G(SCH_1):PAGE418_I88@PURE_QUANTA.Q_CAP_DIFFBUS(CHIPS)':
 C_PATH='@t6g_mb_lib.t6g(sch_1):page418_i88@pure_quanta.q_cap_diffbus(chips)',
 P_PATH='@t6g_mb_lib.t6g(sch_1):page297_i88@pure_quanta.q_cap_diffbus(chips)',
 PATH='I88',
 DRAWING='@T6G_MB_LIB.T6G(SCH_1):PAGE418',
 PIN_NAMES_ROTATE='TRUE',
 TOLERANCE='20%',
 MATERIAL='X6S',
 PHYS_PAGE='297',
 XY='(-7125,575)',
 ROT='2',
 VER='2',
 PACK_TYPE='C0201',
 LOCATION='C6596',
 CDS_LIB='pure_quanta',
 CDS_PART_NAME='Q_CAP_DIFFBUS_C0201-DIFF BUS_0.22UF,6.3V,20%,X6S,SA',
 VOLTAGE='6.3V',
 PART_NUMBER='SP_CH4221MEE01',
 VALUE='DIFF BUS_0.22UF',
 PRIM_FILE='./archive_libs/logical/q_cap_diffbus/chips/chips.prt';

PART_NAME
 C6597 'Q_CAP_DIFFBUS_C0201-DIFF BUS_0.22UF,6.3V,20%,X6S,SA':;

SECTION_NUMBER 1
 '@T6G_MB_LIB.T6G(SCH_1):PAGE429_I40@PURE_QUANTA.Q_CAP_DIFFBUS(CHIPS)':
 C_PATH='@t6g_mb_lib.t6g(sch_1):page429_i40@pure_quanta.q_cap_diffbus(chips)',
 P_PATH='@t6g_mb_lib.t6g(sch_1):page308_i40@pure_quanta.q_cap_diffbus(chips)',
 PATH='I40',
 DRAWING='@T6G_MB_LIB.T6G(SCH_1):PAGE429',
 PIN_NAMES_ROTATE='TRUE',
 TOLERANCE='20%',
 MATERIAL='X6S',
 PHYS_PAGE='308',
 XY='(-2475,2050)',
 ROT='2',
 VER='2',
 PACK_TYPE='C0201',
 LOCATION='C6597',
 CDS_LIB='pure_quanta',
 CDS_PART_NAME='Q_CAP_DIFFBUS_C0201-DIFF BUS_0.22UF,6.3V,20%,X6S,SA',
 VOLTAGE='6.3V',
 PART_NUMBER='SP_CH4221MEE01',
 VALUE='DIFF BUS_0.22UF',
 PRIM_FILE='./archive_libs/logical/q_cap_diffbus/chips/chips.prt';

PART_NAME
 C6598 'Q_CAP_DIFFBUS_C0201-DIFF BUS_0.22UF,6.3V,20%,X6S,SA':;

SECTION_NUMBER 1
 '@T6G_MB_LIB.T6G(SCH_1):PAGE429_I39@PURE_QUANTA.Q_CAP_DIFFBUS(CHIPS)':
 C_PATH='@t6g_mb_lib.t6g(sch_1):page429_i39@pure_quanta.q_cap_diffbus(chips)',
 P_PATH='@t6g_mb_lib.t6g(sch_1):page308_i39@pure_quanta.q_cap_diffbus(chips)',
 PATH='I39',
 DRAWING='@T6G_MB_LIB.T6G(SCH_1):PAGE429',
 PIN_NAMES_ROTATE='TRUE',
 TOLERANCE='20%',
 MATERIAL='X6S',
 PHYS_PAGE='308',
 XY='(-2475,2000)',
 ROT='2',
 VER='2',
 PACK_TYPE='C0201',
 LOCATION='C6598',
 CDS_LIB='pure_quanta',
 CDS_PART_NAME='Q_CAP_DIFFBUS_C0201-DIFF BUS_0.22UF,6.3V,20%,X6S,SA',
 VOLTAGE='6.3V',
 PART_NUMBER='SP_CH4221MEE01',
 VALUE='DIFF BUS_0.22UF',
 PRIM_FILE='./archive_libs/logical/q_cap_diffbus/chips/chips.prt';

PART_NAME
 C6599 'Q_CAP_DIFFBUS_C0201-DIFF BUS_0.22UF,6.3V,20%,X6S,SA':;

SECTION_NUMBER 1
 '@T6G_MB_LIB.T6G(SCH_1):PAGE429_I38@PURE_QUANTA.Q_CAP_DIFFBUS(CHIPS)':
 C_PATH='@t6g_mb_lib.t6g(sch_1):page429_i38@pure_quanta.q_cap_diffbus(chips)',
 P_PATH='@t6g_mb_lib.t6g(sch_1):page308_i38@pure_quanta.q_cap_diffbus(chips)',
 PATH='I38',
 DRAWING='@T6G_MB_LIB.T6G(SCH_1):PAGE429',
 PIN_NAMES_ROTATE='TRUE',
 TOLERANCE='20%',
 MATERIAL='X6S',
 PHYS_PAGE='308',
 XY='(-2475,1850)',
 ROT='2',
 VER='2',
 PACK_TYPE='C0201',
 LOCATION='C6599',
 CDS_LIB='pure_quanta',
 CDS_PART_NAME='Q_CAP_DIFFBUS_C0201-DIFF BUS_0.22UF,6.3V,20%,X6S,SA',
 VOLTAGE='6.3V',
 PART_NUMBER='SP_CH4221MEE01',
 VALUE='DIFF BUS_0.22UF',
 PRIM_FILE='./archive_libs/logical/q_cap_diffbus/chips/chips.prt';

PART_NAME
 C6600 'Q_CAP_DIFFBUS_C0201-DIFF BUS_0.22UF,6.3V,20%,X6S,SA':;

SECTION_NUMBER 1
 '@T6G_MB_LIB.T6G(SCH_1):PAGE429_I37@PURE_QUANTA.Q_CAP_DIFFBUS(CHIPS)':
 C_PATH='@t6g_mb_lib.t6g(sch_1):page429_i37@pure_quanta.q_cap_diffbus(chips)',
 P_PATH='@t6g_mb_lib.t6g(sch_1):page308_i37@pure_quanta.q_cap_diffbus(chips)',
 PATH='I37',
 DRAWING='@T6G_MB_LIB.T6G(SCH_1):PAGE429',
 PIN_NAMES_ROTATE='TRUE',
 TOLERANCE='20%',
 MATERIAL='X6S',
 PHYS_PAGE='308',
 XY='(-2475,1800)',
 ROT='2',
 VER='2',
 PACK_TYPE='C0201',
 LOCATION='C6600',
 CDS_LIB='pure_quanta',
 CDS_PART_NAME='Q_CAP_DIFFBUS_C0201-DIFF BUS_0.22UF,6.3V,20%,X6S,SA',
 VOLTAGE='6.3V',
 PART_NUMBER='SP_CH4221MEE01',
 VALUE='DIFF BUS_0.22UF',
 PRIM_FILE='./archive_libs/logical/q_cap_diffbus/chips/chips.prt';

PART_NAME
 C6601 'Q_CAP_DIFFBUS_C0201-DIFF BUS_0.22UF,6.3V,20%,X6S,SA':;

SECTION_NUMBER 1
 '@T6G_MB_LIB.T6G(SCH_1):PAGE429_I36@PURE_QUANTA.Q_CAP_DIFFBUS(CHIPS)':
 C_PATH='@t6g_mb_lib.t6g(sch_1):page429_i36@pure_quanta.q_cap_diffbus(chips)',
 P_PATH='@t6g_mb_lib.t6g(sch_1):page308_i36@pure_quanta.q_cap_diffbus(chips)',
 PATH='I36',
 DRAWING='@T6G_MB_LIB.T6G(SCH_1):PAGE429',
 PIN_NAMES_ROTATE='TRUE',
 TOLERANCE='20%',
 MATERIAL='X6S',
 PHYS_PAGE='308',
 XY='(-2475,1650)',
 ROT='2',
 VER='2',
 PACK_TYPE='C0201',
 LOCATION='C6601',
 CDS_LIB='pure_quanta',
 CDS_PART_NAME='Q_CAP_DIFFBUS_C0201-DIFF BUS_0.22UF,6.3V,20%,X6S,SA',
 VOLTAGE='6.3V',
 PART_NUMBER='SP_CH4221MEE01',
 VALUE='DIFF BUS_0.22UF',
 PRIM_FILE='./archive_libs/logical/q_cap_diffbus/chips/chips.prt';

PART_NAME
 C6602 'Q_CAP_DIFFBUS_C0201-DIFF BUS_0.22UF,6.3V,20%,X6S,SA':;

SECTION_NUMBER 1
 '@T6G_MB_LIB.T6G(SCH_1):PAGE429_I35@PURE_QUANTA.Q_CAP_DIFFBUS(CHIPS)':
 C_PATH='@t6g_mb_lib.t6g(sch_1):page429_i35@pure_quanta.q_cap_diffbus(chips)',
 P_PATH='@t6g_mb_lib.t6g(sch_1):page308_i35@pure_quanta.q_cap_diffbus(chips)',
 PATH='I35',
 DRAWING='@T6G_MB_LIB.T6G(SCH_1):PAGE429',
 PIN_NAMES_ROTATE='TRUE',
 TOLERANCE='20%',
 MATERIAL='X6S',
 PHYS_PAGE='308',
 XY='(-2475,1600)',
 ROT='2',
 VER='2',
 PACK_TYPE='C0201',
 LOCATION='C6602',
 CDS_LIB='pure_quanta',
 CDS_PART_NAME='Q_CAP_DIFFBUS_C0201-DIFF BUS_0.22UF,6.3V,20%,X6S,SA',
 VOLTAGE='6.3V',
 PART_NUMBER='SP_CH4221MEE01',
 VALUE='DIFF BUS_0.22UF',
 PRIM_FILE='./archive_libs/logical/q_cap_diffbus/chips/chips.prt';

PART_NAME
 C6603 'Q_CAP_DIFFBUS_C0201-DIFF BUS_0.22UF,6.3V,20%,X6S,SA':;

SECTION_NUMBER 1
 '@T6G_MB_LIB.T6G(SCH_1):PAGE429_I34@PURE_QUANTA.Q_CAP_DIFFBUS(CHIPS)':
 C_PATH='@t6g_mb_lib.t6g(sch_1):page429_i34@pure_quanta.q_cap_diffbus(chips)',
 P_PATH='@t6g_mb_lib.t6g(sch_1):page308_i34@pure_quanta.q_cap_diffbus(chips)',
 PATH='I34',
 DRAWING='@T6G_MB_LIB.T6G(SCH_1):PAGE429',
 PIN_NAMES_ROTATE='TRUE',
 TOLERANCE='20%',
 MATERIAL='X6S',
 PHYS_PAGE='308',
 XY='(-2475,1450)',
 ROT='2',
 VER='2',
 PACK_TYPE='C0201',
 LOCATION='C6603',
 CDS_LIB='pure_quanta',
 CDS_PART_NAME='Q_CAP_DIFFBUS_C0201-DIFF BUS_0.22UF,6.3V,20%,X6S,SA',
 VOLTAGE='6.3V',
 PART_NUMBER='SP_CH4221MEE01',
 VALUE='DIFF BUS_0.22UF',
 PRIM_FILE='./archive_libs/logical/q_cap_diffbus/chips/chips.prt';

PART_NAME
 C6604 'Q_CAP_DIFFBUS_C0201-DIFF BUS_0.22UF,6.3V,20%,X6S,SA':;

SECTION_NUMBER 1
 '@T6G_MB_LIB.T6G(SCH_1):PAGE429_I33@PURE_QUANTA.Q_CAP_DIFFBUS(CHIPS)':
 C_PATH='@t6g_mb_lib.t6g(sch_1):page429_i33@pure_quanta.q_cap_diffbus(chips)',
 P_PATH='@t6g_mb_lib.t6g(sch_1):page308_i33@pure_quanta.q_cap_diffbus(chips)',
 PATH='I33',
 DRAWING='@T6G_MB_LIB.T6G(SCH_1):PAGE429',
 PIN_NAMES_ROTATE='TRUE',
 TOLERANCE='20%',
 MATERIAL='X6S',
 PHYS_PAGE='308',
 XY='(-2475,1400)',
 ROT='2',
 VER='2',
 PACK_TYPE='C0201',
 LOCATION='C6604',
 CDS_LIB='pure_quanta',
 CDS_PART_NAME='Q_CAP_DIFFBUS_C0201-DIFF BUS_0.22UF,6.3V,20%,X6S,SA',
 VOLTAGE='6.3V',
 PART_NUMBER='SP_CH4221MEE01',
 VALUE='DIFF BUS_0.22UF',
 PRIM_FILE='./archive_libs/logical/q_cap_diffbus/chips/chips.prt';

PART_NAME
 C6605 'Q_CAP_DIFFBUS_C0201-DIFF BUS_0.22UF,6.3V,20%,X6S,SA':;

SECTION_NUMBER 1
 '@T6G_MB_LIB.T6G(SCH_1):PAGE429_I32@PURE_QUANTA.Q_CAP_DIFFBUS(CHIPS)':
 C_PATH='@t6g_mb_lib.t6g(sch_1):page429_i32@pure_quanta.q_cap_diffbus(chips)',
 P_PATH='@t6g_mb_lib.t6g(sch_1):page308_i32@pure_quanta.q_cap_diffbus(chips)',
 PATH='I32',
 DRAWING='@T6G_MB_LIB.T6G(SCH_1):PAGE429',
 PIN_NAMES_ROTATE='TRUE',
 TOLERANCE='20%',
 MATERIAL='X6S',
 PHYS_PAGE='308',
 XY='(-2475,1250)',
 ROT='2',
 VER='2',
 PACK_TYPE='C0201',
 LOCATION='C6605',
 CDS_LIB='pure_quanta',
 CDS_PART_NAME='Q_CAP_DIFFBUS_C0201-DIFF BUS_0.22UF,6.3V,20%,X6S,SA',
 VOLTAGE='6.3V',
 PART_NUMBER='SP_CH4221MEE01',
 VALUE='DIFF BUS_0.22UF',
 PRIM_FILE='./archive_libs/logical/q_cap_diffbus/chips/chips.prt';

PART_NAME
 C6606 'Q_CAP_DIFFBUS_C0201-DIFF BUS_0.22UF,6.3V,20%,X6S,SA':;

SECTION_NUMBER 1
 '@T6G_MB_LIB.T6G(SCH_1):PAGE429_I31@PURE_QUANTA.Q_CAP_DIFFBUS(CHIPS)':
 C_PATH='@t6g_mb_lib.t6g(sch_1):page429_i31@pure_quanta.q_cap_diffbus(chips)',
 P_PATH='@t6g_mb_lib.t6g(sch_1):page308_i31@pure_quanta.q_cap_diffbus(chips)',
 PATH='I31',
 DRAWING='@T6G_MB_LIB.T6G(SCH_1):PAGE429',
 PIN_NAMES_ROTATE='TRUE',
 TOLERANCE='20%',
 MATERIAL='X6S',
 PHYS_PAGE='308',
 XY='(-2475,1200)',
 ROT='2',
 VER='2',
 PACK_TYPE='C0201',
 LOCATION='C6606',
 CDS_LIB='pure_quanta',
 CDS_PART_NAME='Q_CAP_DIFFBUS_C0201-DIFF BUS_0.22UF,6.3V,20%,X6S,SA',
 VOLTAGE='6.3V',
 PART_NUMBER='SP_CH4221MEE01',
 VALUE='DIFF BUS_0.22UF',
 PRIM_FILE='./archive_libs/logical/q_cap_diffbus/chips/chips.prt';

PART_NAME
 C6607 'Q_CAP_DIFFBUS_C0201-DIFF BUS_0.22UF,6.3V,20%,X6S,SA':;

SECTION_NUMBER 1
 '@T6G_MB_LIB.T6G(SCH_1):PAGE429_I24@PURE_QUANTA.Q_CAP_DIFFBUS(CHIPS)':
 C_PATH='@t6g_mb_lib.t6g(sch_1):page429_i24@pure_quanta.q_cap_diffbus(chips)',
 P_PATH='@t6g_mb_lib.t6g(sch_1):page308_i24@pure_quanta.q_cap_diffbus(chips)',
 PATH='I24',
 DRAWING='@T6G_MB_LIB.T6G(SCH_1):PAGE429',
 PIN_NAMES_ROTATE='TRUE',
 TOLERANCE='20%',
 MATERIAL='X6S',
 PHYS_PAGE='308',
 XY='(-2475,1050)',
 ROT='2',
 VER='2',
 PACK_TYPE='C0201',
 LOCATION='C6607',
 CDS_LIB='pure_quanta',
 CDS_PART_NAME='Q_CAP_DIFFBUS_C0201-DIFF BUS_0.22UF,6.3V,20%,X6S,SA',
 VOLTAGE='6.3V',
 PART_NUMBER='SP_CH4221MEE01',
 VALUE='DIFF BUS_0.22UF',
 PRIM_FILE='./archive_libs/logical/q_cap_diffbus/chips/chips.prt';

PART_NAME
 C6608 'Q_CAP_DIFFBUS_C0201-DIFF BUS_0.22UF,6.3V,20%,X6S,SA':;

SECTION_NUMBER 1
 '@T6G_MB_LIB.T6G(SCH_1):PAGE429_I23@PURE_QUANTA.Q_CAP_DIFFBUS(CHIPS)':
 C_PATH='@t6g_mb_lib.t6g(sch_1):page429_i23@pure_quanta.q_cap_diffbus(chips)',
 P_PATH='@t6g_mb_lib.t6g(sch_1):page308_i23@pure_quanta.q_cap_diffbus(chips)',
 PATH='I23',
 DRAWING='@T6G_MB_LIB.T6G(SCH_1):PAGE429',
 PIN_NAMES_ROTATE='TRUE',
 TOLERANCE='20%',
 MATERIAL='X6S',
 PHYS_PAGE='308',
 XY='(-2475,1000)',
 ROT='2',
 VER='2',
 PACK_TYPE='C0201',
 LOCATION='C6608',
 CDS_LIB='pure_quanta',
 CDS_PART_NAME='Q_CAP_DIFFBUS_C0201-DIFF BUS_0.22UF,6.3V,20%,X6S,SA',
 VOLTAGE='6.3V',
 PART_NUMBER='SP_CH4221MEE01',
 VALUE='DIFF BUS_0.22UF',
 PRIM_FILE='./archive_libs/logical/q_cap_diffbus/chips/chips.prt';

PART_NAME
 C6609 'Q_CAP_DIFFBUS_C0201-DIFF BUS_0.22UF,6.3V,20%,X6S,SA':;

SECTION_NUMBER 1
 '@T6G_MB_LIB.T6G(SCH_1):PAGE429_I22@PURE_QUANTA.Q_CAP_DIFFBUS(CHIPS)':
 C_PATH='@t6g_mb_lib.t6g(sch_1):page429_i22@pure_quanta.q_cap_diffbus(chips)',
 P_PATH='@t6g_mb_lib.t6g(sch_1):page308_i22@pure_quanta.q_cap_diffbus(chips)',
 PATH='I22',
 DRAWING='@T6G_MB_LIB.T6G(SCH_1):PAGE429',
 PIN_NAMES_ROTATE='TRUE',
 TOLERANCE='20%',
 MATERIAL='X6S',
 PHYS_PAGE='308',
 XY='(-2475,850)',
 ROT='2',
 VER='2',
 PACK_TYPE='C0201',
 LOCATION='C6609',
 CDS_LIB='pure_quanta',
 CDS_PART_NAME='Q_CAP_DIFFBUS_C0201-DIFF BUS_0.22UF,6.3V,20%,X6S,SA',
 VOLTAGE='6.3V',
 PART_NUMBER='SP_CH4221MEE01',
 VALUE='DIFF BUS_0.22UF',
 PRIM_FILE='./archive_libs/logical/q_cap_diffbus/chips/chips.prt';

PART_NAME
 C6610 'Q_CAP_DIFFBUS_C0201-DIFF BUS_0.22UF,6.3V,20%,X6S,SA':;

SECTION_NUMBER 1
 '@T6G_MB_LIB.T6G(SCH_1):PAGE429_I21@PURE_QUANTA.Q_CAP_DIFFBUS(CHIPS)':
 C_PATH='@t6g_mb_lib.t6g(sch_1):page429_i21@pure_quanta.q_cap_diffbus(chips)',
 P_PATH='@t6g_mb_lib.t6g(sch_1):page308_i21@pure_quanta.q_cap_diffbus(chips)',
 PATH='I21',
 DRAWING='@T6G_MB_LIB.T6G(SCH_1):PAGE429',
 PIN_NAMES_ROTATE='TRUE',
 TOLERANCE='20%',
 MATERIAL='X6S',
 PHYS_PAGE='308',
 XY='(-2475,800)',
 ROT='2',
 VER='2',
 PACK_TYPE='C0201',
 LOCATION='C6610',
 CDS_LIB='pure_quanta',
 CDS_PART_NAME='Q_CAP_DIFFBUS_C0201-DIFF BUS_0.22UF,6.3V,20%,X6S,SA',
 VOLTAGE='6.3V',
 PART_NUMBER='SP_CH4221MEE01',
 VALUE='DIFF BUS_0.22UF',
 PRIM_FILE='./archive_libs/logical/q_cap_diffbus/chips/chips.prt';

PART_NAME
 C6611 'Q_CAP_DIFFBUS_C0201-DIFF BUS_0.22UF,6.3V,20%,X6S,SA':;

SECTION_NUMBER 1
 '@T6G_MB_LIB.T6G(SCH_1):PAGE429_I19@PURE_QUANTA.Q_CAP_DIFFBUS(CHIPS)':
 C_PATH='@t6g_mb_lib.t6g(sch_1):page429_i19@pure_quanta.q_cap_diffbus(chips)',
 P_PATH='@t6g_mb_lib.t6g(sch_1):page308_i19@pure_quanta.q_cap_diffbus(chips)',
 PATH='I19',
 DRAWING='@T6G_MB_LIB.T6G(SCH_1):PAGE429',
 PIN_NAMES_ROTATE='TRUE',
 TOLERANCE='20%',
 MATERIAL='X6S',
 PHYS_PAGE='308',
 XY='(-2475,650)',
 ROT='2',
 VER='2',
 PACK_TYPE='C0201',
 LOCATION='C6611',
 CDS_LIB='pure_quanta',
 CDS_PART_NAME='Q_CAP_DIFFBUS_C0201-DIFF BUS_0.22UF,6.3V,20%,X6S,SA',
 VOLTAGE='6.3V',
 PART_NUMBER='SP_CH4221MEE01',
 VALUE='DIFF BUS_0.22UF',
 PRIM_FILE='./archive_libs/logical/q_cap_diffbus/chips/chips.prt';

PART_NAME
 C6612 'Q_CAP_DIFFBUS_C0201-DIFF BUS_0.22UF,6.3V,20%,X6S,SA':;

SECTION_NUMBER 1
 '@T6G_MB_LIB.T6G(SCH_1):PAGE429_I20@PURE_QUANTA.Q_CAP_DIFFBUS(CHIPS)':
 C_PATH='@t6g_mb_lib.t6g(sch_1):page429_i20@pure_quanta.q_cap_diffbus(chips)',
 P_PATH='@t6g_mb_lib.t6g(sch_1):page308_i20@pure_quanta.q_cap_diffbus(chips)',
 PATH='I20',
 DRAWING='@T6G_MB_LIB.T6G(SCH_1):PAGE429',
 PIN_NAMES_ROTATE='TRUE',
 TOLERANCE='20%',
 MATERIAL='X6S',
 PHYS_PAGE='308',
 XY='(-2475,600)',
 ROT='2',
 VER='2',
 PACK_TYPE='C0201',
 LOCATION='C6612',
 CDS_LIB='pure_quanta',
 CDS_PART_NAME='Q_CAP_DIFFBUS_C0201-DIFF BUS_0.22UF,6.3V,20%,X6S,SA',
 VOLTAGE='6.3V',
 PART_NUMBER='SP_CH4221MEE01',
 VALUE='DIFF BUS_0.22UF',
 PRIM_FILE='./archive_libs/logical/q_cap_diffbus/chips/chips.prt';

PART_NAME
 C6613 'Q_CAP_DIFFBUS_C0201-DIFF BUS_0.22UF,6.3V,20%,X6S,SA':;

SECTION_NUMBER 1
 '@T6G_MB_LIB.T6G(SCH_1):PAGE429_I105@PURE_QUANTA.Q_CAP_DIFFBUS(CHIPS)':
 C_PATH='@t6g_mb_lib.t6g(sch_1):page429_i105@pure_quanta.q_cap_diffbus(chips)',
 P_PATH='@t6g_mb_lib.t6g(sch_1):page308_i105@pure_quanta.q_cap_diffbus(chips)',
 PATH='I105',
 DRAWING='@T6G_MB_LIB.T6G(SCH_1):PAGE429',
 PIN_NAMES_ROTATE='TRUE',
 TOLERANCE='20%',
 MATERIAL='X6S',
 PHYS_PAGE='308',
 XY='(-7075,2050)',
 ROT='2',
 VER='2',
 PACK_TYPE='C0201',
 LOCATION='C6613',
 CDS_LIB='pure_quanta',
 CDS_PART_NAME='Q_CAP_DIFFBUS_C0201-DIFF BUS_0.22UF,6.3V,20%,X6S,SA',
 VOLTAGE='6.3V',
 PART_NUMBER='SP_CH4221MEE01',
 VALUE='DIFF BUS_0.22UF',
 PRIM_FILE='./archive_libs/logical/q_cap_diffbus/chips/chips.prt';

PART_NAME
 C6614 'Q_CAP_DIFFBUS_C0201-DIFF BUS_0.22UF,6.3V,20%,X6S,SA':;

SECTION_NUMBER 1
 '@T6G_MB_LIB.T6G(SCH_1):PAGE429_I104@PURE_QUANTA.Q_CAP_DIFFBUS(CHIPS)':
 C_PATH='@t6g_mb_lib.t6g(sch_1):page429_i104@pure_quanta.q_cap_diffbus(chips)',
 P_PATH='@t6g_mb_lib.t6g(sch_1):page308_i104@pure_quanta.q_cap_diffbus(chips)',
 PATH='I104',
 DRAWING='@T6G_MB_LIB.T6G(SCH_1):PAGE429',
 PIN_NAMES_ROTATE='TRUE',
 TOLERANCE='20%',
 MATERIAL='X6S',
 PHYS_PAGE='308',
 XY='(-7075,2000)',
 ROT='2',
 VER='2',
 PACK_TYPE='C0201',
 LOCATION='C6614',
 CDS_LIB='pure_quanta',
 CDS_PART_NAME='Q_CAP_DIFFBUS_C0201-DIFF BUS_0.22UF,6.3V,20%,X6S,SA',
 VOLTAGE='6.3V',
 PART_NUMBER='SP_CH4221MEE01',
 VALUE='DIFF BUS_0.22UF',
 PRIM_FILE='./archive_libs/logical/q_cap_diffbus/chips/chips.prt';

PART_NAME
 C6615 'Q_CAP_DIFFBUS_C0201-DIFF BUS_0.22UF,6.3V,20%,X6S,SA':;

SECTION_NUMBER 1
 '@T6G_MB_LIB.T6G(SCH_1):PAGE429_I102@PURE_QUANTA.Q_CAP_DIFFBUS(CHIPS)':
 C_PATH='@t6g_mb_lib.t6g(sch_1):page429_i102@pure_quanta.q_cap_diffbus(chips)',
 P_PATH='@t6g_mb_lib.t6g(sch_1):page308_i102@pure_quanta.q_cap_diffbus(chips)',
 PATH='I102',
 DRAWING='@T6G_MB_LIB.T6G(SCH_1):PAGE429',
 PIN_NAMES_ROTATE='TRUE',
 TOLERANCE='20%',
 MATERIAL='X6S',
 PHYS_PAGE='308',
 XY='(-7075,1850)',
 ROT='2',
 VER='2',
 PACK_TYPE='C0201',
 LOCATION='C6615',
 CDS_LIB='pure_quanta',
 CDS_PART_NAME='Q_CAP_DIFFBUS_C0201-DIFF BUS_0.22UF,6.3V,20%,X6S,SA',
 VOLTAGE='6.3V',
 PART_NUMBER='SP_CH4221MEE01',
 VALUE='DIFF BUS_0.22UF',
 PRIM_FILE='./archive_libs/logical/q_cap_diffbus/chips/chips.prt';

PART_NAME
 C6616 'Q_CAP_DIFFBUS_C0201-DIFF BUS_0.22UF,6.3V,20%,X6S,SA':;

SECTION_NUMBER 1
 '@T6G_MB_LIB.T6G(SCH_1):PAGE429_I103@PURE_QUANTA.Q_CAP_DIFFBUS(CHIPS)':
 C_PATH='@t6g_mb_lib.t6g(sch_1):page429_i103@pure_quanta.q_cap_diffbus(chips)',
 P_PATH='@t6g_mb_lib.t6g(sch_1):page308_i103@pure_quanta.q_cap_diffbus(chips)',
 PATH='I103',
 DRAWING='@T6G_MB_LIB.T6G(SCH_1):PAGE429',
 PIN_NAMES_ROTATE='TRUE',
 TOLERANCE='20%',
 MATERIAL='X6S',
 PHYS_PAGE='308',
 XY='(-7075,1800)',
 ROT='2',
 VER='2',
 PACK_TYPE='C0201',
 LOCATION='C6616',
 CDS_LIB='pure_quanta',
 CDS_PART_NAME='Q_CAP_DIFFBUS_C0201-DIFF BUS_0.22UF,6.3V,20%,X6S,SA',
 VOLTAGE='6.3V',
 PART_NUMBER='SP_CH4221MEE01',
 VALUE='DIFF BUS_0.22UF',
 PRIM_FILE='./archive_libs/logical/q_cap_diffbus/chips/chips.prt';

PART_NAME
 C6617 'Q_CAP_DIFFBUS_C0201-DIFF BUS_0.22UF,6.3V,20%,X6S,SA':;

SECTION_NUMBER 1
 '@T6G_MB_LIB.T6G(SCH_1):PAGE429_I101@PURE_QUANTA.Q_CAP_DIFFBUS(CHIPS)':
 C_PATH='@t6g_mb_lib.t6g(sch_1):page429_i101@pure_quanta.q_cap_diffbus(chips)',
 P_PATH='@t6g_mb_lib.t6g(sch_1):page308_i101@pure_quanta.q_cap_diffbus(chips)',
 PATH='I101',
 DRAWING='@T6G_MB_LIB.T6G(SCH_1):PAGE429',
 PIN_NAMES_ROTATE='TRUE',
 TOLERANCE='20%',
 MATERIAL='X6S',
 PHYS_PAGE='308',
 XY='(-7075,1650)',
 ROT='2',
 VER='2',
 PACK_TYPE='C0201',
 LOCATION='C6617',
 CDS_LIB='pure_quanta',
 CDS_PART_NAME='Q_CAP_DIFFBUS_C0201-DIFF BUS_0.22UF,6.3V,20%,X6S,SA',
 VOLTAGE='6.3V',
 PART_NUMBER='SP_CH4221MEE01',
 VALUE='DIFF BUS_0.22UF',
 PRIM_FILE='./archive_libs/logical/q_cap_diffbus/chips/chips.prt';

PART_NAME
 C6618 'Q_CAP_DIFFBUS_C0201-DIFF BUS_0.22UF,6.3V,20%,X6S,SA':;

SECTION_NUMBER 1
 '@T6G_MB_LIB.T6G(SCH_1):PAGE429_I99@PURE_QUANTA.Q_CAP_DIFFBUS(CHIPS)':
 C_PATH='@t6g_mb_lib.t6g(sch_1):page429_i99@pure_quanta.q_cap_diffbus(chips)',
 P_PATH='@t6g_mb_lib.t6g(sch_1):page308_i99@pure_quanta.q_cap_diffbus(chips)',
 PATH='I99',
 DRAWING='@T6G_MB_LIB.T6G(SCH_1):PAGE429',
 PIN_NAMES_ROTATE='TRUE',
 TOLERANCE='20%',
 MATERIAL='X6S',
 PHYS_PAGE='308',
 XY='(-7075,1600)',
 ROT='2',
 VER='2',
 PACK_TYPE='C0201',
 LOCATION='C6618',
 CDS_LIB='pure_quanta',
 CDS_PART_NAME='Q_CAP_DIFFBUS_C0201-DIFF BUS_0.22UF,6.3V,20%,X6S,SA',
 VOLTAGE='6.3V',
 PART_NUMBER='SP_CH4221MEE01',
 VALUE='DIFF BUS_0.22UF',
 PRIM_FILE='./archive_libs/logical/q_cap_diffbus/chips/chips.prt';

PART_NAME
 C6619 'Q_CAP_DIFFBUS_C0201-DIFF BUS_0.22UF,6.3V,20%,X6S,SA':;

SECTION_NUMBER 1
 '@T6G_MB_LIB.T6G(SCH_1):PAGE429_I100@PURE_QUANTA.Q_CAP_DIFFBUS(CHIPS)':
 C_PATH='@t6g_mb_lib.t6g(sch_1):page429_i100@pure_quanta.q_cap_diffbus(chips)',
 P_PATH='@t6g_mb_lib.t6g(sch_1):page308_i100@pure_quanta.q_cap_diffbus(chips)',
 PATH='I100',
 DRAWING='@T6G_MB_LIB.T6G(SCH_1):PAGE429',
 PIN_NAMES_ROTATE='TRUE',
 TOLERANCE='20%',
 MATERIAL='X6S',
 PHYS_PAGE='308',
 XY='(-7075,1450)',
 ROT='2',
 VER='2',
 PACK_TYPE='C0201',
 LOCATION='C6619',
 CDS_LIB='pure_quanta',
 CDS_PART_NAME='Q_CAP_DIFFBUS_C0201-DIFF BUS_0.22UF,6.3V,20%,X6S,SA',
 VOLTAGE='6.3V',
 PART_NUMBER='SP_CH4221MEE01',
 VALUE='DIFF BUS_0.22UF',
 PRIM_FILE='./archive_libs/logical/q_cap_diffbus/chips/chips.prt';

PART_NAME
 C6620 'Q_CAP_DIFFBUS_C0201-DIFF BUS_0.22UF,6.3V,20%,X6S,SA':;

SECTION_NUMBER 1
 '@T6G_MB_LIB.T6G(SCH_1):PAGE429_I98@PURE_QUANTA.Q_CAP_DIFFBUS(CHIPS)':
 C_PATH='@t6g_mb_lib.t6g(sch_1):page429_i98@pure_quanta.q_cap_diffbus(chips)',
 P_PATH='@t6g_mb_lib.t6g(sch_1):page308_i98@pure_quanta.q_cap_diffbus(chips)',
 PATH='I98',
 DRAWING='@T6G_MB_LIB.T6G(SCH_1):PAGE429',
 PIN_NAMES_ROTATE='TRUE',
 TOLERANCE='20%',
 MATERIAL='X6S',
 PHYS_PAGE='308',
 XY='(-7075,1400)',
 ROT='2',
 VER='2',
 PACK_TYPE='C0201',
 LOCATION='C6620',
 CDS_LIB='pure_quanta',
 CDS_PART_NAME='Q_CAP_DIFFBUS_C0201-DIFF BUS_0.22UF,6.3V,20%,X6S,SA',
 VOLTAGE='6.3V',
 PART_NUMBER='SP_CH4221MEE01',
 VALUE='DIFF BUS_0.22UF',
 PRIM_FILE='./archive_libs/logical/q_cap_diffbus/chips/chips.prt';

PART_NAME
 C6621 'Q_CAP_DIFFBUS_C0201-DIFF BUS_0.22UF,6.3V,20%,X6S,SA':;

SECTION_NUMBER 1
 '@T6G_MB_LIB.T6G(SCH_1):PAGE429_I96@PURE_QUANTA.Q_CAP_DIFFBUS(CHIPS)':
 C_PATH='@t6g_mb_lib.t6g(sch_1):page429_i96@pure_quanta.q_cap_diffbus(chips)',
 P_PATH='@t6g_mb_lib.t6g(sch_1):page308_i96@pure_quanta.q_cap_diffbus(chips)',
 PATH='I96',
 DRAWING='@T6G_MB_LIB.T6G(SCH_1):PAGE429',
 PIN_NAMES_ROTATE='TRUE',
 TOLERANCE='20%',
 MATERIAL='X6S',
 PHYS_PAGE='308',
 XY='(-7075,1250)',
 ROT='2',
 VER='2',
 PACK_TYPE='C0201',
 LOCATION='C6621',
 CDS_LIB='pure_quanta',
 CDS_PART_NAME='Q_CAP_DIFFBUS_C0201-DIFF BUS_0.22UF,6.3V,20%,X6S,SA',
 VOLTAGE='6.3V',
 PART_NUMBER='SP_CH4221MEE01',
 VALUE='DIFF BUS_0.22UF',
 PRIM_FILE='./archive_libs/logical/q_cap_diffbus/chips/chips.prt';

PART_NAME
 C6622 'Q_CAP_DIFFBUS_C0201-DIFF BUS_0.22UF,6.3V,20%,X6S,SA':;

SECTION_NUMBER 1
 '@T6G_MB_LIB.T6G(SCH_1):PAGE429_I97@PURE_QUANTA.Q_CAP_DIFFBUS(CHIPS)':
 C_PATH='@t6g_mb_lib.t6g(sch_1):page429_i97@pure_quanta.q_cap_diffbus(chips)',
 P_PATH='@t6g_mb_lib.t6g(sch_1):page308_i97@pure_quanta.q_cap_diffbus(chips)',
 PATH='I97',
 DRAWING='@T6G_MB_LIB.T6G(SCH_1):PAGE429',
 PIN_NAMES_ROTATE='TRUE',
 TOLERANCE='20%',
 MATERIAL='X6S',
 PHYS_PAGE='308',
 XY='(-7075,1200)',
 ROT='2',
 VER='2',
 PACK_TYPE='C0201',
 LOCATION='C6622',
 CDS_LIB='pure_quanta',
 CDS_PART_NAME='Q_CAP_DIFFBUS_C0201-DIFF BUS_0.22UF,6.3V,20%,X6S,SA',
 VOLTAGE='6.3V',
 PART_NUMBER='SP_CH4221MEE01',
 VALUE='DIFF BUS_0.22UF',
 PRIM_FILE='./archive_libs/logical/q_cap_diffbus/chips/chips.prt';

PART_NAME
 C6623 'Q_CAP_DIFFBUS_C0201-DIFF BUS_0.22UF,6.3V,20%,X6S,SA':;

SECTION_NUMBER 1
 '@T6G_MB_LIB.T6G(SCH_1):PAGE429_I94@PURE_QUANTA.Q_CAP_DIFFBUS(CHIPS)':
 C_PATH='@t6g_mb_lib.t6g(sch_1):page429_i94@pure_quanta.q_cap_diffbus(chips)',
 P_PATH='@t6g_mb_lib.t6g(sch_1):page308_i94@pure_quanta.q_cap_diffbus(chips)',
 PATH='I94',
 DRAWING='@T6G_MB_LIB.T6G(SCH_1):PAGE429',
 PIN_NAMES_ROTATE='TRUE',
 TOLERANCE='20%',
 MATERIAL='X6S',
 PHYS_PAGE='308',
 XY='(-7075,1050)',
 ROT='2',
 VER='2',
 PACK_TYPE='C0201',
 LOCATION='C6623',
 CDS_LIB='pure_quanta',
 CDS_PART_NAME='Q_CAP_DIFFBUS_C0201-DIFF BUS_0.22UF,6.3V,20%,X6S,SA',
 VOLTAGE='6.3V',
 PART_NUMBER='SP_CH4221MEE01',
 VALUE='DIFF BUS_0.22UF',
 PRIM_FILE='./archive_libs/logical/q_cap_diffbus/chips/chips.prt';

PART_NAME
 C6624 'Q_CAP_DIFFBUS_C0201-DIFF BUS_0.22UF,6.3V,20%,X6S,SA':;

SECTION_NUMBER 1
 '@T6G_MB_LIB.T6G(SCH_1):PAGE429_I95@PURE_QUANTA.Q_CAP_DIFFBUS(CHIPS)':
 C_PATH='@t6g_mb_lib.t6g(sch_1):page429_i95@pure_quanta.q_cap_diffbus(chips)',
 P_PATH='@t6g_mb_lib.t6g(sch_1):page308_i95@pure_quanta.q_cap_diffbus(chips)',
 PATH='I95',
 DRAWING='@T6G_MB_LIB.T6G(SCH_1):PAGE429',
 PIN_NAMES_ROTATE='TRUE',
 TOLERANCE='20%',
 MATERIAL='X6S',
 PHYS_PAGE='308',
 XY='(-7075,1000)',
 ROT='2',
 VER='2',
 PACK_TYPE='C0201',
 LOCATION='C6624',
 CDS_LIB='pure_quanta',
 CDS_PART_NAME='Q_CAP_DIFFBUS_C0201-DIFF BUS_0.22UF,6.3V,20%,X6S,SA',
 VOLTAGE='6.3V',
 PART_NUMBER='SP_CH4221MEE01',
 VALUE='DIFF BUS_0.22UF',
 PRIM_FILE='./archive_libs/logical/q_cap_diffbus/chips/chips.prt';

PART_NAME
 C6625 'Q_CAP_DIFFBUS_C0201-DIFF BUS_0.22UF,6.3V,20%,X6S,SA':;

SECTION_NUMBER 1
 '@T6G_MB_LIB.T6G(SCH_1):PAGE429_I91@PURE_QUANTA.Q_CAP_DIFFBUS(CHIPS)':
 C_PATH='@t6g_mb_lib.t6g(sch_1):page429_i91@pure_quanta.q_cap_diffbus(chips)',
 P_PATH='@t6g_mb_lib.t6g(sch_1):page308_i91@pure_quanta.q_cap_diffbus(chips)',
 PATH='I91',
 DRAWING='@T6G_MB_LIB.T6G(SCH_1):PAGE429',
 PIN_NAMES_ROTATE='TRUE',
 TOLERANCE='20%',
 MATERIAL='X6S',
 PHYS_PAGE='308',
 XY='(-7075,850)',
 ROT='2',
 VER='2',
 PACK_TYPE='C0201',
 LOCATION='C6625',
 CDS_LIB='pure_quanta',
 CDS_PART_NAME='Q_CAP_DIFFBUS_C0201-DIFF BUS_0.22UF,6.3V,20%,X6S,SA',
 VOLTAGE='6.3V',
 PART_NUMBER='SP_CH4221MEE01',
 VALUE='DIFF BUS_0.22UF',
 PRIM_FILE='./archive_libs/logical/q_cap_diffbus/chips/chips.prt';

PART_NAME
 C6626 'Q_CAP_DIFFBUS_C0201-DIFF BUS_0.22UF,6.3V,20%,X6S,SA':;

SECTION_NUMBER 1
 '@T6G_MB_LIB.T6G(SCH_1):PAGE429_I92@PURE_QUANTA.Q_CAP_DIFFBUS(CHIPS)':
 C_PATH='@t6g_mb_lib.t6g(sch_1):page429_i92@pure_quanta.q_cap_diffbus(chips)',
 P_PATH='@t6g_mb_lib.t6g(sch_1):page308_i92@pure_quanta.q_cap_diffbus(chips)',
 PATH='I92',
 DRAWING='@T6G_MB_LIB.T6G(SCH_1):PAGE429',
 PIN_NAMES_ROTATE='TRUE',
 TOLERANCE='20%',
 MATERIAL='X6S',
 PHYS_PAGE='308',
 XY='(-7075,800)',
 ROT='2',
 VER='2',
 PACK_TYPE='C0201',
 LOCATION='C6626',
 CDS_LIB='pure_quanta',
 CDS_PART_NAME='Q_CAP_DIFFBUS_C0201-DIFF BUS_0.22UF,6.3V,20%,X6S,SA',
 VOLTAGE='6.3V',
 PART_NUMBER='SP_CH4221MEE01',
 VALUE='DIFF BUS_0.22UF',
 PRIM_FILE='./archive_libs/logical/q_cap_diffbus/chips/chips.prt';

PART_NAME
 C6627 'Q_CAP_DIFFBUS_C0201-DIFF BUS_0.22UF,6.3V,20%,X6S,SA':;

SECTION_NUMBER 1
 '@T6G_MB_LIB.T6G(SCH_1):PAGE429_I93@PURE_QUANTA.Q_CAP_DIFFBUS(CHIPS)':
 C_PATH='@t6g_mb_lib.t6g(sch_1):page429_i93@pure_quanta.q_cap_diffbus(chips)',
 P_PATH='@t6g_mb_lib.t6g(sch_1):page308_i93@pure_quanta.q_cap_diffbus(chips)',
 PATH='I93',
 DRAWING='@T6G_MB_LIB.T6G(SCH_1):PAGE429',
 PIN_NAMES_ROTATE='TRUE',
 TOLERANCE='20%',
 MATERIAL='X6S',
 PHYS_PAGE='308',
 XY='(-7075,650)',
 ROT='2',
 VER='2',
 PACK_TYPE='C0201',
 LOCATION='C6627',
 CDS_LIB='pure_quanta',
 CDS_PART_NAME='Q_CAP_DIFFBUS_C0201-DIFF BUS_0.22UF,6.3V,20%,X6S,SA',
 VOLTAGE='6.3V',
 PART_NUMBER='SP_CH4221MEE01',
 VALUE='DIFF BUS_0.22UF',
 PRIM_FILE='./archive_libs/logical/q_cap_diffbus/chips/chips.prt';

PART_NAME
 C6628 'Q_CAP_DIFFBUS_C0201-DIFF BUS_0.22UF,6.3V,20%,X6S,SA':;

SECTION_NUMBER 1
 '@T6G_MB_LIB.T6G(SCH_1):PAGE429_I90@PURE_QUANTA.Q_CAP_DIFFBUS(CHIPS)':
 C_PATH='@t6g_mb_lib.t6g(sch_1):page429_i90@pure_quanta.q_cap_diffbus(chips)',
 P_PATH='@t6g_mb_lib.t6g(sch_1):page308_i90@pure_quanta.q_cap_diffbus(chips)',
 PATH='I90',
 DRAWING='@T6G_MB_LIB.T6G(SCH_1):PAGE429',
 PIN_NAMES_ROTATE='TRUE',
 TOLERANCE='20%',
 MATERIAL='X6S',
 PHYS_PAGE='308',
 XY='(-7075,600)',
 ROT='2',
 VER='2',
 PACK_TYPE='C0201',
 LOCATION='C6628',
 CDS_LIB='pure_quanta',
 CDS_PART_NAME='Q_CAP_DIFFBUS_C0201-DIFF BUS_0.22UF,6.3V,20%,X6S,SA',
 VOLTAGE='6.3V',
 PART_NUMBER='SP_CH4221MEE01',
 VALUE='DIFF BUS_0.22UF',
 PRIM_FILE='./archive_libs/logical/q_cap_diffbus/chips/chips.prt';

PART_NAME
 C6629 'Q_CAP_DIFFBUS_C0201-DIFF BUS_0.22UF,6.3V,20%,X6S,SA':;

SECTION_NUMBER 1
 '@T6G_MB_LIB.T6G(SCH_1):PAGE439_I46@PURE_QUANTA.Q_CAP_DIFFBUS(CHIPS)':
 C_PATH='@t6g_mb_lib.t6g(sch_1):page439_i46@pure_quanta.q_cap_diffbus(chips)',
 P_PATH='@t6g_mb_lib.t6g(sch_1):page319_i46@pure_quanta.q_cap_diffbus(chips)',
 PATH='I46',
 DRAWING='@T6G_MB_LIB.T6G(SCH_1):PAGE439',
 PIN_NAMES_ROTATE='TRUE',
 TOLERANCE='20%',
 MATERIAL='X6S',
 PHYS_PAGE='319',
 XY='(-2350,2025)',
 ROT='2',
 VER='2',
 PACK_TYPE='C0201',
 LOCATION='C6629',
 CDS_LIB='pure_quanta',
 CDS_PART_NAME='Q_CAP_DIFFBUS_C0201-DIFF BUS_0.22UF,6.3V,20%,X6S,SA',
 VOLTAGE='6.3V',
 PART_NUMBER='SP_CH4221MEE01',
 VALUE='DIFF BUS_0.22UF',
 PRIM_FILE='./archive_libs/logical/q_cap_diffbus/chips/chips.prt';

PART_NAME
 C6630 'Q_CAP_DIFFBUS_C0201-DIFF BUS_0.22UF,6.3V,20%,X6S,SA':;

SECTION_NUMBER 1
 '@T6G_MB_LIB.T6G(SCH_1):PAGE439_I47@PURE_QUANTA.Q_CAP_DIFFBUS(CHIPS)':
 C_PATH='@t6g_mb_lib.t6g(sch_1):page439_i47@pure_quanta.q_cap_diffbus(chips)',
 P_PATH='@t6g_mb_lib.t6g(sch_1):page319_i47@pure_quanta.q_cap_diffbus(chips)',
 PATH='I47',
 DRAWING='@T6G_MB_LIB.T6G(SCH_1):PAGE439',
 PIN_NAMES_ROTATE='TRUE',
 TOLERANCE='20%',
 MATERIAL='X6S',
 PHYS_PAGE='319',
 XY='(-2350,1975)',
 ROT='2',
 VER='2',
 PACK_TYPE='C0201',
 LOCATION='C6630',
 CDS_LIB='pure_quanta',
 CDS_PART_NAME='Q_CAP_DIFFBUS_C0201-DIFF BUS_0.22UF,6.3V,20%,X6S,SA',
 VOLTAGE='6.3V',
 PART_NUMBER='SP_CH4221MEE01',
 VALUE='DIFF BUS_0.22UF',
 PRIM_FILE='./archive_libs/logical/q_cap_diffbus/chips/chips.prt';

PART_NAME
 C6631 'Q_CAP_DIFFBUS_C0201-DIFF BUS_0.22UF,6.3V,20%,X6S,SA':;

SECTION_NUMBER 1
 '@T6G_MB_LIB.T6G(SCH_1):PAGE439_I45@PURE_QUANTA.Q_CAP_DIFFBUS(CHIPS)':
 C_PATH='@t6g_mb_lib.t6g(sch_1):page439_i45@pure_quanta.q_cap_diffbus(chips)',
 P_PATH='@t6g_mb_lib.t6g(sch_1):page319_i45@pure_quanta.q_cap_diffbus(chips)',
 PATH='I45',
 DRAWING='@T6G_MB_LIB.T6G(SCH_1):PAGE439',
 PIN_NAMES_ROTATE='TRUE',
 TOLERANCE='20%',
 MATERIAL='X6S',
 PHYS_PAGE='319',
 XY='(-2350,1825)',
 ROT='2',
 VER='2',
 PACK_TYPE='C0201',
 LOCATION='C6631',
 CDS_LIB='pure_quanta',
 CDS_PART_NAME='Q_CAP_DIFFBUS_C0201-DIFF BUS_0.22UF,6.3V,20%,X6S,SA',
 VOLTAGE='6.3V',
 PART_NUMBER='SP_CH4221MEE01',
 VALUE='DIFF BUS_0.22UF',
 PRIM_FILE='./archive_libs/logical/q_cap_diffbus/chips/chips.prt';

PART_NAME
 C6632 'Q_CAP_DIFFBUS_C0201-DIFF BUS_0.22UF,6.3V,20%,X6S,SA':;

SECTION_NUMBER 1
 '@T6G_MB_LIB.T6G(SCH_1):PAGE439_I44@PURE_QUANTA.Q_CAP_DIFFBUS(CHIPS)':
 C_PATH='@t6g_mb_lib.t6g(sch_1):page439_i44@pure_quanta.q_cap_diffbus(chips)',
 P_PATH='@t6g_mb_lib.t6g(sch_1):page319_i44@pure_quanta.q_cap_diffbus(chips)',
 PATH='I44',
 DRAWING='@T6G_MB_LIB.T6G(SCH_1):PAGE439',
 PIN_NAMES_ROTATE='TRUE',
 TOLERANCE='20%',
 MATERIAL='X6S',
 PHYS_PAGE='319',
 XY='(-2350,1775)',
 ROT='2',
 VER='2',
 PACK_TYPE='C0201',
 LOCATION='C6632',
 CDS_LIB='pure_quanta',
 CDS_PART_NAME='Q_CAP_DIFFBUS_C0201-DIFF BUS_0.22UF,6.3V,20%,X6S,SA',
 VOLTAGE='6.3V',
 PART_NUMBER='SP_CH4221MEE01',
 VALUE='DIFF BUS_0.22UF',
 PRIM_FILE='./archive_libs/logical/q_cap_diffbus/chips/chips.prt';

PART_NAME
 C6633 'Q_CAP_DIFFBUS_C0201-DIFF BUS_0.22UF,6.3V,20%,X6S,SA':;

SECTION_NUMBER 1
 '@T6G_MB_LIB.T6G(SCH_1):PAGE439_I27@PURE_QUANTA.Q_CAP_DIFFBUS(CHIPS)':
 C_PATH='@t6g_mb_lib.t6g(sch_1):page439_i27@pure_quanta.q_cap_diffbus(chips)',
 P_PATH='@t6g_mb_lib.t6g(sch_1):page319_i27@pure_quanta.q_cap_diffbus(chips)',
 PATH='I27',
 DRAWING='@T6G_MB_LIB.T6G(SCH_1):PAGE439',
 PIN_NAMES_ROTATE='TRUE',
 TOLERANCE='20%',
 MATERIAL='X6S',
 PHYS_PAGE='319',
 XY='(-2350,1625)',
 ROT='2',
 VER='2',
 PACK_TYPE='C0201',
 LOCATION='C6633',
 CDS_LIB='pure_quanta',
 CDS_PART_NAME='Q_CAP_DIFFBUS_C0201-DIFF BUS_0.22UF,6.3V,20%,X6S,SA',
 VOLTAGE='6.3V',
 PART_NUMBER='SP_CH4221MEE01',
 VALUE='DIFF BUS_0.22UF',
 PRIM_FILE='./archive_libs/logical/q_cap_diffbus/chips/chips.prt';

PART_NAME
 C6634 'Q_CAP_DIFFBUS_C0201-DIFF BUS_0.22UF,6.3V,20%,X6S,SA':;

SECTION_NUMBER 1
 '@T6G_MB_LIB.T6G(SCH_1):PAGE439_I26@PURE_QUANTA.Q_CAP_DIFFBUS(CHIPS)':
 C_PATH='@t6g_mb_lib.t6g(sch_1):page439_i26@pure_quanta.q_cap_diffbus(chips)',
 P_PATH='@t6g_mb_lib.t6g(sch_1):page319_i26@pure_quanta.q_cap_diffbus(chips)',
 PATH='I26',
 DRAWING='@T6G_MB_LIB.T6G(SCH_1):PAGE439',
 PIN_NAMES_ROTATE='TRUE',
 TOLERANCE='20%',
 MATERIAL='X6S',
 PHYS_PAGE='319',
 XY='(-2350,1575)',
 ROT='2',
 VER='2',
 PACK_TYPE='C0201',
 LOCATION='C6634',
 CDS_LIB='pure_quanta',
 CDS_PART_NAME='Q_CAP_DIFFBUS_C0201-DIFF BUS_0.22UF,6.3V,20%,X6S,SA',
 VOLTAGE='6.3V',
 PART_NUMBER='SP_CH4221MEE01',
 VALUE='DIFF BUS_0.22UF',
 PRIM_FILE='./archive_libs/logical/q_cap_diffbus/chips/chips.prt';

PART_NAME
 C6635 'Q_CAP_DIFFBUS_C0201-DIFF BUS_0.22UF,6.3V,20%,X6S,SA':;

SECTION_NUMBER 1
 '@T6G_MB_LIB.T6G(SCH_1):PAGE439_I25@PURE_QUANTA.Q_CAP_DIFFBUS(CHIPS)':
 C_PATH='@t6g_mb_lib.t6g(sch_1):page439_i25@pure_quanta.q_cap_diffbus(chips)',
 P_PATH='@t6g_mb_lib.t6g(sch_1):page319_i25@pure_quanta.q_cap_diffbus(chips)',
 PATH='I25',
 DRAWING='@T6G_MB_LIB.T6G(SCH_1):PAGE439',
 PIN_NAMES_ROTATE='TRUE',
 TOLERANCE='20%',
 MATERIAL='X6S',
 PHYS_PAGE='319',
 XY='(-2350,1425)',
 ROT='2',
 VER='2',
 PACK_TYPE='C0201',
 LOCATION='C6635',
 CDS_LIB='pure_quanta',
 CDS_PART_NAME='Q_CAP_DIFFBUS_C0201-DIFF BUS_0.22UF,6.3V,20%,X6S,SA',
 VOLTAGE='6.3V',
 PART_NUMBER='SP_CH4221MEE01',
 VALUE='DIFF BUS_0.22UF',
 PRIM_FILE='./archive_libs/logical/q_cap_diffbus/chips/chips.prt';

PART_NAME
 C6636 'Q_CAP_DIFFBUS_C0201-DIFF BUS_0.22UF,6.3V,20%,X6S,SA':;

SECTION_NUMBER 1
 '@T6G_MB_LIB.T6G(SCH_1):PAGE439_I24@PURE_QUANTA.Q_CAP_DIFFBUS(CHIPS)':
 C_PATH='@t6g_mb_lib.t6g(sch_1):page439_i24@pure_quanta.q_cap_diffbus(chips)',
 P_PATH='@t6g_mb_lib.t6g(sch_1):page319_i24@pure_quanta.q_cap_diffbus(chips)',
 PATH='I24',
 DRAWING='@T6G_MB_LIB.T6G(SCH_1):PAGE439',
 PIN_NAMES_ROTATE='TRUE',
 TOLERANCE='20%',
 MATERIAL='X6S',
 PHYS_PAGE='319',
 XY='(-2350,1375)',
 ROT='2',
 VER='2',
 PACK_TYPE='C0201',
 LOCATION='C6636',
 CDS_LIB='pure_quanta',
 CDS_PART_NAME='Q_CAP_DIFFBUS_C0201-DIFF BUS_0.22UF,6.3V,20%,X6S,SA',
 VOLTAGE='6.3V',
 PART_NUMBER='SP_CH4221MEE01',
 VALUE='DIFF BUS_0.22UF',
 PRIM_FILE='./archive_libs/logical/q_cap_diffbus/chips/chips.prt';

PART_NAME
 C6637 'Q_CAP_DIFFBUS_C0201-DIFF BUS_0.22UF,6.3V,20%,X6S,SA':;

SECTION_NUMBER 1
 '@T6G_MB_LIB.T6G(SCH_1):PAGE439_I22@PURE_QUANTA.Q_CAP_DIFFBUS(CHIPS)':
 C_PATH='@t6g_mb_lib.t6g(sch_1):page439_i22@pure_quanta.q_cap_diffbus(chips)',
 P_PATH='@t6g_mb_lib.t6g(sch_1):page319_i22@pure_quanta.q_cap_diffbus(chips)',
 PATH='I22',
 DRAWING='@T6G_MB_LIB.T6G(SCH_1):PAGE439',
 PIN_NAMES_ROTATE='TRUE',
 TOLERANCE='20%',
 MATERIAL='X6S',
 PHYS_PAGE='319',
 XY='(-2350,1225)',
 ROT='2',
 VER='2',
 PACK_TYPE='C0201',
 LOCATION='C6637',
 CDS_LIB='pure_quanta',
 CDS_PART_NAME='Q_CAP_DIFFBUS_C0201-DIFF BUS_0.22UF,6.3V,20%,X6S,SA',
 VOLTAGE='6.3V',
 PART_NUMBER='SP_CH4221MEE01',
 VALUE='DIFF BUS_0.22UF',
 PRIM_FILE='./archive_libs/logical/q_cap_diffbus/chips/chips.prt';

PART_NAME
 C6638 'Q_CAP_DIFFBUS_C0201-DIFF BUS_0.22UF,6.3V,20%,X6S,SA':;

SECTION_NUMBER 1
 '@T6G_MB_LIB.T6G(SCH_1):PAGE439_I23@PURE_QUANTA.Q_CAP_DIFFBUS(CHIPS)':
 C_PATH='@t6g_mb_lib.t6g(sch_1):page439_i23@pure_quanta.q_cap_diffbus(chips)',
 P_PATH='@t6g_mb_lib.t6g(sch_1):page319_i23@pure_quanta.q_cap_diffbus(chips)',
 PATH='I23',
 DRAWING='@T6G_MB_LIB.T6G(SCH_1):PAGE439',
 PIN_NAMES_ROTATE='TRUE',
 TOLERANCE='20%',
 MATERIAL='X6S',
 PHYS_PAGE='319',
 XY='(-2350,1175)',
 ROT='2',
 VER='2',
 PACK_TYPE='C0201',
 LOCATION='C6638',
 CDS_LIB='pure_quanta',
 CDS_PART_NAME='Q_CAP_DIFFBUS_C0201-DIFF BUS_0.22UF,6.3V,20%,X6S,SA',
 VOLTAGE='6.3V',
 PART_NUMBER='SP_CH4221MEE01',
 VALUE='DIFF BUS_0.22UF',
 PRIM_FILE='./archive_libs/logical/q_cap_diffbus/chips/chips.prt';

PART_NAME
 C6639 'Q_CAP_DIFFBUS_C0201-DIFF BUS_0.22UF,6.3V,20%,X6S,SA':;

SECTION_NUMBER 1
 '@T6G_MB_LIB.T6G(SCH_1):PAGE439_I20@PURE_QUANTA.Q_CAP_DIFFBUS(CHIPS)':
 C_PATH='@t6g_mb_lib.t6g(sch_1):page439_i20@pure_quanta.q_cap_diffbus(chips)',
 P_PATH='@t6g_mb_lib.t6g(sch_1):page319_i20@pure_quanta.q_cap_diffbus(chips)',
 PATH='I20',
 DRAWING='@T6G_MB_LIB.T6G(SCH_1):PAGE439',
 PIN_NAMES_ROTATE='TRUE',
 TOLERANCE='20%',
 MATERIAL='X6S',
 PHYS_PAGE='319',
 XY='(-2350,1025)',
 ROT='2',
 VER='2',
 PACK_TYPE='C0201',
 LOCATION='C6639',
 CDS_LIB='pure_quanta',
 CDS_PART_NAME='Q_CAP_DIFFBUS_C0201-DIFF BUS_0.22UF,6.3V,20%,X6S,SA',
 VOLTAGE='6.3V',
 PART_NUMBER='SP_CH4221MEE01',
 VALUE='DIFF BUS_0.22UF',
 PRIM_FILE='./archive_libs/logical/q_cap_diffbus/chips/chips.prt';

PART_NAME
 C6640 'Q_CAP_DIFFBUS_C0201-DIFF BUS_0.22UF,6.3V,20%,X6S,SA':;

SECTION_NUMBER 1
 '@T6G_MB_LIB.T6G(SCH_1):PAGE439_I21@PURE_QUANTA.Q_CAP_DIFFBUS(CHIPS)':
 C_PATH='@t6g_mb_lib.t6g(sch_1):page439_i21@pure_quanta.q_cap_diffbus(chips)',
 P_PATH='@t6g_mb_lib.t6g(sch_1):page319_i21@pure_quanta.q_cap_diffbus(chips)',
 PATH='I21',
 DRAWING='@T6G_MB_LIB.T6G(SCH_1):PAGE439',
 PIN_NAMES_ROTATE='TRUE',
 TOLERANCE='20%',
 MATERIAL='X6S',
 PHYS_PAGE='319',
 XY='(-2350,975)',
 ROT='2',
 VER='2',
 PACK_TYPE='C0201',
 LOCATION='C6640',
 CDS_LIB='pure_quanta',
 CDS_PART_NAME='Q_CAP_DIFFBUS_C0201-DIFF BUS_0.22UF,6.3V,20%,X6S,SA',
 VOLTAGE='6.3V',
 PART_NUMBER='SP_CH4221MEE01',
 VALUE='DIFF BUS_0.22UF',
 PRIM_FILE='./archive_libs/logical/q_cap_diffbus/chips/chips.prt';

PART_NAME
 C6641 'Q_CAP_DIFFBUS_C0201-DIFF BUS_0.22UF,6.3V,20%,X6S,SA':;

SECTION_NUMBER 1
 '@T6G_MB_LIB.T6G(SCH_1):PAGE439_I18@PURE_QUANTA.Q_CAP_DIFFBUS(CHIPS)':
 C_PATH='@t6g_mb_lib.t6g(sch_1):page439_i18@pure_quanta.q_cap_diffbus(chips)',
 P_PATH='@t6g_mb_lib.t6g(sch_1):page319_i18@pure_quanta.q_cap_diffbus(chips)',
 PATH='I18',
 DRAWING='@T6G_MB_LIB.T6G(SCH_1):PAGE439',
 PIN_NAMES_ROTATE='TRUE',
 TOLERANCE='20%',
 MATERIAL='X6S',
 PHYS_PAGE='319',
 XY='(-2350,825)',
 ROT='2',
 VER='2',
 PACK_TYPE='C0201',
 LOCATION='C6641',
 CDS_LIB='pure_quanta',
 CDS_PART_NAME='Q_CAP_DIFFBUS_C0201-DIFF BUS_0.22UF,6.3V,20%,X6S,SA',
 VOLTAGE='6.3V',
 PART_NUMBER='SP_CH4221MEE01',
 VALUE='DIFF BUS_0.22UF',
 PRIM_FILE='./archive_libs/logical/q_cap_diffbus/chips/chips.prt';

PART_NAME
 C6642 'Q_CAP_DIFFBUS_C0201-DIFF BUS_0.22UF,6.3V,20%,X6S,SA':;

SECTION_NUMBER 1
 '@T6G_MB_LIB.T6G(SCH_1):PAGE439_I19@PURE_QUANTA.Q_CAP_DIFFBUS(CHIPS)':
 C_PATH='@t6g_mb_lib.t6g(sch_1):page439_i19@pure_quanta.q_cap_diffbus(chips)',
 P_PATH='@t6g_mb_lib.t6g(sch_1):page319_i19@pure_quanta.q_cap_diffbus(chips)',
 PATH='I19',
 DRAWING='@T6G_MB_LIB.T6G(SCH_1):PAGE439',
 PIN_NAMES_ROTATE='TRUE',
 TOLERANCE='20%',
 MATERIAL='X6S',
 PHYS_PAGE='319',
 XY='(-2350,775)',
 ROT='2',
 VER='2',
 PACK_TYPE='C0201',
 LOCATION='C6642',
 CDS_LIB='pure_quanta',
 CDS_PART_NAME='Q_CAP_DIFFBUS_C0201-DIFF BUS_0.22UF,6.3V,20%,X6S,SA',
 VOLTAGE='6.3V',
 PART_NUMBER='SP_CH4221MEE01',
 VALUE='DIFF BUS_0.22UF',
 PRIM_FILE='./archive_libs/logical/q_cap_diffbus/chips/chips.prt';

PART_NAME
 C6643 'Q_CAP_DIFFBUS_C0201-DIFF BUS_0.22UF,6.3V,20%,X6S,SA':;

SECTION_NUMBER 1
 '@T6G_MB_LIB.T6G(SCH_1):PAGE439_I16@PURE_QUANTA.Q_CAP_DIFFBUS(CHIPS)':
 C_PATH='@t6g_mb_lib.t6g(sch_1):page439_i16@pure_quanta.q_cap_diffbus(chips)',
 P_PATH='@t6g_mb_lib.t6g(sch_1):page319_i16@pure_quanta.q_cap_diffbus(chips)',
 PATH='I16',
 DRAWING='@T6G_MB_LIB.T6G(SCH_1):PAGE439',
 PIN_NAMES_ROTATE='TRUE',
 TOLERANCE='20%',
 MATERIAL='X6S',
 PHYS_PAGE='319',
 XY='(-2350,625)',
 ROT='2',
 VER='2',
 PACK_TYPE='C0201',
 LOCATION='C6643',
 CDS_LIB='pure_quanta',
 CDS_PART_NAME='Q_CAP_DIFFBUS_C0201-DIFF BUS_0.22UF,6.3V,20%,X6S,SA',
 VOLTAGE='6.3V',
 PART_NUMBER='SP_CH4221MEE01',
 VALUE='DIFF BUS_0.22UF',
 PRIM_FILE='./archive_libs/logical/q_cap_diffbus/chips/chips.prt';

PART_NAME
 C6644 'Q_CAP_DIFFBUS_C0201-DIFF BUS_0.22UF,6.3V,20%,X6S,SA':;

SECTION_NUMBER 1
 '@T6G_MB_LIB.T6G(SCH_1):PAGE439_I15@PURE_QUANTA.Q_CAP_DIFFBUS(CHIPS)':
 C_PATH='@t6g_mb_lib.t6g(sch_1):page439_i15@pure_quanta.q_cap_diffbus(chips)',
 P_PATH='@t6g_mb_lib.t6g(sch_1):page319_i15@pure_quanta.q_cap_diffbus(chips)',
 PATH='I15',
 DRAWING='@T6G_MB_LIB.T6G(SCH_1):PAGE439',
 PIN_NAMES_ROTATE='TRUE',
 TOLERANCE='20%',
 MATERIAL='X6S',
 PHYS_PAGE='319',
 XY='(-2350,575)',
 ROT='2',
 VER='2',
 PACK_TYPE='C0201',
 LOCATION='C6644',
 CDS_LIB='pure_quanta',
 CDS_PART_NAME='Q_CAP_DIFFBUS_C0201-DIFF BUS_0.22UF,6.3V,20%,X6S,SA',
 VOLTAGE='6.3V',
 PART_NUMBER='SP_CH4221MEE01',
 VALUE='DIFF BUS_0.22UF',
 PRIM_FILE='./archive_libs/logical/q_cap_diffbus/chips/chips.prt';

PART_NAME
 C6645 'Q_CAP_DIFFBUS_C0201-DIFF BUS_0.22UF,6.3V,20%,X6S,SA':;

SECTION_NUMBER 1
 '@T6G_MB_LIB.T6G(SCH_1):PAGE439_I105@PURE_QUANTA.Q_CAP_DIFFBUS(CHIPS)':
 C_PATH='@t6g_mb_lib.t6g(sch_1):page439_i105@pure_quanta.q_cap_diffbus(chips)',
 P_PATH='@t6g_mb_lib.t6g(sch_1):page319_i105@pure_quanta.q_cap_diffbus(chips)',
 PATH='I105',
 DRAWING='@T6G_MB_LIB.T6G(SCH_1):PAGE439',
 PIN_NAMES_ROTATE='TRUE',
 TOLERANCE='20%',
 MATERIAL='X6S',
 PHYS_PAGE='319',
 XY='(-6950,2050)',
 ROT='2',
 VER='2',
 PACK_TYPE='C0201',
 LOCATION='C6645',
 CDS_LIB='pure_quanta',
 CDS_PART_NAME='Q_CAP_DIFFBUS_C0201-DIFF BUS_0.22UF,6.3V,20%,X6S,SA',
 VOLTAGE='6.3V',
 PART_NUMBER='SP_CH4221MEE01',
 VALUE='DIFF BUS_0.22UF',
 PRIM_FILE='./archive_libs/logical/q_cap_diffbus/chips/chips.prt';

PART_NAME
 C6646 'Q_CAP_DIFFBUS_C0201-DIFF BUS_0.22UF,6.3V,20%,X6S,SA':;

SECTION_NUMBER 1
 '@T6G_MB_LIB.T6G(SCH_1):PAGE439_I104@PURE_QUANTA.Q_CAP_DIFFBUS(CHIPS)':
 C_PATH='@t6g_mb_lib.t6g(sch_1):page439_i104@pure_quanta.q_cap_diffbus(chips)',
 P_PATH='@t6g_mb_lib.t6g(sch_1):page319_i104@pure_quanta.q_cap_diffbus(chips)',
 PATH='I104',
 DRAWING='@T6G_MB_LIB.T6G(SCH_1):PAGE439',
 PIN_NAMES_ROTATE='TRUE',
 TOLERANCE='20%',
 MATERIAL='X6S',
 PHYS_PAGE='319',
 XY='(-6950,2000)',
 ROT='2',
 VER='2',
 PACK_TYPE='C0201',
 LOCATION='C6646',
 CDS_LIB='pure_quanta',
 CDS_PART_NAME='Q_CAP_DIFFBUS_C0201-DIFF BUS_0.22UF,6.3V,20%,X6S,SA',
 VOLTAGE='6.3V',
 PART_NUMBER='SP_CH4221MEE01',
 VALUE='DIFF BUS_0.22UF',
 PRIM_FILE='./archive_libs/logical/q_cap_diffbus/chips/chips.prt';

PART_NAME
 C6647 'Q_CAP_DIFFBUS_C0201-DIFF BUS_0.22UF,6.3V,20%,X6S,SA':;

SECTION_NUMBER 1
 '@T6G_MB_LIB.T6G(SCH_1):PAGE439_I102@PURE_QUANTA.Q_CAP_DIFFBUS(CHIPS)':
 C_PATH='@t6g_mb_lib.t6g(sch_1):page439_i102@pure_quanta.q_cap_diffbus(chips)',
 P_PATH='@t6g_mb_lib.t6g(sch_1):page319_i102@pure_quanta.q_cap_diffbus(chips)',
 PATH='I102',
 DRAWING='@T6G_MB_LIB.T6G(SCH_1):PAGE439',
 PIN_NAMES_ROTATE='TRUE',
 TOLERANCE='20%',
 MATERIAL='X6S',
 PHYS_PAGE='319',
 XY='(-6950,1850)',
 ROT='2',
 VER='2',
 PACK_TYPE='C0201',
 LOCATION='C6647',
 CDS_LIB='pure_quanta',
 CDS_PART_NAME='Q_CAP_DIFFBUS_C0201-DIFF BUS_0.22UF,6.3V,20%,X6S,SA',
 VOLTAGE='6.3V',
 PART_NUMBER='SP_CH4221MEE01',
 VALUE='DIFF BUS_0.22UF',
 PRIM_FILE='./archive_libs/logical/q_cap_diffbus/chips/chips.prt';

PART_NAME
 C6648 'Q_CAP_DIFFBUS_C0201-DIFF BUS_0.22UF,6.3V,20%,X6S,SA':;

SECTION_NUMBER 1
 '@T6G_MB_LIB.T6G(SCH_1):PAGE439_I103@PURE_QUANTA.Q_CAP_DIFFBUS(CHIPS)':
 C_PATH='@t6g_mb_lib.t6g(sch_1):page439_i103@pure_quanta.q_cap_diffbus(chips)',
 P_PATH='@t6g_mb_lib.t6g(sch_1):page319_i103@pure_quanta.q_cap_diffbus(chips)',
 PATH='I103',
 DRAWING='@T6G_MB_LIB.T6G(SCH_1):PAGE439',
 PIN_NAMES_ROTATE='TRUE',
 TOLERANCE='20%',
 MATERIAL='X6S',
 PHYS_PAGE='319',
 XY='(-6950,1800)',
 ROT='2',
 VER='2',
 PACK_TYPE='C0201',
 LOCATION='C6648',
 CDS_LIB='pure_quanta',
 CDS_PART_NAME='Q_CAP_DIFFBUS_C0201-DIFF BUS_0.22UF,6.3V,20%,X6S,SA',
 VOLTAGE='6.3V',
 PART_NUMBER='SP_CH4221MEE01',
 VALUE='DIFF BUS_0.22UF',
 PRIM_FILE='./archive_libs/logical/q_cap_diffbus/chips/chips.prt';

PART_NAME
 C6649 'Q_CAP_DIFFBUS_C0201-DIFF BUS_0.22UF,6.3V,20%,X6S,SA':;

SECTION_NUMBER 1
 '@T6G_MB_LIB.T6G(SCH_1):PAGE439_I96@PURE_QUANTA.Q_CAP_DIFFBUS(CHIPS)':
 C_PATH='@t6g_mb_lib.t6g(sch_1):page439_i96@pure_quanta.q_cap_diffbus(chips)',
 P_PATH='@t6g_mb_lib.t6g(sch_1):page319_i96@pure_quanta.q_cap_diffbus(chips)',
 PATH='I96',
 DRAWING='@T6G_MB_LIB.T6G(SCH_1):PAGE439',
 PIN_NAMES_ROTATE='TRUE',
 TOLERANCE='20%',
 MATERIAL='X6S',
 PHYS_PAGE='319',
 XY='(-6950,1650)',
 ROT='2',
 VER='2',
 PACK_TYPE='C0201',
 LOCATION='C6649',
 CDS_LIB='pure_quanta',
 CDS_PART_NAME='Q_CAP_DIFFBUS_C0201-DIFF BUS_0.22UF,6.3V,20%,X6S,SA',
 VOLTAGE='6.3V',
 PART_NUMBER='SP_CH4221MEE01',
 VALUE='DIFF BUS_0.22UF',
 PRIM_FILE='./archive_libs/logical/q_cap_diffbus/chips/chips.prt';

PART_NAME
 C6650 'Q_CAP_DIFFBUS_C0201-DIFF BUS_0.22UF,6.3V,20%,X6S,SA':;

SECTION_NUMBER 1
 '@T6G_MB_LIB.T6G(SCH_1):PAGE439_I97@PURE_QUANTA.Q_CAP_DIFFBUS(CHIPS)':
 C_PATH='@t6g_mb_lib.t6g(sch_1):page439_i97@pure_quanta.q_cap_diffbus(chips)',
 P_PATH='@t6g_mb_lib.t6g(sch_1):page319_i97@pure_quanta.q_cap_diffbus(chips)',
 PATH='I97',
 DRAWING='@T6G_MB_LIB.T6G(SCH_1):PAGE439',
 PIN_NAMES_ROTATE='TRUE',
 TOLERANCE='20%',
 MATERIAL='X6S',
 PHYS_PAGE='319',
 XY='(-6950,1600)',
 ROT='2',
 VER='2',
 PACK_TYPE='C0201',
 LOCATION='C6650',
 CDS_LIB='pure_quanta',
 CDS_PART_NAME='Q_CAP_DIFFBUS_C0201-DIFF BUS_0.22UF,6.3V,20%,X6S,SA',
 VOLTAGE='6.3V',
 PART_NUMBER='SP_CH4221MEE01',
 VALUE='DIFF BUS_0.22UF',
 PRIM_FILE='./archive_libs/logical/q_cap_diffbus/chips/chips.prt';

PART_NAME
 C6651 'Q_CAP_DIFFBUS_C0201-DIFF BUS_0.22UF,6.3V,20%,X6S,SA':;

SECTION_NUMBER 1
 '@T6G_MB_LIB.T6G(SCH_1):PAGE439_I95@PURE_QUANTA.Q_CAP_DIFFBUS(CHIPS)':
 C_PATH='@t6g_mb_lib.t6g(sch_1):page439_i95@pure_quanta.q_cap_diffbus(chips)',
 P_PATH='@t6g_mb_lib.t6g(sch_1):page319_i95@pure_quanta.q_cap_diffbus(chips)',
 PATH='I95',
 DRAWING='@T6G_MB_LIB.T6G(SCH_1):PAGE439',
 PIN_NAMES_ROTATE='TRUE',
 TOLERANCE='20%',
 MATERIAL='X6S',
 PHYS_PAGE='319',
 XY='(-6950,1450)',
 ROT='2',
 VER='2',
 PACK_TYPE='C0201',
 LOCATION='C6651',
 CDS_LIB='pure_quanta',
 CDS_PART_NAME='Q_CAP_DIFFBUS_C0201-DIFF BUS_0.22UF,6.3V,20%,X6S,SA',
 VOLTAGE='6.3V',
 PART_NUMBER='SP_CH4221MEE01',
 VALUE='DIFF BUS_0.22UF',
 PRIM_FILE='./archive_libs/logical/q_cap_diffbus/chips/chips.prt';

PART_NAME
 C6652 'Q_CAP_DIFFBUS_C0201-DIFF BUS_0.22UF,6.3V,20%,X6S,SA':;

SECTION_NUMBER 1
 '@T6G_MB_LIB.T6G(SCH_1):PAGE439_I94@PURE_QUANTA.Q_CAP_DIFFBUS(CHIPS)':
 C_PATH='@t6g_mb_lib.t6g(sch_1):page439_i94@pure_quanta.q_cap_diffbus(chips)',
 P_PATH='@t6g_mb_lib.t6g(sch_1):page319_i94@pure_quanta.q_cap_diffbus(chips)',
 PATH='I94',
 DRAWING='@T6G_MB_LIB.T6G(SCH_1):PAGE439',
 PIN_NAMES_ROTATE='TRUE',
 TOLERANCE='20%',
 MATERIAL='X6S',
 PHYS_PAGE='319',
 XY='(-6950,1400)',
 ROT='2',
 VER='2',
 PACK_TYPE='C0201',
 LOCATION='C6652',
 CDS_LIB='pure_quanta',
 CDS_PART_NAME='Q_CAP_DIFFBUS_C0201-DIFF BUS_0.22UF,6.3V,20%,X6S,SA',
 VOLTAGE='6.3V',
 PART_NUMBER='SP_CH4221MEE01',
 VALUE='DIFF BUS_0.22UF',
 PRIM_FILE='./archive_libs/logical/q_cap_diffbus/chips/chips.prt';

PART_NAME
 C6653 'Q_CAP_DIFFBUS_C0201-DIFF BUS_0.22UF,6.3V,20%,X6S,SA':;

SECTION_NUMBER 1
 '@T6G_MB_LIB.T6G(SCH_1):PAGE439_I93@PURE_QUANTA.Q_CAP_DIFFBUS(CHIPS)':
 C_PATH='@t6g_mb_lib.t6g(sch_1):page439_i93@pure_quanta.q_cap_diffbus(chips)',
 P_PATH='@t6g_mb_lib.t6g(sch_1):page319_i93@pure_quanta.q_cap_diffbus(chips)',
 PATH='I93',
 DRAWING='@T6G_MB_LIB.T6G(SCH_1):PAGE439',
 PIN_NAMES_ROTATE='TRUE',
 TOLERANCE='20%',
 MATERIAL='X6S',
 PHYS_PAGE='319',
 XY='(-6950,1250)',
 ROT='2',
 VER='2',
 PACK_TYPE='C0201',
 LOCATION='C6653',
 CDS_LIB='pure_quanta',
 CDS_PART_NAME='Q_CAP_DIFFBUS_C0201-DIFF BUS_0.22UF,6.3V,20%,X6S,SA',
 VOLTAGE='6.3V',
 PART_NUMBER='SP_CH4221MEE01',
 VALUE='DIFF BUS_0.22UF',
 PRIM_FILE='./archive_libs/logical/q_cap_diffbus/chips/chips.prt';

PART_NAME
 C6654 'Q_CAP_DIFFBUS_C0201-DIFF BUS_0.22UF,6.3V,20%,X6S,SA':;

SECTION_NUMBER 1
 '@T6G_MB_LIB.T6G(SCH_1):PAGE439_I92@PURE_QUANTA.Q_CAP_DIFFBUS(CHIPS)':
 C_PATH='@t6g_mb_lib.t6g(sch_1):page439_i92@pure_quanta.q_cap_diffbus(chips)',
 P_PATH='@t6g_mb_lib.t6g(sch_1):page319_i92@pure_quanta.q_cap_diffbus(chips)',
 PATH='I92',
 DRAWING='@T6G_MB_LIB.T6G(SCH_1):PAGE439',
 PIN_NAMES_ROTATE='TRUE',
 TOLERANCE='20%',
 MATERIAL='X6S',
 PHYS_PAGE='319',
 XY='(-6950,1200)',
 ROT='2',
 VER='2',
 PACK_TYPE='C0201',
 LOCATION='C6654',
 CDS_LIB='pure_quanta',
 CDS_PART_NAME='Q_CAP_DIFFBUS_C0201-DIFF BUS_0.22UF,6.3V,20%,X6S,SA',
 VOLTAGE='6.3V',
 PART_NUMBER='SP_CH4221MEE01',
 VALUE='DIFF BUS_0.22UF',
 PRIM_FILE='./archive_libs/logical/q_cap_diffbus/chips/chips.prt';

PART_NAME
 C6655 'Q_CAP_DIFFBUS_C0201-DIFF BUS_0.22UF,6.3V,20%,X6S,SA':;

SECTION_NUMBER 1
 '@T6G_MB_LIB.T6G(SCH_1):PAGE439_I91@PURE_QUANTA.Q_CAP_DIFFBUS(CHIPS)':
 C_PATH='@t6g_mb_lib.t6g(sch_1):page439_i91@pure_quanta.q_cap_diffbus(chips)',
 P_PATH='@t6g_mb_lib.t6g(sch_1):page319_i91@pure_quanta.q_cap_diffbus(chips)',
 PATH='I91',
 DRAWING='@T6G_MB_LIB.T6G(SCH_1):PAGE439',
 PIN_NAMES_ROTATE='TRUE',
 TOLERANCE='20%',
 MATERIAL='X6S',
 PHYS_PAGE='319',
 XY='(-6950,1050)',
 ROT='2',
 VER='2',
 PACK_TYPE='C0201',
 LOCATION='C6655',
 CDS_LIB='pure_quanta',
 CDS_PART_NAME='Q_CAP_DIFFBUS_C0201-DIFF BUS_0.22UF,6.3V,20%,X6S,SA',
 VOLTAGE='6.3V',
 PART_NUMBER='SP_CH4221MEE01',
 VALUE='DIFF BUS_0.22UF',
 PRIM_FILE='./archive_libs/logical/q_cap_diffbus/chips/chips.prt';

PART_NAME
 C6656 'Q_CAP_DIFFBUS_C0201-DIFF BUS_0.22UF,6.3V,20%,X6S,SA':;

SECTION_NUMBER 1
 '@T6G_MB_LIB.T6G(SCH_1):PAGE439_I90@PURE_QUANTA.Q_CAP_DIFFBUS(CHIPS)':
 C_PATH='@t6g_mb_lib.t6g(sch_1):page439_i90@pure_quanta.q_cap_diffbus(chips)',
 P_PATH='@t6g_mb_lib.t6g(sch_1):page319_i90@pure_quanta.q_cap_diffbus(chips)',
 PATH='I90',
 DRAWING='@T6G_MB_LIB.T6G(SCH_1):PAGE439',
 PIN_NAMES_ROTATE='TRUE',
 TOLERANCE='20%',
 MATERIAL='X6S',
 PHYS_PAGE='319',
 XY='(-6950,1000)',
 ROT='2',
 VER='2',
 PACK_TYPE='C0201',
 LOCATION='C6656',
 CDS_LIB='pure_quanta',
 CDS_PART_NAME='Q_CAP_DIFFBUS_C0201-DIFF BUS_0.22UF,6.3V,20%,X6S,SA',
 VOLTAGE='6.3V',
 PART_NUMBER='SP_CH4221MEE01',
 VALUE='DIFF BUS_0.22UF',
 PRIM_FILE='./archive_libs/logical/q_cap_diffbus/chips/chips.prt';

PART_NAME
 C6657 'Q_CAP_DIFFBUS_C0201-DIFF BUS_0.22UF,6.3V,20%,X6S,SA':;

SECTION_NUMBER 1
 '@T6G_MB_LIB.T6G(SCH_1):PAGE439_I89@PURE_QUANTA.Q_CAP_DIFFBUS(CHIPS)':
 C_PATH='@t6g_mb_lib.t6g(sch_1):page439_i89@pure_quanta.q_cap_diffbus(chips)',
 P_PATH='@t6g_mb_lib.t6g(sch_1):page319_i89@pure_quanta.q_cap_diffbus(chips)',
 PATH='I89',
 DRAWING='@T6G_MB_LIB.T6G(SCH_1):PAGE439',
 PIN_NAMES_ROTATE='TRUE',
 TOLERANCE='20%',
 MATERIAL='X6S',
 PHYS_PAGE='319',
 XY='(-6950,850)',
 ROT='2',
 VER='2',
 PACK_TYPE='C0201',
 LOCATION='C6657',
 CDS_LIB='pure_quanta',
 CDS_PART_NAME='Q_CAP_DIFFBUS_C0201-DIFF BUS_0.22UF,6.3V,20%,X6S,SA',
 VOLTAGE='6.3V',
 PART_NUMBER='SP_CH4221MEE01',
 VALUE='DIFF BUS_0.22UF',
 PRIM_FILE='./archive_libs/logical/q_cap_diffbus/chips/chips.prt';

PART_NAME
 C6658 'Q_CAP_DIFFBUS_C0201-DIFF BUS_0.22UF,6.3V,20%,X6S,SA':;

SECTION_NUMBER 1
 '@T6G_MB_LIB.T6G(SCH_1):PAGE439_I88@PURE_QUANTA.Q_CAP_DIFFBUS(CHIPS)':
 C_PATH='@t6g_mb_lib.t6g(sch_1):page439_i88@pure_quanta.q_cap_diffbus(chips)',
 P_PATH='@t6g_mb_lib.t6g(sch_1):page319_i88@pure_quanta.q_cap_diffbus(chips)',
 PATH='I88',
 DRAWING='@T6G_MB_LIB.T6G(SCH_1):PAGE439',
 PIN_NAMES_ROTATE='TRUE',
 TOLERANCE='20%',
 MATERIAL='X6S',
 PHYS_PAGE='319',
 XY='(-6950,800)',
 ROT='2',
 VER='2',
 PACK_TYPE='C0201',
 LOCATION='C6658',
 CDS_LIB='pure_quanta',
 CDS_PART_NAME='Q_CAP_DIFFBUS_C0201-DIFF BUS_0.22UF,6.3V,20%,X6S,SA',
 VOLTAGE='6.3V',
 PART_NUMBER='SP_CH4221MEE01',
 VALUE='DIFF BUS_0.22UF',
 PRIM_FILE='./archive_libs/logical/q_cap_diffbus/chips/chips.prt';

PART_NAME
 C6659 'Q_CAP_DIFFBUS_C0201-DIFF BUS_0.22UF,6.3V,20%,X6S,SA':;

SECTION_NUMBER 1
 '@T6G_MB_LIB.T6G(SCH_1):PAGE439_I87@PURE_QUANTA.Q_CAP_DIFFBUS(CHIPS)':
 C_PATH='@t6g_mb_lib.t6g(sch_1):page439_i87@pure_quanta.q_cap_diffbus(chips)',
 P_PATH='@t6g_mb_lib.t6g(sch_1):page319_i87@pure_quanta.q_cap_diffbus(chips)',
 PATH='I87',
 DRAWING='@T6G_MB_LIB.T6G(SCH_1):PAGE439',
 PIN_NAMES_ROTATE='TRUE',
 TOLERANCE='20%',
 MATERIAL='X6S',
 PHYS_PAGE='319',
 XY='(-6950,650)',
 ROT='2',
 VER='2',
 PACK_TYPE='C0201',
 LOCATION='C6659',
 CDS_LIB='pure_quanta',
 CDS_PART_NAME='Q_CAP_DIFFBUS_C0201-DIFF BUS_0.22UF,6.3V,20%,X6S,SA',
 VOLTAGE='6.3V',
 PART_NUMBER='SP_CH4221MEE01',
 VALUE='DIFF BUS_0.22UF',
 PRIM_FILE='./archive_libs/logical/q_cap_diffbus/chips/chips.prt';

PART_NAME
 C6660 'Q_CAP_DIFFBUS_C0201-DIFF BUS_0.22UF,6.3V,20%,X6S,SA':;

SECTION_NUMBER 1
 '@T6G_MB_LIB.T6G(SCH_1):PAGE439_I86@PURE_QUANTA.Q_CAP_DIFFBUS(CHIPS)':
 C_PATH='@t6g_mb_lib.t6g(sch_1):page439_i86@pure_quanta.q_cap_diffbus(chips)',
 P_PATH='@t6g_mb_lib.t6g(sch_1):page319_i86@pure_quanta.q_cap_diffbus(chips)',
 PATH='I86',
 DRAWING='@T6G_MB_LIB.T6G(SCH_1):PAGE439',
 PIN_NAMES_ROTATE='TRUE',
 TOLERANCE='20%',
 MATERIAL='X6S',
 PHYS_PAGE='319',
 XY='(-6950,600)',
 ROT='2',
 VER='2',
 PACK_TYPE='C0201',
 LOCATION='C6660',
 CDS_LIB='pure_quanta',
 CDS_PART_NAME='Q_CAP_DIFFBUS_C0201-DIFF BUS_0.22UF,6.3V,20%,X6S,SA',
 VOLTAGE='6.3V',
 PART_NUMBER='SP_CH4221MEE01',
 VALUE='DIFF BUS_0.22UF',
 PRIM_FILE='./archive_libs/logical/q_cap_diffbus/chips/chips.prt';

PART_NAME
 C6661 'Q_CAP_DIFFBUS_C0201-DIFF BUS_0.22UF,6.3V,20%,X6S,SA':;

SECTION_NUMBER 1
 '@T6G_MB_LIB.T6G(SCH_1):PAGE393_I42@PURE_QUANTA.Q_CAP_DIFFBUS(CHIPS)':
 C_PATH='@t6g_mb_lib.t6g(sch_1):page393_i42@pure_quanta.q_cap_diffbus(chips)',
 P_PATH='@t6g_mb_lib.t6g(sch_1):page330_i42@pure_quanta.q_cap_diffbus(chips)',
 PATH='I42',
 DRAWING='@T6G_MB_LIB.T6G(SCH_1):PAGE393',
 PIN_NAMES_ROTATE='TRUE',
 TOLERANCE='20%',
 MATERIAL='X6S',
 PHYS_PAGE='330',
 XY='(-2375,2200)',
 ROT='2',
 VER='2',
 PACK_TYPE='C0201',
 LOCATION='C6661',
 CDS_LIB='pure_quanta',
 CDS_PART_NAME='Q_CAP_DIFFBUS_C0201-DIFF BUS_0.22UF,6.3V,20%,X6S,SA',
 VOLTAGE='6.3V',
 PART_NUMBER='SP_CH4221MEE01',
 VALUE='DIFF BUS_0.22UF',
 PRIM_FILE='./archive_libs/logical/q_cap_diffbus/chips/chips.prt';

PART_NAME
 C6662 'Q_CAP_DIFFBUS_C0201-DIFF BUS_0.22UF,6.3V,20%,X6S,SA':;

SECTION_NUMBER 1
 '@T6G_MB_LIB.T6G(SCH_1):PAGE393_I33@PURE_QUANTA.Q_CAP_DIFFBUS(CHIPS)':
 C_PATH='@t6g_mb_lib.t6g(sch_1):page393_i33@pure_quanta.q_cap_diffbus(chips)',
 P_PATH='@t6g_mb_lib.t6g(sch_1):page330_i33@pure_quanta.q_cap_diffbus(chips)',
 PATH='I33',
 DRAWING='@T6G_MB_LIB.T6G(SCH_1):PAGE393',
 PIN_NAMES_ROTATE='TRUE',
 TOLERANCE='20%',
 MATERIAL='X6S',
 PHYS_PAGE='330',
 XY='(-2375,2150)',
 ROT='2',
 VER='2',
 PACK_TYPE='C0201',
 LOCATION='C6662',
 CDS_LIB='pure_quanta',
 CDS_PART_NAME='Q_CAP_DIFFBUS_C0201-DIFF BUS_0.22UF,6.3V,20%,X6S,SA',
 VOLTAGE='6.3V',
 PART_NUMBER='SP_CH4221MEE01',
 VALUE='DIFF BUS_0.22UF',
 PRIM_FILE='./archive_libs/logical/q_cap_diffbus/chips/chips.prt';

PART_NAME
 C6663 'Q_CAP_DIFFBUS_C0201-DIFF BUS_0.22UF,6.3V,20%,X6S,SA':;

SECTION_NUMBER 1
 '@T6G_MB_LIB.T6G(SCH_1):PAGE393_I31@PURE_QUANTA.Q_CAP_DIFFBUS(CHIPS)':
 C_PATH='@t6g_mb_lib.t6g(sch_1):page393_i31@pure_quanta.q_cap_diffbus(chips)',
 P_PATH='@t6g_mb_lib.t6g(sch_1):page330_i31@pure_quanta.q_cap_diffbus(chips)',
 PATH='I31',
 DRAWING='@T6G_MB_LIB.T6G(SCH_1):PAGE393',
 PIN_NAMES_ROTATE='TRUE',
 TOLERANCE='20%',
 MATERIAL='X6S',
 PHYS_PAGE='330',
 XY='(-2375,2000)',
 ROT='2',
 VER='2',
 PACK_TYPE='C0201',
 LOCATION='C6663',
 CDS_LIB='pure_quanta',
 CDS_PART_NAME='Q_CAP_DIFFBUS_C0201-DIFF BUS_0.22UF,6.3V,20%,X6S,SA',
 VOLTAGE='6.3V',
 PART_NUMBER='SP_CH4221MEE01',
 VALUE='DIFF BUS_0.22UF',
 PRIM_FILE='./archive_libs/logical/q_cap_diffbus/chips/chips.prt';

PART_NAME
 C6664 'Q_CAP_DIFFBUS_C0201-DIFF BUS_0.22UF,6.3V,20%,X6S,SA':;

SECTION_NUMBER 1
 '@T6G_MB_LIB.T6G(SCH_1):PAGE393_I32@PURE_QUANTA.Q_CAP_DIFFBUS(CHIPS)':
 C_PATH='@t6g_mb_lib.t6g(sch_1):page393_i32@pure_quanta.q_cap_diffbus(chips)',
 P_PATH='@t6g_mb_lib.t6g(sch_1):page330_i32@pure_quanta.q_cap_diffbus(chips)',
 PATH='I32',
 DRAWING='@T6G_MB_LIB.T6G(SCH_1):PAGE393',
 PIN_NAMES_ROTATE='TRUE',
 TOLERANCE='20%',
 MATERIAL='X6S',
 PHYS_PAGE='330',
 XY='(-2375,1950)',
 ROT='2',
 VER='2',
 PACK_TYPE='C0201',
 LOCATION='C6664',
 CDS_LIB='pure_quanta',
 CDS_PART_NAME='Q_CAP_DIFFBUS_C0201-DIFF BUS_0.22UF,6.3V,20%,X6S,SA',
 VOLTAGE='6.3V',
 PART_NUMBER='SP_CH4221MEE01',
 VALUE='DIFF BUS_0.22UF',
 PRIM_FILE='./archive_libs/logical/q_cap_diffbus/chips/chips.prt';

PART_NAME
 C6665 'Q_CAP_DIFFBUS_C0201-DIFF BUS_0.22UF,6.3V,20%,X6S,SA':;

SECTION_NUMBER 1
 '@T6G_MB_LIB.T6G(SCH_1):PAGE393_I30@PURE_QUANTA.Q_CAP_DIFFBUS(CHIPS)':
 C_PATH='@t6g_mb_lib.t6g(sch_1):page393_i30@pure_quanta.q_cap_diffbus(chips)',
 P_PATH='@t6g_mb_lib.t6g(sch_1):page330_i30@pure_quanta.q_cap_diffbus(chips)',
 PATH='I30',
 DRAWING='@T6G_MB_LIB.T6G(SCH_1):PAGE393',
 PIN_NAMES_ROTATE='TRUE',
 TOLERANCE='20%',
 MATERIAL='X6S',
 PHYS_PAGE='330',
 XY='(-2375,1800)',
 ROT='2',
 VER='2',
 PACK_TYPE='C0201',
 LOCATION='C6665',
 CDS_LIB='pure_quanta',
 CDS_PART_NAME='Q_CAP_DIFFBUS_C0201-DIFF BUS_0.22UF,6.3V,20%,X6S,SA',
 VOLTAGE='6.3V',
 PART_NUMBER='SP_CH4221MEE01',
 VALUE='DIFF BUS_0.22UF',
 PRIM_FILE='./archive_libs/logical/q_cap_diffbus/chips/chips.prt';

PART_NAME
 C6666 'Q_CAP_DIFFBUS_C0201-DIFF BUS_0.22UF,6.3V,20%,X6S,SA':;

SECTION_NUMBER 1
 '@T6G_MB_LIB.T6G(SCH_1):PAGE393_I29@PURE_QUANTA.Q_CAP_DIFFBUS(CHIPS)':
 C_PATH='@t6g_mb_lib.t6g(sch_1):page393_i29@pure_quanta.q_cap_diffbus(chips)',
 P_PATH='@t6g_mb_lib.t6g(sch_1):page330_i29@pure_quanta.q_cap_diffbus(chips)',
 PATH='I29',
 DRAWING='@T6G_MB_LIB.T6G(SCH_1):PAGE393',
 PIN_NAMES_ROTATE='TRUE',
 TOLERANCE='20%',
 MATERIAL='X6S',
 PHYS_PAGE='330',
 XY='(-2375,1750)',
 ROT='2',
 VER='2',
 PACK_TYPE='C0201',
 LOCATION='C6666',
 CDS_LIB='pure_quanta',
 CDS_PART_NAME='Q_CAP_DIFFBUS_C0201-DIFF BUS_0.22UF,6.3V,20%,X6S,SA',
 VOLTAGE='6.3V',
 PART_NUMBER='SP_CH4221MEE01',
 VALUE='DIFF BUS_0.22UF',
 PRIM_FILE='./archive_libs/logical/q_cap_diffbus/chips/chips.prt';

PART_NAME
 C6667 'Q_CAP_DIFFBUS_C0201-DIFF BUS_0.22UF,6.3V,20%,X6S,SA':;

SECTION_NUMBER 1
 '@T6G_MB_LIB.T6G(SCH_1):PAGE393_I27@PURE_QUANTA.Q_CAP_DIFFBUS(CHIPS)':
 C_PATH='@t6g_mb_lib.t6g(sch_1):page393_i27@pure_quanta.q_cap_diffbus(chips)',
 P_PATH='@t6g_mb_lib.t6g(sch_1):page330_i27@pure_quanta.q_cap_diffbus(chips)',
 PATH='I27',
 DRAWING='@T6G_MB_LIB.T6G(SCH_1):PAGE393',
 PIN_NAMES_ROTATE='TRUE',
 TOLERANCE='20%',
 MATERIAL='X6S',
 PHYS_PAGE='330',
 XY='(-2375,1600)',
 ROT='2',
 VER='2',
 PACK_TYPE='C0201',
 LOCATION='C6667',
 CDS_LIB='pure_quanta',
 CDS_PART_NAME='Q_CAP_DIFFBUS_C0201-DIFF BUS_0.22UF,6.3V,20%,X6S,SA',
 VOLTAGE='6.3V',
 PART_NUMBER='SP_CH4221MEE01',
 VALUE='DIFF BUS_0.22UF',
 PRIM_FILE='./archive_libs/logical/q_cap_diffbus/chips/chips.prt';

PART_NAME
 C6668 'Q_CAP_DIFFBUS_C0201-DIFF BUS_0.22UF,6.3V,20%,X6S,SA':;

SECTION_NUMBER 1
 '@T6G_MB_LIB.T6G(SCH_1):PAGE393_I28@PURE_QUANTA.Q_CAP_DIFFBUS(CHIPS)':
 C_PATH='@t6g_mb_lib.t6g(sch_1):page393_i28@pure_quanta.q_cap_diffbus(chips)',
 P_PATH='@t6g_mb_lib.t6g(sch_1):page330_i28@pure_quanta.q_cap_diffbus(chips)',
 PATH='I28',
 DRAWING='@T6G_MB_LIB.T6G(SCH_1):PAGE393',
 PIN_NAMES_ROTATE='TRUE',
 TOLERANCE='20%',
 MATERIAL='X6S',
 PHYS_PAGE='330',
 XY='(-2375,1550)',
 ROT='2',
 VER='2',
 PACK_TYPE='C0201',
 LOCATION='C6668',
 CDS_LIB='pure_quanta',
 CDS_PART_NAME='Q_CAP_DIFFBUS_C0201-DIFF BUS_0.22UF,6.3V,20%,X6S,SA',
 VOLTAGE='6.3V',
 PART_NUMBER='SP_CH4221MEE01',
 VALUE='DIFF BUS_0.22UF',
 PRIM_FILE='./archive_libs/logical/q_cap_diffbus/chips/chips.prt';

PART_NAME
 C6669 'Q_CAP_DIFFBUS_C0201-DIFF BUS_0.22UF,6.3V,20%,X6S,SA':;

SECTION_NUMBER 1
 '@T6G_MB_LIB.T6G(SCH_1):PAGE393_I26@PURE_QUANTA.Q_CAP_DIFFBUS(CHIPS)':
 C_PATH='@t6g_mb_lib.t6g(sch_1):page393_i26@pure_quanta.q_cap_diffbus(chips)',
 P_PATH='@t6g_mb_lib.t6g(sch_1):page330_i26@pure_quanta.q_cap_diffbus(chips)',
 PATH='I26',
 DRAWING='@T6G_MB_LIB.T6G(SCH_1):PAGE393',
 PIN_NAMES_ROTATE='TRUE',
 TOLERANCE='20%',
 MATERIAL='X6S',
 PHYS_PAGE='330',
 XY='(-2375,1400)',
 ROT='2',
 VER='2',
 PACK_TYPE='C0201',
 LOCATION='C6669',
 CDS_LIB='pure_quanta',
 CDS_PART_NAME='Q_CAP_DIFFBUS_C0201-DIFF BUS_0.22UF,6.3V,20%,X6S,SA',
 VOLTAGE='6.3V',
 PART_NUMBER='SP_CH4221MEE01',
 VALUE='DIFF BUS_0.22UF',
 PRIM_FILE='./archive_libs/logical/q_cap_diffbus/chips/chips.prt';

PART_NAME
 C6670 'Q_CAP_DIFFBUS_C0201-DIFF BUS_0.22UF,6.3V,20%,X6S,SA':;

SECTION_NUMBER 1
 '@T6G_MB_LIB.T6G(SCH_1):PAGE393_I25@PURE_QUANTA.Q_CAP_DIFFBUS(CHIPS)':
 C_PATH='@t6g_mb_lib.t6g(sch_1):page393_i25@pure_quanta.q_cap_diffbus(chips)',
 P_PATH='@t6g_mb_lib.t6g(sch_1):page330_i25@pure_quanta.q_cap_diffbus(chips)',
 PATH='I25',
 DRAWING='@T6G_MB_LIB.T6G(SCH_1):PAGE393',
 PIN_NAMES_ROTATE='TRUE',
 TOLERANCE='20%',
 MATERIAL='X6S',
 PHYS_PAGE='330',
 XY='(-2375,1350)',
 ROT='2',
 VER='2',
 PACK_TYPE='C0201',
 LOCATION='C6670',
 CDS_LIB='pure_quanta',
 CDS_PART_NAME='Q_CAP_DIFFBUS_C0201-DIFF BUS_0.22UF,6.3V,20%,X6S,SA',
 VOLTAGE='6.3V',
 PART_NUMBER='SP_CH4221MEE01',
 VALUE='DIFF BUS_0.22UF',
 PRIM_FILE='./archive_libs/logical/q_cap_diffbus/chips/chips.prt';

PART_NAME
 C6671 'Q_CAP_DIFFBUS_C0201-DIFF BUS_0.22UF,6.3V,20%,X6S,SA':;

SECTION_NUMBER 1
 '@T6G_MB_LIB.T6G(SCH_1):PAGE393_I24@PURE_QUANTA.Q_CAP_DIFFBUS(CHIPS)':
 C_PATH='@t6g_mb_lib.t6g(sch_1):page393_i24@pure_quanta.q_cap_diffbus(chips)',
 P_PATH='@t6g_mb_lib.t6g(sch_1):page330_i24@pure_quanta.q_cap_diffbus(chips)',
 PATH='I24',
 DRAWING='@T6G_MB_LIB.T6G(SCH_1):PAGE393',
 PIN_NAMES_ROTATE='TRUE',
 TOLERANCE='20%',
 MATERIAL='X6S',
 PHYS_PAGE='330',
 XY='(-2375,1200)',
 ROT='2',
 VER='2',
 PACK_TYPE='C0201',
 LOCATION='C6671',
 CDS_LIB='pure_quanta',
 CDS_PART_NAME='Q_CAP_DIFFBUS_C0201-DIFF BUS_0.22UF,6.3V,20%,X6S,SA',
 VOLTAGE='6.3V',
 PART_NUMBER='SP_CH4221MEE01',
 VALUE='DIFF BUS_0.22UF',
 PRIM_FILE='./archive_libs/logical/q_cap_diffbus/chips/chips.prt';

PART_NAME
 C6672 'Q_CAP_DIFFBUS_C0201-DIFF BUS_0.22UF,6.3V,20%,X6S,SA':;

SECTION_NUMBER 1
 '@T6G_MB_LIB.T6G(SCH_1):PAGE393_I23@PURE_QUANTA.Q_CAP_DIFFBUS(CHIPS)':
 C_PATH='@t6g_mb_lib.t6g(sch_1):page393_i23@pure_quanta.q_cap_diffbus(chips)',
 P_PATH='@t6g_mb_lib.t6g(sch_1):page330_i23@pure_quanta.q_cap_diffbus(chips)',
 PATH='I23',
 DRAWING='@T6G_MB_LIB.T6G(SCH_1):PAGE393',
 PIN_NAMES_ROTATE='TRUE',
 TOLERANCE='20%',
 MATERIAL='X6S',
 PHYS_PAGE='330',
 XY='(-2375,1150)',
 ROT='2',
 VER='2',
 PACK_TYPE='C0201',
 LOCATION='C6672',
 CDS_LIB='pure_quanta',
 CDS_PART_NAME='Q_CAP_DIFFBUS_C0201-DIFF BUS_0.22UF,6.3V,20%,X6S,SA',
 VOLTAGE='6.3V',
 PART_NUMBER='SP_CH4221MEE01',
 VALUE='DIFF BUS_0.22UF',
 PRIM_FILE='./archive_libs/logical/q_cap_diffbus/chips/chips.prt';

PART_NAME
 C6673 'Q_CAP_DIFFBUS_C0201-DIFF BUS_0.22UF,6.3V,20%,X6S,SA':;

SECTION_NUMBER 1
 '@T6G_MB_LIB.T6G(SCH_1):PAGE393_I20@PURE_QUANTA.Q_CAP_DIFFBUS(CHIPS)':
 C_PATH='@t6g_mb_lib.t6g(sch_1):page393_i20@pure_quanta.q_cap_diffbus(chips)',
 P_PATH='@t6g_mb_lib.t6g(sch_1):page330_i20@pure_quanta.q_cap_diffbus(chips)',
 PATH='I20',
 DRAWING='@T6G_MB_LIB.T6G(SCH_1):PAGE393',
 PIN_NAMES_ROTATE='TRUE',
 TOLERANCE='20%',
 MATERIAL='X6S',
 PHYS_PAGE='330',
 XY='(-2375,1000)',
 ROT='2',
 VER='2',
 PACK_TYPE='C0201',
 LOCATION='C6673',
 CDS_LIB='pure_quanta',
 CDS_PART_NAME='Q_CAP_DIFFBUS_C0201-DIFF BUS_0.22UF,6.3V,20%,X6S,SA',
 VOLTAGE='6.3V',
 PART_NUMBER='SP_CH4221MEE01',
 VALUE='DIFF BUS_0.22UF',
 PRIM_FILE='./archive_libs/logical/q_cap_diffbus/chips/chips.prt';

PART_NAME
 C6674 'Q_CAP_DIFFBUS_C0201-DIFF BUS_0.22UF,6.3V,20%,X6S,SA':;

SECTION_NUMBER 1
 '@T6G_MB_LIB.T6G(SCH_1):PAGE393_I19@PURE_QUANTA.Q_CAP_DIFFBUS(CHIPS)':
 C_PATH='@t6g_mb_lib.t6g(sch_1):page393_i19@pure_quanta.q_cap_diffbus(chips)',
 P_PATH='@t6g_mb_lib.t6g(sch_1):page330_i19@pure_quanta.q_cap_diffbus(chips)',
 PATH='I19',
 DRAWING='@T6G_MB_LIB.T6G(SCH_1):PAGE393',
 PIN_NAMES_ROTATE='TRUE',
 TOLERANCE='20%',
 MATERIAL='X6S',
 PHYS_PAGE='330',
 XY='(-2375,950)',
 ROT='2',
 VER='2',
 PACK_TYPE='C0201',
 LOCATION='C6674',
 CDS_LIB='pure_quanta',
 CDS_PART_NAME='Q_CAP_DIFFBUS_C0201-DIFF BUS_0.22UF,6.3V,20%,X6S,SA',
 VOLTAGE='6.3V',
 PART_NUMBER='SP_CH4221MEE01',
 VALUE='DIFF BUS_0.22UF',
 PRIM_FILE='./archive_libs/logical/q_cap_diffbus/chips/chips.prt';

PART_NAME
 C6675 'Q_CAP_DIFFBUS_C0201-DIFF BUS_0.22UF,6.3V,20%,X6S,SA':;

SECTION_NUMBER 1
 '@T6G_MB_LIB.T6G(SCH_1):PAGE393_I18@PURE_QUANTA.Q_CAP_DIFFBUS(CHIPS)':
 C_PATH='@t6g_mb_lib.t6g(sch_1):page393_i18@pure_quanta.q_cap_diffbus(chips)',
 P_PATH='@t6g_mb_lib.t6g(sch_1):page330_i18@pure_quanta.q_cap_diffbus(chips)',
 PATH='I18',
 DRAWING='@T6G_MB_LIB.T6G(SCH_1):PAGE393',
 PIN_NAMES_ROTATE='TRUE',
 TOLERANCE='20%',
 MATERIAL='X6S',
 PHYS_PAGE='330',
 XY='(-2375,800)',
 ROT='2',
 VER='2',
 PACK_TYPE='C0201',
 LOCATION='C6675',
 CDS_LIB='pure_quanta',
 CDS_PART_NAME='Q_CAP_DIFFBUS_C0201-DIFF BUS_0.22UF,6.3V,20%,X6S,SA',
 VOLTAGE='6.3V',
 PART_NUMBER='SP_CH4221MEE01',
 VALUE='DIFF BUS_0.22UF',
 PRIM_FILE='./archive_libs/logical/q_cap_diffbus/chips/chips.prt';

PART_NAME
 C6676 'Q_CAP_DIFFBUS_C0201-DIFF BUS_0.22UF,6.3V,20%,X6S,SA':;

SECTION_NUMBER 1
 '@T6G_MB_LIB.T6G(SCH_1):PAGE393_I17@PURE_QUANTA.Q_CAP_DIFFBUS(CHIPS)':
 C_PATH='@t6g_mb_lib.t6g(sch_1):page393_i17@pure_quanta.q_cap_diffbus(chips)',
 P_PATH='@t6g_mb_lib.t6g(sch_1):page330_i17@pure_quanta.q_cap_diffbus(chips)',
 PATH='I17',
 DRAWING='@T6G_MB_LIB.T6G(SCH_1):PAGE393',
 PIN_NAMES_ROTATE='TRUE',
 TOLERANCE='20%',
 MATERIAL='X6S',
 PHYS_PAGE='330',
 XY='(-2375,750)',
 ROT='2',
 VER='2',
 PACK_TYPE='C0201',
 LOCATION='C6676',
 CDS_LIB='pure_quanta',
 CDS_PART_NAME='Q_CAP_DIFFBUS_C0201-DIFF BUS_0.22UF,6.3V,20%,X6S,SA',
 VOLTAGE='6.3V',
 PART_NUMBER='SP_CH4221MEE01',
 VALUE='DIFF BUS_0.22UF',
 PRIM_FILE='./archive_libs/logical/q_cap_diffbus/chips/chips.prt';

PART_NAME
 C6677 'Q_CAP_DIFFBUS_C0201-DIFF BUS_0.22UF,6.3V,20%,X6S,SA':;

SECTION_NUMBER 1
 '@T6G_MB_LIB.T6G(SCH_1):PAGE393_I104@PURE_QUANTA.Q_CAP_DIFFBUS(CHIPS)':
 C_PATH='@t6g_mb_lib.t6g(sch_1):page393_i104@pure_quanta.q_cap_diffbus(chips)',
 P_PATH='@t6g_mb_lib.t6g(sch_1):page330_i104@pure_quanta.q_cap_diffbus(chips)',
 PATH='I104',
 DRAWING='@T6G_MB_LIB.T6G(SCH_1):PAGE393',
 PIN_NAMES_ROTATE='TRUE',
 TOLERANCE='20%',
 MATERIAL='X6S',
 PHYS_PAGE='330',
 XY='(-7000,2200)',
 ROT='2',
 VER='2',
 PACK_TYPE='C0201',
 LOCATION='C6677',
 CDS_LIB='pure_quanta',
 CDS_PART_NAME='Q_CAP_DIFFBUS_C0201-DIFF BUS_0.22UF,6.3V,20%,X6S,SA',
 VOLTAGE='6.3V',
 PART_NUMBER='SP_CH4221MEE01',
 VALUE='DIFF BUS_0.22UF',
 PRIM_FILE='./archive_libs/logical/q_cap_diffbus/chips/chips.prt';

PART_NAME
 C6678 'Q_CAP_DIFFBUS_C0201-DIFF BUS_0.22UF,6.3V,20%,X6S,SA':;

SECTION_NUMBER 1
 '@T6G_MB_LIB.T6G(SCH_1):PAGE393_I103@PURE_QUANTA.Q_CAP_DIFFBUS(CHIPS)':
 C_PATH='@t6g_mb_lib.t6g(sch_1):page393_i103@pure_quanta.q_cap_diffbus(chips)',
 P_PATH='@t6g_mb_lib.t6g(sch_1):page330_i103@pure_quanta.q_cap_diffbus(chips)',
 PATH='I103',
 DRAWING='@T6G_MB_LIB.T6G(SCH_1):PAGE393',
 PIN_NAMES_ROTATE='TRUE',
 TOLERANCE='20%',
 MATERIAL='X6S',
 PHYS_PAGE='330',
 XY='(-7000,2150)',
 ROT='2',
 VER='2',
 PACK_TYPE='C0201',
 LOCATION='C6678',
 CDS_LIB='pure_quanta',
 CDS_PART_NAME='Q_CAP_DIFFBUS_C0201-DIFF BUS_0.22UF,6.3V,20%,X6S,SA',
 VOLTAGE='6.3V',
 PART_NUMBER='SP_CH4221MEE01',
 VALUE='DIFF BUS_0.22UF',
 PRIM_FILE='./archive_libs/logical/q_cap_diffbus/chips/chips.prt';

PART_NAME
 C6679 'Q_CAP_DIFFBUS_C0201-DIFF BUS_0.22UF,6.3V,20%,X6S,SA':;

SECTION_NUMBER 1
 '@T6G_MB_LIB.T6G(SCH_1):PAGE393_I101@PURE_QUANTA.Q_CAP_DIFFBUS(CHIPS)':
 C_PATH='@t6g_mb_lib.t6g(sch_1):page393_i101@pure_quanta.q_cap_diffbus(chips)',
 P_PATH='@t6g_mb_lib.t6g(sch_1):page330_i101@pure_quanta.q_cap_diffbus(chips)',
 PATH='I101',
 DRAWING='@T6G_MB_LIB.T6G(SCH_1):PAGE393',
 PIN_NAMES_ROTATE='TRUE',
 TOLERANCE='20%',
 MATERIAL='X6S',
 PHYS_PAGE='330',
 XY='(-7000,2000)',
 ROT='2',
 VER='2',
 PACK_TYPE='C0201',
 LOCATION='C6679',
 CDS_LIB='pure_quanta',
 CDS_PART_NAME='Q_CAP_DIFFBUS_C0201-DIFF BUS_0.22UF,6.3V,20%,X6S,SA',
 VOLTAGE='6.3V',
 PART_NUMBER='SP_CH4221MEE01',
 VALUE='DIFF BUS_0.22UF',
 PRIM_FILE='./archive_libs/logical/q_cap_diffbus/chips/chips.prt';

PART_NAME
 C6680 'Q_CAP_DIFFBUS_C0201-DIFF BUS_0.22UF,6.3V,20%,X6S,SA':;

SECTION_NUMBER 1
 '@T6G_MB_LIB.T6G(SCH_1):PAGE393_I102@PURE_QUANTA.Q_CAP_DIFFBUS(CHIPS)':
 C_PATH='@t6g_mb_lib.t6g(sch_1):page393_i102@pure_quanta.q_cap_diffbus(chips)',
 P_PATH='@t6g_mb_lib.t6g(sch_1):page330_i102@pure_quanta.q_cap_diffbus(chips)',
 PATH='I102',
 DRAWING='@T6G_MB_LIB.T6G(SCH_1):PAGE393',
 PIN_NAMES_ROTATE='TRUE',
 TOLERANCE='20%',
 MATERIAL='X6S',
 PHYS_PAGE='330',
 XY='(-7000,1950)',
 ROT='2',
 VER='2',
 PACK_TYPE='C0201',
 LOCATION='C6680',
 CDS_LIB='pure_quanta',
 CDS_PART_NAME='Q_CAP_DIFFBUS_C0201-DIFF BUS_0.22UF,6.3V,20%,X6S,SA',
 VOLTAGE='6.3V',
 PART_NUMBER='SP_CH4221MEE01',
 VALUE='DIFF BUS_0.22UF',
 PRIM_FILE='./archive_libs/logical/q_cap_diffbus/chips/chips.prt';

PART_NAME
 C6681 'Q_CAP_DIFFBUS_C0201-DIFF BUS_0.22UF,6.3V,20%,X6S,SA':;

SECTION_NUMBER 1
 '@T6G_MB_LIB.T6G(SCH_1):PAGE393_I99@PURE_QUANTA.Q_CAP_DIFFBUS(CHIPS)':
 C_PATH='@t6g_mb_lib.t6g(sch_1):page393_i99@pure_quanta.q_cap_diffbus(chips)',
 P_PATH='@t6g_mb_lib.t6g(sch_1):page330_i99@pure_quanta.q_cap_diffbus(chips)',
 PATH='I99',
 DRAWING='@T6G_MB_LIB.T6G(SCH_1):PAGE393',
 PIN_NAMES_ROTATE='TRUE',
 TOLERANCE='20%',
 MATERIAL='X6S',
 PHYS_PAGE='330',
 XY='(-7000,1800)',
 ROT='2',
 VER='2',
 PACK_TYPE='C0201',
 LOCATION='C6681',
 CDS_LIB='pure_quanta',
 CDS_PART_NAME='Q_CAP_DIFFBUS_C0201-DIFF BUS_0.22UF,6.3V,20%,X6S,SA',
 VOLTAGE='6.3V',
 PART_NUMBER='SP_CH4221MEE01',
 VALUE='DIFF BUS_0.22UF',
 PRIM_FILE='./archive_libs/logical/q_cap_diffbus/chips/chips.prt';

PART_NAME
 C6682 'Q_CAP_DIFFBUS_C0201-DIFF BUS_0.22UF,6.3V,20%,X6S,SA':;

SECTION_NUMBER 1
 '@T6G_MB_LIB.T6G(SCH_1):PAGE393_I100@PURE_QUANTA.Q_CAP_DIFFBUS(CHIPS)':
 C_PATH='@t6g_mb_lib.t6g(sch_1):page393_i100@pure_quanta.q_cap_diffbus(chips)',
 P_PATH='@t6g_mb_lib.t6g(sch_1):page330_i100@pure_quanta.q_cap_diffbus(chips)',
 PATH='I100',
 DRAWING='@T6G_MB_LIB.T6G(SCH_1):PAGE393',
 PIN_NAMES_ROTATE='TRUE',
 TOLERANCE='20%',
 MATERIAL='X6S',
 PHYS_PAGE='330',
 XY='(-7000,1750)',
 ROT='2',
 VER='2',
 PACK_TYPE='C0201',
 LOCATION='C6682',
 CDS_LIB='pure_quanta',
 CDS_PART_NAME='Q_CAP_DIFFBUS_C0201-DIFF BUS_0.22UF,6.3V,20%,X6S,SA',
 VOLTAGE='6.3V',
 PART_NUMBER='SP_CH4221MEE01',
 VALUE='DIFF BUS_0.22UF',
 PRIM_FILE='./archive_libs/logical/q_cap_diffbus/chips/chips.prt';

PART_NAME
 C6683 'Q_CAP_DIFFBUS_C0201-DIFF BUS_0.22UF,6.3V,20%,X6S,SA':;

SECTION_NUMBER 1
 '@T6G_MB_LIB.T6G(SCH_1):PAGE393_I98@PURE_QUANTA.Q_CAP_DIFFBUS(CHIPS)':
 C_PATH='@t6g_mb_lib.t6g(sch_1):page393_i98@pure_quanta.q_cap_diffbus(chips)',
 P_PATH='@t6g_mb_lib.t6g(sch_1):page330_i98@pure_quanta.q_cap_diffbus(chips)',
 PATH='I98',
 DRAWING='@T6G_MB_LIB.T6G(SCH_1):PAGE393',
 PIN_NAMES_ROTATE='TRUE',
 TOLERANCE='20%',
 MATERIAL='X6S',
 PHYS_PAGE='330',
 XY='(-7000,1600)',
 ROT='2',
 VER='2',
 PACK_TYPE='C0201',
 LOCATION='C6683',
 CDS_LIB='pure_quanta',
 CDS_PART_NAME='Q_CAP_DIFFBUS_C0201-DIFF BUS_0.22UF,6.3V,20%,X6S,SA',
 VOLTAGE='6.3V',
 PART_NUMBER='SP_CH4221MEE01',
 VALUE='DIFF BUS_0.22UF',
 PRIM_FILE='./archive_libs/logical/q_cap_diffbus/chips/chips.prt';

PART_NAME
 C6684 'Q_CAP_DIFFBUS_C0201-DIFF BUS_0.22UF,6.3V,20%,X6S,SA':;

SECTION_NUMBER 1
 '@T6G_MB_LIB.T6G(SCH_1):PAGE393_I97@PURE_QUANTA.Q_CAP_DIFFBUS(CHIPS)':
 C_PATH='@t6g_mb_lib.t6g(sch_1):page393_i97@pure_quanta.q_cap_diffbus(chips)',
 P_PATH='@t6g_mb_lib.t6g(sch_1):page330_i97@pure_quanta.q_cap_diffbus(chips)',
 PATH='I97',
 DRAWING='@T6G_MB_LIB.T6G(SCH_1):PAGE393',
 PIN_NAMES_ROTATE='TRUE',
 TOLERANCE='20%',
 MATERIAL='X6S',
 PHYS_PAGE='330',
 XY='(-7000,1550)',
 ROT='2',
 VER='2',
 PACK_TYPE='C0201',
 LOCATION='C6684',
 CDS_LIB='pure_quanta',
 CDS_PART_NAME='Q_CAP_DIFFBUS_C0201-DIFF BUS_0.22UF,6.3V,20%,X6S,SA',
 VOLTAGE='6.3V',
 PART_NUMBER='SP_CH4221MEE01',
 VALUE='DIFF BUS_0.22UF',
 PRIM_FILE='./archive_libs/logical/q_cap_diffbus/chips/chips.prt';

PART_NAME
 C6685 'Q_CAP_DIFFBUS_C0201-DIFF BUS_0.22UF,6.3V,20%,X6S,SA':;

SECTION_NUMBER 1
 '@T6G_MB_LIB.T6G(SCH_1):PAGE393_I96@PURE_QUANTA.Q_CAP_DIFFBUS(CHIPS)':
 C_PATH='@t6g_mb_lib.t6g(sch_1):page393_i96@pure_quanta.q_cap_diffbus(chips)',
 P_PATH='@t6g_mb_lib.t6g(sch_1):page330_i96@pure_quanta.q_cap_diffbus(chips)',
 PATH='I96',
 DRAWING='@T6G_MB_LIB.T6G(SCH_1):PAGE393',
 PIN_NAMES_ROTATE='TRUE',
 TOLERANCE='20%',
 MATERIAL='X6S',
 PHYS_PAGE='330',
 XY='(-7000,1400)',
 ROT='2',
 VER='2',
 PACK_TYPE='C0201',
 LOCATION='C6685',
 CDS_LIB='pure_quanta',
 CDS_PART_NAME='Q_CAP_DIFFBUS_C0201-DIFF BUS_0.22UF,6.3V,20%,X6S,SA',
 VOLTAGE='6.3V',
 PART_NUMBER='SP_CH4221MEE01',
 VALUE='DIFF BUS_0.22UF',
 PRIM_FILE='./archive_libs/logical/q_cap_diffbus/chips/chips.prt';

PART_NAME
 C6686 'Q_CAP_DIFFBUS_C0201-DIFF BUS_0.22UF,6.3V,20%,X6S,SA':;

SECTION_NUMBER 1
 '@T6G_MB_LIB.T6G(SCH_1):PAGE393_I95@PURE_QUANTA.Q_CAP_DIFFBUS(CHIPS)':
 C_PATH='@t6g_mb_lib.t6g(sch_1):page393_i95@pure_quanta.q_cap_diffbus(chips)',
 P_PATH='@t6g_mb_lib.t6g(sch_1):page330_i95@pure_quanta.q_cap_diffbus(chips)',
 PATH='I95',
 DRAWING='@T6G_MB_LIB.T6G(SCH_1):PAGE393',
 PIN_NAMES_ROTATE='TRUE',
 TOLERANCE='20%',
 MATERIAL='X6S',
 PHYS_PAGE='330',
 XY='(-7000,1350)',
 ROT='2',
 VER='2',
 PACK_TYPE='C0201',
 LOCATION='C6686',
 CDS_LIB='pure_quanta',
 CDS_PART_NAME='Q_CAP_DIFFBUS_C0201-DIFF BUS_0.22UF,6.3V,20%,X6S,SA',
 VOLTAGE='6.3V',
 PART_NUMBER='SP_CH4221MEE01',
 VALUE='DIFF BUS_0.22UF',
 PRIM_FILE='./archive_libs/logical/q_cap_diffbus/chips/chips.prt';

PART_NAME
 C6687 'Q_CAP_DIFFBUS_C0201-DIFF BUS_0.22UF,6.3V,20%,X6S,SA':;

SECTION_NUMBER 1
 '@T6G_MB_LIB.T6G(SCH_1):PAGE393_I89@PURE_QUANTA.Q_CAP_DIFFBUS(CHIPS)':
 C_PATH='@t6g_mb_lib.t6g(sch_1):page393_i89@pure_quanta.q_cap_diffbus(chips)',
 P_PATH='@t6g_mb_lib.t6g(sch_1):page330_i89@pure_quanta.q_cap_diffbus(chips)',
 PATH='I89',
 DRAWING='@T6G_MB_LIB.T6G(SCH_1):PAGE393',
 PIN_NAMES_ROTATE='TRUE',
 TOLERANCE='20%',
 MATERIAL='X6S',
 PHYS_PAGE='330',
 XY='(-7000,1200)',
 ROT='2',
 VER='2',
 PACK_TYPE='C0201',
 LOCATION='C6687',
 CDS_LIB='pure_quanta',
 CDS_PART_NAME='Q_CAP_DIFFBUS_C0201-DIFF BUS_0.22UF,6.3V,20%,X6S,SA',
 VOLTAGE='6.3V',
 PART_NUMBER='SP_CH4221MEE01',
 VALUE='DIFF BUS_0.22UF',
 PRIM_FILE='./archive_libs/logical/q_cap_diffbus/chips/chips.prt';

PART_NAME
 C6688 'Q_CAP_DIFFBUS_C0201-DIFF BUS_0.22UF,6.3V,20%,X6S,SA':;

SECTION_NUMBER 1
 '@T6G_MB_LIB.T6G(SCH_1):PAGE393_I88@PURE_QUANTA.Q_CAP_DIFFBUS(CHIPS)':
 C_PATH='@t6g_mb_lib.t6g(sch_1):page393_i88@pure_quanta.q_cap_diffbus(chips)',
 P_PATH='@t6g_mb_lib.t6g(sch_1):page330_i88@pure_quanta.q_cap_diffbus(chips)',
 PATH='I88',
 DRAWING='@T6G_MB_LIB.T6G(SCH_1):PAGE393',
 PIN_NAMES_ROTATE='TRUE',
 TOLERANCE='20%',
 MATERIAL='X6S',
 PHYS_PAGE='330',
 XY='(-7000,1150)',
 ROT='2',
 VER='2',
 PACK_TYPE='C0201',
 LOCATION='C6688',
 CDS_LIB='pure_quanta',
 CDS_PART_NAME='Q_CAP_DIFFBUS_C0201-DIFF BUS_0.22UF,6.3V,20%,X6S,SA',
 VOLTAGE='6.3V',
 PART_NUMBER='SP_CH4221MEE01',
 VALUE='DIFF BUS_0.22UF',
 PRIM_FILE='./archive_libs/logical/q_cap_diffbus/chips/chips.prt';

PART_NAME
 C6689 'Q_CAP_DIFFBUS_C0201-DIFF BUS_0.22UF,6.3V,20%,X6S,SA':;

SECTION_NUMBER 1
 '@T6G_MB_LIB.T6G(SCH_1):PAGE393_I87@PURE_QUANTA.Q_CAP_DIFFBUS(CHIPS)':
 C_PATH='@t6g_mb_lib.t6g(sch_1):page393_i87@pure_quanta.q_cap_diffbus(chips)',
 P_PATH='@t6g_mb_lib.t6g(sch_1):page330_i87@pure_quanta.q_cap_diffbus(chips)',
 PATH='I87',
 DRAWING='@T6G_MB_LIB.T6G(SCH_1):PAGE393',
 PIN_NAMES_ROTATE='TRUE',
 TOLERANCE='20%',
 MATERIAL='X6S',
 PHYS_PAGE='330',
 XY='(-7000,1000)',
 ROT='2',
 VER='2',
 PACK_TYPE='C0201',
 LOCATION='C6689',
 CDS_LIB='pure_quanta',
 CDS_PART_NAME='Q_CAP_DIFFBUS_C0201-DIFF BUS_0.22UF,6.3V,20%,X6S,SA',
 VOLTAGE='6.3V',
 PART_NUMBER='SP_CH4221MEE01',
 VALUE='DIFF BUS_0.22UF',
 PRIM_FILE='./archive_libs/logical/q_cap_diffbus/chips/chips.prt';

PART_NAME
 C6690 'Q_CAP_DIFFBUS_C0201-DIFF BUS_0.22UF,6.3V,20%,X6S,SA':;

SECTION_NUMBER 1
 '@T6G_MB_LIB.T6G(SCH_1):PAGE393_I86@PURE_QUANTA.Q_CAP_DIFFBUS(CHIPS)':
 C_PATH='@t6g_mb_lib.t6g(sch_1):page393_i86@pure_quanta.q_cap_diffbus(chips)',
 P_PATH='@t6g_mb_lib.t6g(sch_1):page330_i86@pure_quanta.q_cap_diffbus(chips)',
 PATH='I86',
 DRAWING='@T6G_MB_LIB.T6G(SCH_1):PAGE393',
 PIN_NAMES_ROTATE='TRUE',
 TOLERANCE='20%',
 MATERIAL='X6S',
 PHYS_PAGE='330',
 XY='(-7000,950)',
 ROT='2',
 VER='2',
 PACK_TYPE='C0201',
 LOCATION='C6690',
 CDS_LIB='pure_quanta',
 CDS_PART_NAME='Q_CAP_DIFFBUS_C0201-DIFF BUS_0.22UF,6.3V,20%,X6S,SA',
 VOLTAGE='6.3V',
 PART_NUMBER='SP_CH4221MEE01',
 VALUE='DIFF BUS_0.22UF',
 PRIM_FILE='./archive_libs/logical/q_cap_diffbus/chips/chips.prt';

PART_NAME
 C6691 'Q_CAP_DIFFBUS_C0201-DIFF BUS_0.22UF,6.3V,20%,X6S,SA':;

SECTION_NUMBER 1
 '@T6G_MB_LIB.T6G(SCH_1):PAGE393_I85@PURE_QUANTA.Q_CAP_DIFFBUS(CHIPS)':
 C_PATH='@t6g_mb_lib.t6g(sch_1):page393_i85@pure_quanta.q_cap_diffbus(chips)',
 P_PATH='@t6g_mb_lib.t6g(sch_1):page330_i85@pure_quanta.q_cap_diffbus(chips)',
 PATH='I85',
 DRAWING='@T6G_MB_LIB.T6G(SCH_1):PAGE393',
 PIN_NAMES_ROTATE='TRUE',
 TOLERANCE='20%',
 MATERIAL='X6S',
 PHYS_PAGE='330',
 XY='(-7000,800)',
 ROT='2',
 VER='2',
 PACK_TYPE='C0201',
 LOCATION='C6691',
 CDS_LIB='pure_quanta',
 CDS_PART_NAME='Q_CAP_DIFFBUS_C0201-DIFF BUS_0.22UF,6.3V,20%,X6S,SA',
 VOLTAGE='6.3V',
 PART_NUMBER='SP_CH4221MEE01',
 VALUE='DIFF BUS_0.22UF',
 PRIM_FILE='./archive_libs/logical/q_cap_diffbus/chips/chips.prt';

PART_NAME
 C6692 'Q_CAP_DIFFBUS_C0201-DIFF BUS_0.22UF,6.3V,20%,X6S,SA':;

SECTION_NUMBER 1
 '@T6G_MB_LIB.T6G(SCH_1):PAGE393_I84@PURE_QUANTA.Q_CAP_DIFFBUS(CHIPS)':
 C_PATH='@t6g_mb_lib.t6g(sch_1):page393_i84@pure_quanta.q_cap_diffbus(chips)',
 P_PATH='@t6g_mb_lib.t6g(sch_1):page330_i84@pure_quanta.q_cap_diffbus(chips)',
 PATH='I84',
 DRAWING='@T6G_MB_LIB.T6G(SCH_1):PAGE393',
 PIN_NAMES_ROTATE='TRUE',
 TOLERANCE='20%',
 MATERIAL='X6S',
 PHYS_PAGE='330',
 XY='(-7000,750)',
 ROT='2',
 VER='2',
 PACK_TYPE='C0201',
 LOCATION='C6692',
 CDS_LIB='pure_quanta',
 CDS_PART_NAME='Q_CAP_DIFFBUS_C0201-DIFF BUS_0.22UF,6.3V,20%,X6S,SA',
 VOLTAGE='6.3V',
 PART_NUMBER='SP_CH4221MEE01',
 VALUE='DIFF BUS_0.22UF',
 PRIM_FILE='./archive_libs/logical/q_cap_diffbus/chips/chips.prt';

PART_NAME
 C6693 'Q_CAP_DIFFBUS_C0201-DIFF BUS_0.22UF,6.3V,20%,X6S,SA':;

SECTION_NUMBER 1
 '@T6G_MB_LIB.T6G(SCH_1):PAGE450_I34@PURE_QUANTA.Q_CAP_DIFFBUS(CHIPS)':
 C_PATH='@t6g_mb_lib.t6g(sch_1):page450_i34@pure_quanta.q_cap_diffbus(chips)',
 P_PATH='@t6g_mb_lib.t6g(sch_1):page341_i34@pure_quanta.q_cap_diffbus(chips)',
 PATH='I34',
 DRAWING='@T6G_MB_LIB.T6G(SCH_1):PAGE450',
 PIN_NAMES_ROTATE='TRUE',
 TOLERANCE='20%',
 MATERIAL='X6S',
 PHYS_PAGE='341',
 XY='(-2325,2175)',
 ROT='2',
 VER='2',
 PACK_TYPE='C0201',
 LOCATION='C6693',
 CDS_LIB='pure_quanta',
 CDS_PART_NAME='Q_CAP_DIFFBUS_C0201-DIFF BUS_0.22UF,6.3V,20%,X6S,SA',
 VOLTAGE='6.3V',
 PART_NUMBER='SP_CH4221MEE01',
 VALUE='DIFF BUS_0.22UF',
 PRIM_FILE='./archive_libs/logical/q_cap_diffbus/chips/chips.prt';

PART_NAME
 C6694 'Q_CAP_DIFFBUS_C0201-DIFF BUS_0.22UF,6.3V,20%,X6S,SA':;

SECTION_NUMBER 1
 '@T6G_MB_LIB.T6G(SCH_1):PAGE450_I35@PURE_QUANTA.Q_CAP_DIFFBUS(CHIPS)':
 C_PATH='@t6g_mb_lib.t6g(sch_1):page450_i35@pure_quanta.q_cap_diffbus(chips)',
 P_PATH='@t6g_mb_lib.t6g(sch_1):page341_i35@pure_quanta.q_cap_diffbus(chips)',
 PATH='I35',
 DRAWING='@T6G_MB_LIB.T6G(SCH_1):PAGE450',
 PIN_NAMES_ROTATE='TRUE',
 TOLERANCE='20%',
 MATERIAL='X6S',
 PHYS_PAGE='341',
 XY='(-2325,2125)',
 ROT='2',
 VER='2',
 PACK_TYPE='C0201',
 LOCATION='C6694',
 CDS_LIB='pure_quanta',
 CDS_PART_NAME='Q_CAP_DIFFBUS_C0201-DIFF BUS_0.22UF,6.3V,20%,X6S,SA',
 VOLTAGE='6.3V',
 PART_NUMBER='SP_CH4221MEE01',
 VALUE='DIFF BUS_0.22UF',
 PRIM_FILE='./archive_libs/logical/q_cap_diffbus/chips/chips.prt';

PART_NAME
 C6695 'Q_CAP_DIFFBUS_C0201-DIFF BUS_0.22UF,6.3V,20%,X6S,SA':;

SECTION_NUMBER 1
 '@T6G_MB_LIB.T6G(SCH_1):PAGE450_I29@PURE_QUANTA.Q_CAP_DIFFBUS(CHIPS)':
 C_PATH='@t6g_mb_lib.t6g(sch_1):page450_i29@pure_quanta.q_cap_diffbus(chips)',
 P_PATH='@t6g_mb_lib.t6g(sch_1):page341_i29@pure_quanta.q_cap_diffbus(chips)',
 PATH='I29',
 DRAWING='@T6G_MB_LIB.T6G(SCH_1):PAGE450',
 PIN_NAMES_ROTATE='TRUE',
 TOLERANCE='20%',
 MATERIAL='X6S',
 PHYS_PAGE='341',
 XY='(-2325,1975)',
 ROT='2',
 VER='2',
 PACK_TYPE='C0201',
 LOCATION='C6695',
 CDS_LIB='pure_quanta',
 CDS_PART_NAME='Q_CAP_DIFFBUS_C0201-DIFF BUS_0.22UF,6.3V,20%,X6S,SA',
 VOLTAGE='6.3V',
 PART_NUMBER='SP_CH4221MEE01',
 VALUE='DIFF BUS_0.22UF',
 PRIM_FILE='./archive_libs/logical/q_cap_diffbus/chips/chips.prt';

PART_NAME
 C6696 'Q_CAP_DIFFBUS_C0201-DIFF BUS_0.22UF,6.3V,20%,X6S,SA':;

SECTION_NUMBER 1
 '@T6G_MB_LIB.T6G(SCH_1):PAGE450_I28@PURE_QUANTA.Q_CAP_DIFFBUS(CHIPS)':
 C_PATH='@t6g_mb_lib.t6g(sch_1):page450_i28@pure_quanta.q_cap_diffbus(chips)',
 P_PATH='@t6g_mb_lib.t6g(sch_1):page341_i28@pure_quanta.q_cap_diffbus(chips)',
 PATH='I28',
 DRAWING='@T6G_MB_LIB.T6G(SCH_1):PAGE450',
 PIN_NAMES_ROTATE='TRUE',
 TOLERANCE='20%',
 MATERIAL='X6S',
 PHYS_PAGE='341',
 XY='(-2325,1925)',
 ROT='2',
 VER='2',
 PACK_TYPE='C0201',
 LOCATION='C6696',
 CDS_LIB='pure_quanta',
 CDS_PART_NAME='Q_CAP_DIFFBUS_C0201-DIFF BUS_0.22UF,6.3V,20%,X6S,SA',
 VOLTAGE='6.3V',
 PART_NUMBER='SP_CH4221MEE01',
 VALUE='DIFF BUS_0.22UF',
 PRIM_FILE='./archive_libs/logical/q_cap_diffbus/chips/chips.prt';

PART_NAME
 C6697 'Q_CAP_DIFFBUS_C0201-DIFF BUS_0.22UF,6.3V,20%,X6S,SA':;

SECTION_NUMBER 1
 '@T6G_MB_LIB.T6G(SCH_1):PAGE450_I30@PURE_QUANTA.Q_CAP_DIFFBUS(CHIPS)':
 C_PATH='@t6g_mb_lib.t6g(sch_1):page450_i30@pure_quanta.q_cap_diffbus(chips)',
 P_PATH='@t6g_mb_lib.t6g(sch_1):page341_i30@pure_quanta.q_cap_diffbus(chips)',
 PATH='I30',
 DRAWING='@T6G_MB_LIB.T6G(SCH_1):PAGE450',
 PIN_NAMES_ROTATE='TRUE',
 TOLERANCE='20%',
 MATERIAL='X6S',
 PHYS_PAGE='341',
 XY='(-2325,1775)',
 ROT='2',
 VER='2',
 PACK_TYPE='C0201',
 LOCATION='C6697',
 CDS_LIB='pure_quanta',
 CDS_PART_NAME='Q_CAP_DIFFBUS_C0201-DIFF BUS_0.22UF,6.3V,20%,X6S,SA',
 VOLTAGE='6.3V',
 PART_NUMBER='SP_CH4221MEE01',
 VALUE='DIFF BUS_0.22UF',
 PRIM_FILE='./archive_libs/logical/q_cap_diffbus/chips/chips.prt';

PART_NAME
 C6698 'Q_CAP_DIFFBUS_C0201-DIFF BUS_0.22UF,6.3V,20%,X6S,SA':;

SECTION_NUMBER 1
 '@T6G_MB_LIB.T6G(SCH_1):PAGE450_I27@PURE_QUANTA.Q_CAP_DIFFBUS(CHIPS)':
 C_PATH='@t6g_mb_lib.t6g(sch_1):page450_i27@pure_quanta.q_cap_diffbus(chips)',
 P_PATH='@t6g_mb_lib.t6g(sch_1):page341_i27@pure_quanta.q_cap_diffbus(chips)',
 PATH='I27',
 DRAWING='@T6G_MB_LIB.T6G(SCH_1):PAGE450',
 PIN_NAMES_ROTATE='TRUE',
 TOLERANCE='20%',
 MATERIAL='X6S',
 PHYS_PAGE='341',
 XY='(-2325,1725)',
 ROT='2',
 VER='2',
 PACK_TYPE='C0201',
 LOCATION='C6698',
 CDS_LIB='pure_quanta',
 CDS_PART_NAME='Q_CAP_DIFFBUS_C0201-DIFF BUS_0.22UF,6.3V,20%,X6S,SA',
 VOLTAGE='6.3V',
 PART_NUMBER='SP_CH4221MEE01',
 VALUE='DIFF BUS_0.22UF',
 PRIM_FILE='./archive_libs/logical/q_cap_diffbus/chips/chips.prt';

PART_NAME
 C6699 'Q_CAP_DIFFBUS_C0201-DIFF BUS_0.22UF,6.3V,20%,X6S,SA':;

SECTION_NUMBER 1
 '@T6G_MB_LIB.T6G(SCH_1):PAGE450_I25@PURE_QUANTA.Q_CAP_DIFFBUS(CHIPS)':
 C_PATH='@t6g_mb_lib.t6g(sch_1):page450_i25@pure_quanta.q_cap_diffbus(chips)',
 P_PATH='@t6g_mb_lib.t6g(sch_1):page341_i25@pure_quanta.q_cap_diffbus(chips)',
 PATH='I25',
 DRAWING='@T6G_MB_LIB.T6G(SCH_1):PAGE450',
 PIN_NAMES_ROTATE='TRUE',
 TOLERANCE='20%',
 MATERIAL='X6S',
 PHYS_PAGE='341',
 XY='(-2325,1575)',
 ROT='2',
 VER='2',
 PACK_TYPE='C0201',
 LOCATION='C6699',
 CDS_LIB='pure_quanta',
 CDS_PART_NAME='Q_CAP_DIFFBUS_C0201-DIFF BUS_0.22UF,6.3V,20%,X6S,SA',
 VOLTAGE='6.3V',
 PART_NUMBER='SP_CH4221MEE01',
 VALUE='DIFF BUS_0.22UF',
 PRIM_FILE='./archive_libs/logical/q_cap_diffbus/chips/chips.prt';

PART_NAME
 C6700 'Q_CAP_DIFFBUS_C0201-DIFF BUS_0.22UF,6.3V,20%,X6S,SA':;

SECTION_NUMBER 1
 '@T6G_MB_LIB.T6G(SCH_1):PAGE450_I26@PURE_QUANTA.Q_CAP_DIFFBUS(CHIPS)':
 C_PATH='@t6g_mb_lib.t6g(sch_1):page450_i26@pure_quanta.q_cap_diffbus(chips)',
 P_PATH='@t6g_mb_lib.t6g(sch_1):page341_i26@pure_quanta.q_cap_diffbus(chips)',
 PATH='I26',
 DRAWING='@T6G_MB_LIB.T6G(SCH_1):PAGE450',
 PIN_NAMES_ROTATE='TRUE',
 TOLERANCE='20%',
 MATERIAL='X6S',
 PHYS_PAGE='341',
 XY='(-2325,1525)',
 ROT='2',
 VER='2',
 PACK_TYPE='C0201',
 LOCATION='C6700',
 CDS_LIB='pure_quanta',
 CDS_PART_NAME='Q_CAP_DIFFBUS_C0201-DIFF BUS_0.22UF,6.3V,20%,X6S,SA',
 VOLTAGE='6.3V',
 PART_NUMBER='SP_CH4221MEE01',
 VALUE='DIFF BUS_0.22UF',
 PRIM_FILE='./archive_libs/logical/q_cap_diffbus/chips/chips.prt';

PART_NAME
 C6701 'Q_CAP_DIFFBUS_C0201-DIFF BUS_0.22UF,6.3V,20%,X6S,SA':;

SECTION_NUMBER 1
 '@T6G_MB_LIB.T6G(SCH_1):PAGE450_I24@PURE_QUANTA.Q_CAP_DIFFBUS(CHIPS)':
 C_PATH='@t6g_mb_lib.t6g(sch_1):page450_i24@pure_quanta.q_cap_diffbus(chips)',
 P_PATH='@t6g_mb_lib.t6g(sch_1):page341_i24@pure_quanta.q_cap_diffbus(chips)',
 PATH='I24',
 DRAWING='@T6G_MB_LIB.T6G(SCH_1):PAGE450',
 PIN_NAMES_ROTATE='TRUE',
 TOLERANCE='20%',
 MATERIAL='X6S',
 PHYS_PAGE='341',
 XY='(-2325,1375)',
 ROT='2',
 VER='2',
 PACK_TYPE='C0201',
 LOCATION='C6701',
 CDS_LIB='pure_quanta',
 CDS_PART_NAME='Q_CAP_DIFFBUS_C0201-DIFF BUS_0.22UF,6.3V,20%,X6S,SA',
 VOLTAGE='6.3V',
 PART_NUMBER='SP_CH4221MEE01',
 VALUE='DIFF BUS_0.22UF',
 PRIM_FILE='./archive_libs/logical/q_cap_diffbus/chips/chips.prt';

PART_NAME
 C6702 'Q_CAP_DIFFBUS_C0201-DIFF BUS_0.22UF,6.3V,20%,X6S,SA':;

SECTION_NUMBER 1
 '@T6G_MB_LIB.T6G(SCH_1):PAGE450_I23@PURE_QUANTA.Q_CAP_DIFFBUS(CHIPS)':
 C_PATH='@t6g_mb_lib.t6g(sch_1):page450_i23@pure_quanta.q_cap_diffbus(chips)',
 P_PATH='@t6g_mb_lib.t6g(sch_1):page341_i23@pure_quanta.q_cap_diffbus(chips)',
 PATH='I23',
 DRAWING='@T6G_MB_LIB.T6G(SCH_1):PAGE450',
 PIN_NAMES_ROTATE='TRUE',
 TOLERANCE='20%',
 MATERIAL='X6S',
 PHYS_PAGE='341',
 XY='(-2325,1325)',
 ROT='2',
 VER='2',
 PACK_TYPE='C0201',
 LOCATION='C6702',
 CDS_LIB='pure_quanta',
 CDS_PART_NAME='Q_CAP_DIFFBUS_C0201-DIFF BUS_0.22UF,6.3V,20%,X6S,SA',
 VOLTAGE='6.3V',
 PART_NUMBER='SP_CH4221MEE01',
 VALUE='DIFF BUS_0.22UF',
 PRIM_FILE='./archive_libs/logical/q_cap_diffbus/chips/chips.prt';

PART_NAME
 C6703 'Q_CAP_DIFFBUS_C0201-DIFF BUS_0.22UF,6.3V,20%,X6S,SA':;

SECTION_NUMBER 1
 '@T6G_MB_LIB.T6G(SCH_1):PAGE450_I22@PURE_QUANTA.Q_CAP_DIFFBUS(CHIPS)':
 C_PATH='@t6g_mb_lib.t6g(sch_1):page450_i22@pure_quanta.q_cap_diffbus(chips)',
 P_PATH='@t6g_mb_lib.t6g(sch_1):page341_i22@pure_quanta.q_cap_diffbus(chips)',
 PATH='I22',
 DRAWING='@T6G_MB_LIB.T6G(SCH_1):PAGE450',
 PIN_NAMES_ROTATE='TRUE',
 TOLERANCE='20%',
 MATERIAL='X6S',
 PHYS_PAGE='341',
 XY='(-2325,1175)',
 ROT='2',
 VER='2',
 PACK_TYPE='C0201',
 LOCATION='C6703',
 CDS_LIB='pure_quanta',
 CDS_PART_NAME='Q_CAP_DIFFBUS_C0201-DIFF BUS_0.22UF,6.3V,20%,X6S,SA',
 VOLTAGE='6.3V',
 PART_NUMBER='SP_CH4221MEE01',
 VALUE='DIFF BUS_0.22UF',
 PRIM_FILE='./archive_libs/logical/q_cap_diffbus/chips/chips.prt';

PART_NAME
 C6704 'Q_CAP_DIFFBUS_C0201-DIFF BUS_0.22UF,6.3V,20%,X6S,SA':;

SECTION_NUMBER 1
 '@T6G_MB_LIB.T6G(SCH_1):PAGE450_I21@PURE_QUANTA.Q_CAP_DIFFBUS(CHIPS)':
 C_PATH='@t6g_mb_lib.t6g(sch_1):page450_i21@pure_quanta.q_cap_diffbus(chips)',
 P_PATH='@t6g_mb_lib.t6g(sch_1):page341_i21@pure_quanta.q_cap_diffbus(chips)',
 PATH='I21',
 DRAWING='@T6G_MB_LIB.T6G(SCH_1):PAGE450',
 PIN_NAMES_ROTATE='TRUE',
 TOLERANCE='20%',
 MATERIAL='X6S',
 PHYS_PAGE='341',
 XY='(-2325,1125)',
 ROT='2',
 VER='2',
 PACK_TYPE='C0201',
 LOCATION='C6704',
 CDS_LIB='pure_quanta',
 CDS_PART_NAME='Q_CAP_DIFFBUS_C0201-DIFF BUS_0.22UF,6.3V,20%,X6S,SA',
 VOLTAGE='6.3V',
 PART_NUMBER='SP_CH4221MEE01',
 VALUE='DIFF BUS_0.22UF',
 PRIM_FILE='./archive_libs/logical/q_cap_diffbus/chips/chips.prt';

PART_NAME
 C6705 'Q_CAP_DIFFBUS_C0201-DIFF BUS_0.22UF,6.3V,20%,X6S,SA':;

SECTION_NUMBER 1
 '@T6G_MB_LIB.T6G(SCH_1):PAGE450_I20@PURE_QUANTA.Q_CAP_DIFFBUS(CHIPS)':
 C_PATH='@t6g_mb_lib.t6g(sch_1):page450_i20@pure_quanta.q_cap_diffbus(chips)',
 P_PATH='@t6g_mb_lib.t6g(sch_1):page341_i20@pure_quanta.q_cap_diffbus(chips)',
 PATH='I20',
 DRAWING='@T6G_MB_LIB.T6G(SCH_1):PAGE450',
 PIN_NAMES_ROTATE='TRUE',
 TOLERANCE='20%',
 MATERIAL='X6S',
 PHYS_PAGE='341',
 XY='(-2325,975)',
 ROT='2',
 VER='2',
 PACK_TYPE='C0201',
 LOCATION='C6705',
 CDS_LIB='pure_quanta',
 CDS_PART_NAME='Q_CAP_DIFFBUS_C0201-DIFF BUS_0.22UF,6.3V,20%,X6S,SA',
 VOLTAGE='6.3V',
 PART_NUMBER='SP_CH4221MEE01',
 VALUE='DIFF BUS_0.22UF',
 PRIM_FILE='./archive_libs/logical/q_cap_diffbus/chips/chips.prt';

PART_NAME
 C6706 'Q_CAP_DIFFBUS_C0201-DIFF BUS_0.22UF,6.3V,20%,X6S,SA':;

SECTION_NUMBER 1
 '@T6G_MB_LIB.T6G(SCH_1):PAGE450_I19@PURE_QUANTA.Q_CAP_DIFFBUS(CHIPS)':
 C_PATH='@t6g_mb_lib.t6g(sch_1):page450_i19@pure_quanta.q_cap_diffbus(chips)',
 P_PATH='@t6g_mb_lib.t6g(sch_1):page341_i19@pure_quanta.q_cap_diffbus(chips)',
 PATH='I19',
 DRAWING='@T6G_MB_LIB.T6G(SCH_1):PAGE450',
 PIN_NAMES_ROTATE='TRUE',
 TOLERANCE='20%',
 MATERIAL='X6S',
 PHYS_PAGE='341',
 XY='(-2325,925)',
 ROT='2',
 VER='2',
 PACK_TYPE='C0201',
 LOCATION='C6706',
 CDS_LIB='pure_quanta',
 CDS_PART_NAME='Q_CAP_DIFFBUS_C0201-DIFF BUS_0.22UF,6.3V,20%,X6S,SA',
 VOLTAGE='6.3V',
 PART_NUMBER='SP_CH4221MEE01',
 VALUE='DIFF BUS_0.22UF',
 PRIM_FILE='./archive_libs/logical/q_cap_diffbus/chips/chips.prt';

PART_NAME
 C6707 'Q_CAP_DIFFBUS_C0201-DIFF BUS_0.22UF,6.3V,20%,X6S,SA':;

SECTION_NUMBER 1
 '@T6G_MB_LIB.T6G(SCH_1):PAGE450_I18@PURE_QUANTA.Q_CAP_DIFFBUS(CHIPS)':
 C_PATH='@t6g_mb_lib.t6g(sch_1):page450_i18@pure_quanta.q_cap_diffbus(chips)',
 P_PATH='@t6g_mb_lib.t6g(sch_1):page341_i18@pure_quanta.q_cap_diffbus(chips)',
 PATH='I18',
 DRAWING='@T6G_MB_LIB.T6G(SCH_1):PAGE450',
 PIN_NAMES_ROTATE='TRUE',
 TOLERANCE='20%',
 MATERIAL='X6S',
 PHYS_PAGE='341',
 XY='(-2325,775)',
 ROT='2',
 VER='2',
 PACK_TYPE='C0201',
 LOCATION='C6707',
 CDS_LIB='pure_quanta',
 CDS_PART_NAME='Q_CAP_DIFFBUS_C0201-DIFF BUS_0.22UF,6.3V,20%,X6S,SA',
 VOLTAGE='6.3V',
 PART_NUMBER='SP_CH4221MEE01',
 VALUE='DIFF BUS_0.22UF',
 PRIM_FILE='./archive_libs/logical/q_cap_diffbus/chips/chips.prt';

PART_NAME
 C6708 'Q_CAP_DIFFBUS_C0201-DIFF BUS_0.22UF,6.3V,20%,X6S,SA':;

SECTION_NUMBER 1
 '@T6G_MB_LIB.T6G(SCH_1):PAGE450_I17@PURE_QUANTA.Q_CAP_DIFFBUS(CHIPS)':
 C_PATH='@t6g_mb_lib.t6g(sch_1):page450_i17@pure_quanta.q_cap_diffbus(chips)',
 P_PATH='@t6g_mb_lib.t6g(sch_1):page341_i17@pure_quanta.q_cap_diffbus(chips)',
 PATH='I17',
 DRAWING='@T6G_MB_LIB.T6G(SCH_1):PAGE450',
 PIN_NAMES_ROTATE='TRUE',
 TOLERANCE='20%',
 MATERIAL='X6S',
 PHYS_PAGE='341',
 XY='(-2325,725)',
 ROT='2',
 VER='2',
 PACK_TYPE='C0201',
 LOCATION='C6708',
 CDS_LIB='pure_quanta',
 CDS_PART_NAME='Q_CAP_DIFFBUS_C0201-DIFF BUS_0.22UF,6.3V,20%,X6S,SA',
 VOLTAGE='6.3V',
 PART_NUMBER='SP_CH4221MEE01',
 VALUE='DIFF BUS_0.22UF',
 PRIM_FILE='./archive_libs/logical/q_cap_diffbus/chips/chips.prt';

PART_NAME
 C6709 'Q_CAP_DIFFBUS_C0201-DIFF BUS_0.22UF,6.3V,20%,X6S,SA':;

SECTION_NUMBER 1
 '@T6G_MB_LIB.T6G(SCH_1):PAGE450_I102@PURE_QUANTA.Q_CAP_DIFFBUS(CHIPS)':
 C_PATH='@t6g_mb_lib.t6g(sch_1):page450_i102@pure_quanta.q_cap_diffbus(chips)',
 P_PATH='@t6g_mb_lib.t6g(sch_1):page341_i102@pure_quanta.q_cap_diffbus(chips)',
 PATH='I102',
 DRAWING='@T6G_MB_LIB.T6G(SCH_1):PAGE450',
 PIN_NAMES_ROTATE='TRUE',
 TOLERANCE='20%',
 MATERIAL='X6S',
 PHYS_PAGE='341',
 XY='(-7100,2250)',
 ROT='2',
 VER='2',
 PACK_TYPE='C0201',
 LOCATION='C6709',
 CDS_LIB='pure_quanta',
 CDS_PART_NAME='Q_CAP_DIFFBUS_C0201-DIFF BUS_0.22UF,6.3V,20%,X6S,SA',
 VOLTAGE='6.3V',
 PART_NUMBER='SP_CH4221MEE01',
 VALUE='DIFF BUS_0.22UF',
 PRIM_FILE='./archive_libs/logical/q_cap_diffbus/chips/chips.prt';

PART_NAME
 C6710 'Q_CAP_DIFFBUS_C0201-DIFF BUS_0.22UF,6.3V,20%,X6S,SA':;

SECTION_NUMBER 1
 '@T6G_MB_LIB.T6G(SCH_1):PAGE450_I103@PURE_QUANTA.Q_CAP_DIFFBUS(CHIPS)':
 C_PATH='@t6g_mb_lib.t6g(sch_1):page450_i103@pure_quanta.q_cap_diffbus(chips)',
 P_PATH='@t6g_mb_lib.t6g(sch_1):page341_i103@pure_quanta.q_cap_diffbus(chips)',
 PATH='I103',
 DRAWING='@T6G_MB_LIB.T6G(SCH_1):PAGE450',
 PIN_NAMES_ROTATE='TRUE',
 TOLERANCE='20%',
 MATERIAL='X6S',
 PHYS_PAGE='341',
 XY='(-7100,2200)',
 ROT='2',
 VER='2',
 PACK_TYPE='C0201',
 LOCATION='C6710',
 CDS_LIB='pure_quanta',
 CDS_PART_NAME='Q_CAP_DIFFBUS_C0201-DIFF BUS_0.22UF,6.3V,20%,X6S,SA',
 VOLTAGE='6.3V',
 PART_NUMBER='SP_CH4221MEE01',
 VALUE='DIFF BUS_0.22UF',
 PRIM_FILE='./archive_libs/logical/q_cap_diffbus/chips/chips.prt';

PART_NAME
 C6711 'Q_CAP_DIFFBUS_C0201-DIFF BUS_0.22UF,6.3V,20%,X6S,SA':;

SECTION_NUMBER 1
 '@T6G_MB_LIB.T6G(SCH_1):PAGE450_I99@PURE_QUANTA.Q_CAP_DIFFBUS(CHIPS)':
 C_PATH='@t6g_mb_lib.t6g(sch_1):page450_i99@pure_quanta.q_cap_diffbus(chips)',
 P_PATH='@t6g_mb_lib.t6g(sch_1):page341_i99@pure_quanta.q_cap_diffbus(chips)',
 PATH='I99',
 DRAWING='@T6G_MB_LIB.T6G(SCH_1):PAGE450',
 PIN_NAMES_ROTATE='TRUE',
 TOLERANCE='20%',
 MATERIAL='X6S',
 PHYS_PAGE='341',
 XY='(-7100,2050)',
 ROT='2',
 VER='2',
 PACK_TYPE='C0201',
 LOCATION='C6711',
 CDS_LIB='pure_quanta',
 CDS_PART_NAME='Q_CAP_DIFFBUS_C0201-DIFF BUS_0.22UF,6.3V,20%,X6S,SA',
 VOLTAGE='6.3V',
 PART_NUMBER='SP_CH4221MEE01',
 VALUE='DIFF BUS_0.22UF',
 PRIM_FILE='./archive_libs/logical/q_cap_diffbus/chips/chips.prt';

PART_NAME
 C6712 'Q_CAP_DIFFBUS_C0201-DIFF BUS_0.22UF,6.3V,20%,X6S,SA':;

SECTION_NUMBER 1
 '@T6G_MB_LIB.T6G(SCH_1):PAGE450_I98@PURE_QUANTA.Q_CAP_DIFFBUS(CHIPS)':
 C_PATH='@t6g_mb_lib.t6g(sch_1):page450_i98@pure_quanta.q_cap_diffbus(chips)',
 P_PATH='@t6g_mb_lib.t6g(sch_1):page341_i98@pure_quanta.q_cap_diffbus(chips)',
 PATH='I98',
 DRAWING='@T6G_MB_LIB.T6G(SCH_1):PAGE450',
 PIN_NAMES_ROTATE='TRUE',
 TOLERANCE='20%',
 MATERIAL='X6S',
 PHYS_PAGE='341',
 XY='(-7100,2000)',
 ROT='2',
 VER='2',
 PACK_TYPE='C0201',
 LOCATION='C6712',
 CDS_LIB='pure_quanta',
 CDS_PART_NAME='Q_CAP_DIFFBUS_C0201-DIFF BUS_0.22UF,6.3V,20%,X6S,SA',
 VOLTAGE='6.3V',
 PART_NUMBER='SP_CH4221MEE01',
 VALUE='DIFF BUS_0.22UF',
 PRIM_FILE='./archive_libs/logical/q_cap_diffbus/chips/chips.prt';

PART_NAME
 C6713 'Q_CAP_DIFFBUS_C0201-DIFF BUS_0.22UF,6.3V,20%,X6S,SA':;

SECTION_NUMBER 1
 '@T6G_MB_LIB.T6G(SCH_1):PAGE450_I97@PURE_QUANTA.Q_CAP_DIFFBUS(CHIPS)':
 C_PATH='@t6g_mb_lib.t6g(sch_1):page450_i97@pure_quanta.q_cap_diffbus(chips)',
 P_PATH='@t6g_mb_lib.t6g(sch_1):page341_i97@pure_quanta.q_cap_diffbus(chips)',
 PATH='I97',
 DRAWING='@T6G_MB_LIB.T6G(SCH_1):PAGE450',
 PIN_NAMES_ROTATE='TRUE',
 TOLERANCE='20%',
 MATERIAL='X6S',
 PHYS_PAGE='341',
 XY='(-7100,1850)',
 ROT='2',
 VER='2',
 PACK_TYPE='C0201',
 LOCATION='C6713',
 CDS_LIB='pure_quanta',
 CDS_PART_NAME='Q_CAP_DIFFBUS_C0201-DIFF BUS_0.22UF,6.3V,20%,X6S,SA',
 VOLTAGE='6.3V',
 PART_NUMBER='SP_CH4221MEE01',
 VALUE='DIFF BUS_0.22UF',
 PRIM_FILE='./archive_libs/logical/q_cap_diffbus/chips/chips.prt';

PART_NAME
 C6714 'Q_CAP_DIFFBUS_C0201-DIFF BUS_0.22UF,6.3V,20%,X6S,SA':;

SECTION_NUMBER 1
 '@T6G_MB_LIB.T6G(SCH_1):PAGE450_I96@PURE_QUANTA.Q_CAP_DIFFBUS(CHIPS)':
 C_PATH='@t6g_mb_lib.t6g(sch_1):page450_i96@pure_quanta.q_cap_diffbus(chips)',
 P_PATH='@t6g_mb_lib.t6g(sch_1):page341_i96@pure_quanta.q_cap_diffbus(chips)',
 PATH='I96',
 DRAWING='@T6G_MB_LIB.T6G(SCH_1):PAGE450',
 PIN_NAMES_ROTATE='TRUE',
 TOLERANCE='20%',
 MATERIAL='X6S',
 PHYS_PAGE='341',
 XY='(-7100,1800)',
 ROT='2',
 VER='2',
 PACK_TYPE='C0201',
 LOCATION='C6714',
 CDS_LIB='pure_quanta',
 CDS_PART_NAME='Q_CAP_DIFFBUS_C0201-DIFF BUS_0.22UF,6.3V,20%,X6S,SA',
 VOLTAGE='6.3V',
 PART_NUMBER='SP_CH4221MEE01',
 VALUE='DIFF BUS_0.22UF',
 PRIM_FILE='./archive_libs/logical/q_cap_diffbus/chips/chips.prt';

PART_NAME
 C6715 'Q_CAP_DIFFBUS_C0201-DIFF BUS_0.22UF,6.3V,20%,X6S,SA':;

SECTION_NUMBER 1
 '@T6G_MB_LIB.T6G(SCH_1):PAGE450_I95@PURE_QUANTA.Q_CAP_DIFFBUS(CHIPS)':
 C_PATH='@t6g_mb_lib.t6g(sch_1):page450_i95@pure_quanta.q_cap_diffbus(chips)',
 P_PATH='@t6g_mb_lib.t6g(sch_1):page341_i95@pure_quanta.q_cap_diffbus(chips)',
 PATH='I95',
 DRAWING='@T6G_MB_LIB.T6G(SCH_1):PAGE450',
 PIN_NAMES_ROTATE='TRUE',
 TOLERANCE='20%',
 MATERIAL='X6S',
 PHYS_PAGE='341',
 XY='(-7100,1650)',
 ROT='2',
 VER='2',
 PACK_TYPE='C0201',
 LOCATION='C6715',
 CDS_LIB='pure_quanta',
 CDS_PART_NAME='Q_CAP_DIFFBUS_C0201-DIFF BUS_0.22UF,6.3V,20%,X6S,SA',
 VOLTAGE='6.3V',
 PART_NUMBER='SP_CH4221MEE01',
 VALUE='DIFF BUS_0.22UF',
 PRIM_FILE='./archive_libs/logical/q_cap_diffbus/chips/chips.prt';

PART_NAME
 C6716 'Q_CAP_DIFFBUS_C0201-DIFF BUS_0.22UF,6.3V,20%,X6S,SA':;

SECTION_NUMBER 1
 '@T6G_MB_LIB.T6G(SCH_1):PAGE450_I94@PURE_QUANTA.Q_CAP_DIFFBUS(CHIPS)':
 C_PATH='@t6g_mb_lib.t6g(sch_1):page450_i94@pure_quanta.q_cap_diffbus(chips)',
 P_PATH='@t6g_mb_lib.t6g(sch_1):page341_i94@pure_quanta.q_cap_diffbus(chips)',
 PATH='I94',
 DRAWING='@T6G_MB_LIB.T6G(SCH_1):PAGE450',
 PIN_NAMES_ROTATE='TRUE',
 TOLERANCE='20%',
 MATERIAL='X6S',
 PHYS_PAGE='341',
 XY='(-7100,1600)',
 ROT='2',
 VER='2',
 PACK_TYPE='C0201',
 LOCATION='C6716',
 CDS_LIB='pure_quanta',
 CDS_PART_NAME='Q_CAP_DIFFBUS_C0201-DIFF BUS_0.22UF,6.3V,20%,X6S,SA',
 VOLTAGE='6.3V',
 PART_NUMBER='SP_CH4221MEE01',
 VALUE='DIFF BUS_0.22UF',
 PRIM_FILE='./archive_libs/logical/q_cap_diffbus/chips/chips.prt';

PART_NAME
 C6717 'Q_CAP_DIFFBUS_C0201-DIFF BUS_0.22UF,6.3V,20%,X6S,SA':;

SECTION_NUMBER 1
 '@T6G_MB_LIB.T6G(SCH_1):PAGE450_I93@PURE_QUANTA.Q_CAP_DIFFBUS(CHIPS)':
 C_PATH='@t6g_mb_lib.t6g(sch_1):page450_i93@pure_quanta.q_cap_diffbus(chips)',
 P_PATH='@t6g_mb_lib.t6g(sch_1):page341_i93@pure_quanta.q_cap_diffbus(chips)',
 PATH='I93',
 DRAWING='@T6G_MB_LIB.T6G(SCH_1):PAGE450',
 PIN_NAMES_ROTATE='TRUE',
 TOLERANCE='20%',
 MATERIAL='X6S',
 PHYS_PAGE='341',
 XY='(-7100,1450)',
 ROT='2',
 VER='2',
 PACK_TYPE='C0201',
 LOCATION='C6717',
 CDS_LIB='pure_quanta',
 CDS_PART_NAME='Q_CAP_DIFFBUS_C0201-DIFF BUS_0.22UF,6.3V,20%,X6S,SA',
 VOLTAGE='6.3V',
 PART_NUMBER='SP_CH4221MEE01',
 VALUE='DIFF BUS_0.22UF',
 PRIM_FILE='./archive_libs/logical/q_cap_diffbus/chips/chips.prt';

PART_NAME
 C6718 'Q_CAP_DIFFBUS_C0201-DIFF BUS_0.22UF,6.3V,20%,X6S,SA':;

SECTION_NUMBER 1
 '@T6G_MB_LIB.T6G(SCH_1):PAGE450_I92@PURE_QUANTA.Q_CAP_DIFFBUS(CHIPS)':
 C_PATH='@t6g_mb_lib.t6g(sch_1):page450_i92@pure_quanta.q_cap_diffbus(chips)',
 P_PATH='@t6g_mb_lib.t6g(sch_1):page341_i92@pure_quanta.q_cap_diffbus(chips)',
 PATH='I92',
 DRAWING='@T6G_MB_LIB.T6G(SCH_1):PAGE450',
 PIN_NAMES_ROTATE='TRUE',
 TOLERANCE='20%',
 MATERIAL='X6S',
 PHYS_PAGE='341',
 XY='(-7100,1400)',
 ROT='2',
 VER='2',
 PACK_TYPE='C0201',
 LOCATION='C6718',
 CDS_LIB='pure_quanta',
 CDS_PART_NAME='Q_CAP_DIFFBUS_C0201-DIFF BUS_0.22UF,6.3V,20%,X6S,SA',
 VOLTAGE='6.3V',
 PART_NUMBER='SP_CH4221MEE01',
 VALUE='DIFF BUS_0.22UF',
 PRIM_FILE='./archive_libs/logical/q_cap_diffbus/chips/chips.prt';

PART_NAME
 C6719 'Q_CAP_DIFFBUS_C0201-DIFF BUS_0.22UF,6.3V,20%,X6S,SA':;

SECTION_NUMBER 1
 '@T6G_MB_LIB.T6G(SCH_1):PAGE450_I91@PURE_QUANTA.Q_CAP_DIFFBUS(CHIPS)':
 C_PATH='@t6g_mb_lib.t6g(sch_1):page450_i91@pure_quanta.q_cap_diffbus(chips)',
 P_PATH='@t6g_mb_lib.t6g(sch_1):page341_i91@pure_quanta.q_cap_diffbus(chips)',
 PATH='I91',
 DRAWING='@T6G_MB_LIB.T6G(SCH_1):PAGE450',
 PIN_NAMES_ROTATE='TRUE',
 TOLERANCE='20%',
 MATERIAL='X6S',
 PHYS_PAGE='341',
 XY='(-7100,1250)',
 ROT='2',
 VER='2',
 PACK_TYPE='C0201',
 LOCATION='C6719',
 CDS_LIB='pure_quanta',
 CDS_PART_NAME='Q_CAP_DIFFBUS_C0201-DIFF BUS_0.22UF,6.3V,20%,X6S,SA',
 VOLTAGE='6.3V',
 PART_NUMBER='SP_CH4221MEE01',
 VALUE='DIFF BUS_0.22UF',
 PRIM_FILE='./archive_libs/logical/q_cap_diffbus/chips/chips.prt';

PART_NAME
 C6720 'Q_CAP_DIFFBUS_C0201-DIFF BUS_0.22UF,6.3V,20%,X6S,SA':;

SECTION_NUMBER 1
 '@T6G_MB_LIB.T6G(SCH_1):PAGE450_I90@PURE_QUANTA.Q_CAP_DIFFBUS(CHIPS)':
 C_PATH='@t6g_mb_lib.t6g(sch_1):page450_i90@pure_quanta.q_cap_diffbus(chips)',
 P_PATH='@t6g_mb_lib.t6g(sch_1):page341_i90@pure_quanta.q_cap_diffbus(chips)',
 PATH='I90',
 DRAWING='@T6G_MB_LIB.T6G(SCH_1):PAGE450',
 PIN_NAMES_ROTATE='TRUE',
 TOLERANCE='20%',
 MATERIAL='X6S',
 PHYS_PAGE='341',
 XY='(-7100,1200)',
 ROT='2',
 VER='2',
 PACK_TYPE='C0201',
 LOCATION='C6720',
 CDS_LIB='pure_quanta',
 CDS_PART_NAME='Q_CAP_DIFFBUS_C0201-DIFF BUS_0.22UF,6.3V,20%,X6S,SA',
 VOLTAGE='6.3V',
 PART_NUMBER='SP_CH4221MEE01',
 VALUE='DIFF BUS_0.22UF',
 PRIM_FILE='./archive_libs/logical/q_cap_diffbus/chips/chips.prt';

PART_NAME
 C6721 'Q_CAP_DIFFBUS_C0201-DIFF BUS_0.22UF,6.3V,20%,X6S,SA':;

SECTION_NUMBER 1
 '@T6G_MB_LIB.T6G(SCH_1):PAGE450_I84@PURE_QUANTA.Q_CAP_DIFFBUS(CHIPS)':
 C_PATH='@t6g_mb_lib.t6g(sch_1):page450_i84@pure_quanta.q_cap_diffbus(chips)',
 P_PATH='@t6g_mb_lib.t6g(sch_1):page341_i84@pure_quanta.q_cap_diffbus(chips)',
 PATH='I84',
 DRAWING='@T6G_MB_LIB.T6G(SCH_1):PAGE450',
 PIN_NAMES_ROTATE='TRUE',
 TOLERANCE='20%',
 MATERIAL='X6S',
 PHYS_PAGE='341',
 XY='(-7100,1050)',
 ROT='2',
 VER='2',
 PACK_TYPE='C0201',
 LOCATION='C6721',
 CDS_LIB='pure_quanta',
 CDS_PART_NAME='Q_CAP_DIFFBUS_C0201-DIFF BUS_0.22UF,6.3V,20%,X6S,SA',
 VOLTAGE='6.3V',
 PART_NUMBER='SP_CH4221MEE01',
 VALUE='DIFF BUS_0.22UF',
 PRIM_FILE='./archive_libs/logical/q_cap_diffbus/chips/chips.prt';

PART_NAME
 C6722 'Q_CAP_DIFFBUS_C0201-DIFF BUS_0.22UF,6.3V,20%,X6S,SA':;

SECTION_NUMBER 1
 '@T6G_MB_LIB.T6G(SCH_1):PAGE450_I83@PURE_QUANTA.Q_CAP_DIFFBUS(CHIPS)':
 C_PATH='@t6g_mb_lib.t6g(sch_1):page450_i83@pure_quanta.q_cap_diffbus(chips)',
 P_PATH='@t6g_mb_lib.t6g(sch_1):page341_i83@pure_quanta.q_cap_diffbus(chips)',
 PATH='I83',
 DRAWING='@T6G_MB_LIB.T6G(SCH_1):PAGE450',
 PIN_NAMES_ROTATE='TRUE',
 TOLERANCE='20%',
 MATERIAL='X6S',
 PHYS_PAGE='341',
 XY='(-7100,1000)',
 ROT='2',
 VER='2',
 PACK_TYPE='C0201',
 LOCATION='C6722',
 CDS_LIB='pure_quanta',
 CDS_PART_NAME='Q_CAP_DIFFBUS_C0201-DIFF BUS_0.22UF,6.3V,20%,X6S,SA',
 VOLTAGE='6.3V',
 PART_NUMBER='SP_CH4221MEE01',
 VALUE='DIFF BUS_0.22UF',
 PRIM_FILE='./archive_libs/logical/q_cap_diffbus/chips/chips.prt';

PART_NAME
 C6723 'Q_CAP_DIFFBUS_C0201-DIFF BUS_0.22UF,6.3V,20%,X6S,SA':;

SECTION_NUMBER 1
 '@T6G_MB_LIB.T6G(SCH_1):PAGE450_I82@PURE_QUANTA.Q_CAP_DIFFBUS(CHIPS)':
 C_PATH='@t6g_mb_lib.t6g(sch_1):page450_i82@pure_quanta.q_cap_diffbus(chips)',
 P_PATH='@t6g_mb_lib.t6g(sch_1):page341_i82@pure_quanta.q_cap_diffbus(chips)',
 PATH='I82',
 DRAWING='@T6G_MB_LIB.T6G(SCH_1):PAGE450',
 PIN_NAMES_ROTATE='TRUE',
 TOLERANCE='20%',
 MATERIAL='X6S',
 PHYS_PAGE='341',
 XY='(-7100,850)',
 ROT='2',
 VER='2',
 PACK_TYPE='C0201',
 LOCATION='C6723',
 CDS_LIB='pure_quanta',
 CDS_PART_NAME='Q_CAP_DIFFBUS_C0201-DIFF BUS_0.22UF,6.3V,20%,X6S,SA',
 VOLTAGE='6.3V',
 PART_NUMBER='SP_CH4221MEE01',
 VALUE='DIFF BUS_0.22UF',
 PRIM_FILE='./archive_libs/logical/q_cap_diffbus/chips/chips.prt';

PART_NAME
 C6724 'Q_CAP_DIFFBUS_C0201-DIFF BUS_0.22UF,6.3V,20%,X6S,SA':;

SECTION_NUMBER 1
 '@T6G_MB_LIB.T6G(SCH_1):PAGE450_I81@PURE_QUANTA.Q_CAP_DIFFBUS(CHIPS)':
 C_PATH='@t6g_mb_lib.t6g(sch_1):page450_i81@pure_quanta.q_cap_diffbus(chips)',
 P_PATH='@t6g_mb_lib.t6g(sch_1):page341_i81@pure_quanta.q_cap_diffbus(chips)',
 PATH='I81',
 DRAWING='@T6G_MB_LIB.T6G(SCH_1):PAGE450',
 PIN_NAMES_ROTATE='TRUE',
 TOLERANCE='20%',
 MATERIAL='X6S',
 PHYS_PAGE='341',
 XY='(-7100,800)',
 ROT='2',
 VER='2',
 PACK_TYPE='C0201',
 LOCATION='C6724',
 CDS_LIB='pure_quanta',
 CDS_PART_NAME='Q_CAP_DIFFBUS_C0201-DIFF BUS_0.22UF,6.3V,20%,X6S,SA',
 VOLTAGE='6.3V',
 PART_NUMBER='SP_CH4221MEE01',
 VALUE='DIFF BUS_0.22UF',
 PRIM_FILE='./archive_libs/logical/q_cap_diffbus/chips/chips.prt';

PART_NAME
 C6725 'Q_CAP_DIFFBUS_C0201-DIFF BUS_0.22UF,6.3V,20%,X6S,SA':;

SECTION_NUMBER 1
 '@T6G_MB_LIB.T6G(SCH_1):PAGE461_I48@PURE_QUANTA.Q_CAP_DIFFBUS(CHIPS)':
 C_PATH='@t6g_mb_lib.t6g(sch_1):page461_i48@pure_quanta.q_cap_diffbus(chips)',
 P_PATH='@t6g_mb_lib.t6g(sch_1):page352_i48@pure_quanta.q_cap_diffbus(chips)',
 PATH='I48',
 DRAWING='@T6G_MB_LIB.T6G(SCH_1):PAGE461',
 PIN_NAMES_ROTATE='TRUE',
 TOLERANCE='20%',
 MATERIAL='X6S',
 PHYS_PAGE='352',
 XY='(-2450,2225)',
 ROT='2',
 VER='2',
 PACK_TYPE='C0201',
 LOCATION='C6725',
 CDS_LIB='pure_quanta',
 CDS_PART_NAME='Q_CAP_DIFFBUS_C0201-DIFF BUS_0.22UF,6.3V,20%,X6S,SA',
 VOLTAGE='6.3V',
 PART_NUMBER='SP_CH4221MEE01',
 VALUE='DIFF BUS_0.22UF',
 PRIM_FILE='./archive_libs/logical/q_cap_diffbus/chips/chips.prt';

PART_NAME
 C6726 'Q_CAP_DIFFBUS_C0201-DIFF BUS_0.22UF,6.3V,20%,X6S,SA':;

SECTION_NUMBER 1
 '@T6G_MB_LIB.T6G(SCH_1):PAGE461_I47@PURE_QUANTA.Q_CAP_DIFFBUS(CHIPS)':
 C_PATH='@t6g_mb_lib.t6g(sch_1):page461_i47@pure_quanta.q_cap_diffbus(chips)',
 P_PATH='@t6g_mb_lib.t6g(sch_1):page352_i47@pure_quanta.q_cap_diffbus(chips)',
 PATH='I47',
 DRAWING='@T6G_MB_LIB.T6G(SCH_1):PAGE461',
 PIN_NAMES_ROTATE='TRUE',
 TOLERANCE='20%',
 MATERIAL='X6S',
 PHYS_PAGE='352',
 XY='(-2450,2175)',
 ROT='2',
 VER='2',
 PACK_TYPE='C0201',
 LOCATION='C6726',
 CDS_LIB='pure_quanta',
 CDS_PART_NAME='Q_CAP_DIFFBUS_C0201-DIFF BUS_0.22UF,6.3V,20%,X6S,SA',
 VOLTAGE='6.3V',
 PART_NUMBER='SP_CH4221MEE01',
 VALUE='DIFF BUS_0.22UF',
 PRIM_FILE='./archive_libs/logical/q_cap_diffbus/chips/chips.prt';

PART_NAME
 C6727 'Q_CAP_DIFFBUS_C0201-DIFF BUS_0.22UF,6.3V,20%,X6S,SA':;

SECTION_NUMBER 1
 '@T6G_MB_LIB.T6G(SCH_1):PAGE461_I32@PURE_QUANTA.Q_CAP_DIFFBUS(CHIPS)':
 C_PATH='@t6g_mb_lib.t6g(sch_1):page461_i32@pure_quanta.q_cap_diffbus(chips)',
 P_PATH='@t6g_mb_lib.t6g(sch_1):page352_i32@pure_quanta.q_cap_diffbus(chips)',
 PATH='I32',
 DRAWING='@T6G_MB_LIB.T6G(SCH_1):PAGE461',
 PIN_NAMES_ROTATE='TRUE',
 TOLERANCE='20%',
 MATERIAL='X6S',
 PHYS_PAGE='352',
 XY='(-2450,2025)',
 ROT='2',
 VER='2',
 PACK_TYPE='C0201',
 LOCATION='C6727',
 CDS_LIB='pure_quanta',
 CDS_PART_NAME='Q_CAP_DIFFBUS_C0201-DIFF BUS_0.22UF,6.3V,20%,X6S,SA',
 VOLTAGE='6.3V',
 PART_NUMBER='SP_CH4221MEE01',
 VALUE='DIFF BUS_0.22UF',
 PRIM_FILE='./archive_libs/logical/q_cap_diffbus/chips/chips.prt';

PART_NAME
 C6728 'Q_CAP_DIFFBUS_C0201-DIFF BUS_0.22UF,6.3V,20%,X6S,SA':;

SECTION_NUMBER 1
 '@T6G_MB_LIB.T6G(SCH_1):PAGE461_I30@PURE_QUANTA.Q_CAP_DIFFBUS(CHIPS)':
 C_PATH='@t6g_mb_lib.t6g(sch_1):page461_i30@pure_quanta.q_cap_diffbus(chips)',
 P_PATH='@t6g_mb_lib.t6g(sch_1):page352_i30@pure_quanta.q_cap_diffbus(chips)',
 PATH='I30',
 DRAWING='@T6G_MB_LIB.T6G(SCH_1):PAGE461',
 PIN_NAMES_ROTATE='TRUE',
 TOLERANCE='20%',
 MATERIAL='X6S',
 PHYS_PAGE='352',
 XY='(-2450,1975)',
 ROT='2',
 VER='2',
 PACK_TYPE='C0201',
 LOCATION='C6728',
 CDS_LIB='pure_quanta',
 CDS_PART_NAME='Q_CAP_DIFFBUS_C0201-DIFF BUS_0.22UF,6.3V,20%,X6S,SA',
 VOLTAGE='6.3V',
 PART_NUMBER='SP_CH4221MEE01',
 VALUE='DIFF BUS_0.22UF',
 PRIM_FILE='./archive_libs/logical/q_cap_diffbus/chips/chips.prt';

PART_NAME
 C6729 'Q_CAP_DIFFBUS_C0201-DIFF BUS_0.22UF,6.3V,20%,X6S,SA':;

SECTION_NUMBER 1
 '@T6G_MB_LIB.T6G(SCH_1):PAGE461_I31@PURE_QUANTA.Q_CAP_DIFFBUS(CHIPS)':
 C_PATH='@t6g_mb_lib.t6g(sch_1):page461_i31@pure_quanta.q_cap_diffbus(chips)',
 P_PATH='@t6g_mb_lib.t6g(sch_1):page352_i31@pure_quanta.q_cap_diffbus(chips)',
 PATH='I31',
 DRAWING='@T6G_MB_LIB.T6G(SCH_1):PAGE461',
 PIN_NAMES_ROTATE='TRUE',
 TOLERANCE='20%',
 MATERIAL='X6S',
 PHYS_PAGE='352',
 XY='(-2450,1825)',
 ROT='2',
 VER='2',
 PACK_TYPE='C0201',
 LOCATION='C6729',
 CDS_LIB='pure_quanta',
 CDS_PART_NAME='Q_CAP_DIFFBUS_C0201-DIFF BUS_0.22UF,6.3V,20%,X6S,SA',
 VOLTAGE='6.3V',
 PART_NUMBER='SP_CH4221MEE01',
 VALUE='DIFF BUS_0.22UF',
 PRIM_FILE='./archive_libs/logical/q_cap_diffbus/chips/chips.prt';

PART_NAME
 C6730 'Q_CAP_DIFFBUS_C0201-DIFF BUS_0.22UF,6.3V,20%,X6S,SA':;

SECTION_NUMBER 1
 '@T6G_MB_LIB.T6G(SCH_1):PAGE461_I29@PURE_QUANTA.Q_CAP_DIFFBUS(CHIPS)':
 C_PATH='@t6g_mb_lib.t6g(sch_1):page461_i29@pure_quanta.q_cap_diffbus(chips)',
 P_PATH='@t6g_mb_lib.t6g(sch_1):page352_i29@pure_quanta.q_cap_diffbus(chips)',
 PATH='I29',
 DRAWING='@T6G_MB_LIB.T6G(SCH_1):PAGE461',
 PIN_NAMES_ROTATE='TRUE',
 TOLERANCE='20%',
 MATERIAL='X6S',
 PHYS_PAGE='352',
 XY='(-2450,1775)',
 ROT='2',
 VER='2',
 PACK_TYPE='C0201',
 LOCATION='C6730',
 CDS_LIB='pure_quanta',
 CDS_PART_NAME='Q_CAP_DIFFBUS_C0201-DIFF BUS_0.22UF,6.3V,20%,X6S,SA',
 VOLTAGE='6.3V',
 PART_NUMBER='SP_CH4221MEE01',
 VALUE='DIFF BUS_0.22UF',
 PRIM_FILE='./archive_libs/logical/q_cap_diffbus/chips/chips.prt';

PART_NAME
 C6731 'Q_CAP_DIFFBUS_C0201-DIFF BUS_0.22UF,6.3V,20%,X6S,SA':;

SECTION_NUMBER 1
 '@T6G_MB_LIB.T6G(SCH_1):PAGE461_I27@PURE_QUANTA.Q_CAP_DIFFBUS(CHIPS)':
 C_PATH='@t6g_mb_lib.t6g(sch_1):page461_i27@pure_quanta.q_cap_diffbus(chips)',
 P_PATH='@t6g_mb_lib.t6g(sch_1):page352_i27@pure_quanta.q_cap_diffbus(chips)',
 PATH='I27',
 DRAWING='@T6G_MB_LIB.T6G(SCH_1):PAGE461',
 PIN_NAMES_ROTATE='TRUE',
 TOLERANCE='20%',
 MATERIAL='X6S',
 PHYS_PAGE='352',
 XY='(-2450,1625)',
 ROT='2',
 VER='2',
 PACK_TYPE='C0201',
 LOCATION='C6731',
 CDS_LIB='pure_quanta',
 CDS_PART_NAME='Q_CAP_DIFFBUS_C0201-DIFF BUS_0.22UF,6.3V,20%,X6S,SA',
 VOLTAGE='6.3V',
 PART_NUMBER='SP_CH4221MEE01',
 VALUE='DIFF BUS_0.22UF',
 PRIM_FILE='./archive_libs/logical/q_cap_diffbus/chips/chips.prt';

PART_NAME
 C6732 'Q_CAP_DIFFBUS_C0201-DIFF BUS_0.22UF,6.3V,20%,X6S,SA':;

SECTION_NUMBER 1
 '@T6G_MB_LIB.T6G(SCH_1):PAGE461_I28@PURE_QUANTA.Q_CAP_DIFFBUS(CHIPS)':
 C_PATH='@t6g_mb_lib.t6g(sch_1):page461_i28@pure_quanta.q_cap_diffbus(chips)',
 P_PATH='@t6g_mb_lib.t6g(sch_1):page352_i28@pure_quanta.q_cap_diffbus(chips)',
 PATH='I28',
 DRAWING='@T6G_MB_LIB.T6G(SCH_1):PAGE461',
 PIN_NAMES_ROTATE='TRUE',
 TOLERANCE='20%',
 MATERIAL='X6S',
 PHYS_PAGE='352',
 XY='(-2450,1575)',
 ROT='2',
 VER='2',
 PACK_TYPE='C0201',
 LOCATION='C6732',
 CDS_LIB='pure_quanta',
 CDS_PART_NAME='Q_CAP_DIFFBUS_C0201-DIFF BUS_0.22UF,6.3V,20%,X6S,SA',
 VOLTAGE='6.3V',
 PART_NUMBER='SP_CH4221MEE01',
 VALUE='DIFF BUS_0.22UF',
 PRIM_FILE='./archive_libs/logical/q_cap_diffbus/chips/chips.prt';

PART_NAME
 C6733 'Q_CAP_DIFFBUS_C0201-DIFF BUS_0.22UF,6.3V,20%,X6S,SA':;

SECTION_NUMBER 1
 '@T6G_MB_LIB.T6G(SCH_1):PAGE461_I26@PURE_QUANTA.Q_CAP_DIFFBUS(CHIPS)':
 C_PATH='@t6g_mb_lib.t6g(sch_1):page461_i26@pure_quanta.q_cap_diffbus(chips)',
 P_PATH='@t6g_mb_lib.t6g(sch_1):page352_i26@pure_quanta.q_cap_diffbus(chips)',
 PATH='I26',
 DRAWING='@T6G_MB_LIB.T6G(SCH_1):PAGE461',
 PIN_NAMES_ROTATE='TRUE',
 TOLERANCE='20%',
 MATERIAL='X6S',
 PHYS_PAGE='352',
 XY='(-2450,1425)',
 ROT='2',
 VER='2',
 PACK_TYPE='C0201',
 LOCATION='C6733',
 CDS_LIB='pure_quanta',
 CDS_PART_NAME='Q_CAP_DIFFBUS_C0201-DIFF BUS_0.22UF,6.3V,20%,X6S,SA',
 VOLTAGE='6.3V',
 PART_NUMBER='SP_CH4221MEE01',
 VALUE='DIFF BUS_0.22UF',
 PRIM_FILE='./archive_libs/logical/q_cap_diffbus/chips/chips.prt';

PART_NAME
 C6734 'Q_CAP_DIFFBUS_C0201-DIFF BUS_0.22UF,6.3V,20%,X6S,SA':;

SECTION_NUMBER 1
 '@T6G_MB_LIB.T6G(SCH_1):PAGE461_I25@PURE_QUANTA.Q_CAP_DIFFBUS(CHIPS)':
 C_PATH='@t6g_mb_lib.t6g(sch_1):page461_i25@pure_quanta.q_cap_diffbus(chips)',
 P_PATH='@t6g_mb_lib.t6g(sch_1):page352_i25@pure_quanta.q_cap_diffbus(chips)',
 PATH='I25',
 DRAWING='@T6G_MB_LIB.T6G(SCH_1):PAGE461',
 PIN_NAMES_ROTATE='TRUE',
 TOLERANCE='20%',
 MATERIAL='X6S',
 PHYS_PAGE='352',
 XY='(-2450,1375)',
 ROT='2',
 VER='2',
 PACK_TYPE='C0201',
 LOCATION='C6734',
 CDS_LIB='pure_quanta',
 CDS_PART_NAME='Q_CAP_DIFFBUS_C0201-DIFF BUS_0.22UF,6.3V,20%,X6S,SA',
 VOLTAGE='6.3V',
 PART_NUMBER='SP_CH4221MEE01',
 VALUE='DIFF BUS_0.22UF',
 PRIM_FILE='./archive_libs/logical/q_cap_diffbus/chips/chips.prt';

PART_NAME
 C6735 'Q_CAP_DIFFBUS_C0201-DIFF BUS_0.22UF,6.3V,20%,X6S,SA':;

SECTION_NUMBER 1
 '@T6G_MB_LIB.T6G(SCH_1):PAGE461_I24@PURE_QUANTA.Q_CAP_DIFFBUS(CHIPS)':
 C_PATH='@t6g_mb_lib.t6g(sch_1):page461_i24@pure_quanta.q_cap_diffbus(chips)',
 P_PATH='@t6g_mb_lib.t6g(sch_1):page352_i24@pure_quanta.q_cap_diffbus(chips)',
 PATH='I24',
 DRAWING='@T6G_MB_LIB.T6G(SCH_1):PAGE461',
 PIN_NAMES_ROTATE='TRUE',
 TOLERANCE='20%',
 MATERIAL='X6S',
 PHYS_PAGE='352',
 XY='(-2450,1225)',
 ROT='2',
 VER='2',
 PACK_TYPE='C0201',
 LOCATION='C6735',
 CDS_LIB='pure_quanta',
 CDS_PART_NAME='Q_CAP_DIFFBUS_C0201-DIFF BUS_0.22UF,6.3V,20%,X6S,SA',
 VOLTAGE='6.3V',
 PART_NUMBER='SP_CH4221MEE01',
 VALUE='DIFF BUS_0.22UF',
 PRIM_FILE='./archive_libs/logical/q_cap_diffbus/chips/chips.prt';

PART_NAME
 C6736 'Q_CAP_DIFFBUS_C0201-DIFF BUS_0.22UF,6.3V,20%,X6S,SA':;

SECTION_NUMBER 1
 '@T6G_MB_LIB.T6G(SCH_1):PAGE461_I23@PURE_QUANTA.Q_CAP_DIFFBUS(CHIPS)':
 C_PATH='@t6g_mb_lib.t6g(sch_1):page461_i23@pure_quanta.q_cap_diffbus(chips)',
 P_PATH='@t6g_mb_lib.t6g(sch_1):page352_i23@pure_quanta.q_cap_diffbus(chips)',
 PATH='I23',
 DRAWING='@T6G_MB_LIB.T6G(SCH_1):PAGE461',
 PIN_NAMES_ROTATE='TRUE',
 TOLERANCE='20%',
 MATERIAL='X6S',
 PHYS_PAGE='352',
 XY='(-2450,1175)',
 ROT='2',
 VER='2',
 PACK_TYPE='C0201',
 LOCATION='C6736',
 CDS_LIB='pure_quanta',
 CDS_PART_NAME='Q_CAP_DIFFBUS_C0201-DIFF BUS_0.22UF,6.3V,20%,X6S,SA',
 VOLTAGE='6.3V',
 PART_NUMBER='SP_CH4221MEE01',
 VALUE='DIFF BUS_0.22UF',
 PRIM_FILE='./archive_libs/logical/q_cap_diffbus/chips/chips.prt';

PART_NAME
 C6737 'Q_CAP_DIFFBUS_C0201-DIFF BUS_0.22UF,6.3V,20%,X6S,SA':;

SECTION_NUMBER 1
 '@T6G_MB_LIB.T6G(SCH_1):PAGE461_I22@PURE_QUANTA.Q_CAP_DIFFBUS(CHIPS)':
 C_PATH='@t6g_mb_lib.t6g(sch_1):page461_i22@pure_quanta.q_cap_diffbus(chips)',
 P_PATH='@t6g_mb_lib.t6g(sch_1):page352_i22@pure_quanta.q_cap_diffbus(chips)',
 PATH='I22',
 DRAWING='@T6G_MB_LIB.T6G(SCH_1):PAGE461',
 PIN_NAMES_ROTATE='TRUE',
 TOLERANCE='20%',
 MATERIAL='X6S',
 PHYS_PAGE='352',
 XY='(-2450,1025)',
 ROT='2',
 VER='2',
 PACK_TYPE='C0201',
 LOCATION='C6737',
 CDS_LIB='pure_quanta',
 CDS_PART_NAME='Q_CAP_DIFFBUS_C0201-DIFF BUS_0.22UF,6.3V,20%,X6S,SA',
 VOLTAGE='6.3V',
 PART_NUMBER='SP_CH4221MEE01',
 VALUE='DIFF BUS_0.22UF',
 PRIM_FILE='./archive_libs/logical/q_cap_diffbus/chips/chips.prt';

PART_NAME
 C6738 'Q_CAP_DIFFBUS_C0201-DIFF BUS_0.22UF,6.3V,20%,X6S,SA':;

SECTION_NUMBER 1
 '@T6G_MB_LIB.T6G(SCH_1):PAGE461_I16@PURE_QUANTA.Q_CAP_DIFFBUS(CHIPS)':
 C_PATH='@t6g_mb_lib.t6g(sch_1):page461_i16@pure_quanta.q_cap_diffbus(chips)',
 P_PATH='@t6g_mb_lib.t6g(sch_1):page352_i16@pure_quanta.q_cap_diffbus(chips)',
 PATH='I16',
 DRAWING='@T6G_MB_LIB.T6G(SCH_1):PAGE461',
 PIN_NAMES_ROTATE='TRUE',
 TOLERANCE='20%',
 MATERIAL='X6S',
 PHYS_PAGE='352',
 XY='(-2450,975)',
 ROT='2',
 VER='2',
 PACK_TYPE='C0201',
 LOCATION='C6738',
 CDS_LIB='pure_quanta',
 CDS_PART_NAME='Q_CAP_DIFFBUS_C0201-DIFF BUS_0.22UF,6.3V,20%,X6S,SA',
 VOLTAGE='6.3V',
 PART_NUMBER='SP_CH4221MEE01',
 VALUE='DIFF BUS_0.22UF',
 PRIM_FILE='./archive_libs/logical/q_cap_diffbus/chips/chips.prt';

PART_NAME
 C6739 'Q_CAP_DIFFBUS_C0201-DIFF BUS_0.22UF,6.3V,20%,X6S,SA':;

SECTION_NUMBER 1
 '@T6G_MB_LIB.T6G(SCH_1):PAGE461_I17@PURE_QUANTA.Q_CAP_DIFFBUS(CHIPS)':
 C_PATH='@t6g_mb_lib.t6g(sch_1):page461_i17@pure_quanta.q_cap_diffbus(chips)',
 P_PATH='@t6g_mb_lib.t6g(sch_1):page352_i17@pure_quanta.q_cap_diffbus(chips)',
 PATH='I17',
 DRAWING='@T6G_MB_LIB.T6G(SCH_1):PAGE461',
 PIN_NAMES_ROTATE='TRUE',
 TOLERANCE='20%',
 MATERIAL='X6S',
 PHYS_PAGE='352',
 XY='(-2450,825)',
 ROT='2',
 VER='2',
 PACK_TYPE='C0201',
 LOCATION='C6739',
 CDS_LIB='pure_quanta',
 CDS_PART_NAME='Q_CAP_DIFFBUS_C0201-DIFF BUS_0.22UF,6.3V,20%,X6S,SA',
 VOLTAGE='6.3V',
 PART_NUMBER='SP_CH4221MEE01',
 VALUE='DIFF BUS_0.22UF',
 PRIM_FILE='./archive_libs/logical/q_cap_diffbus/chips/chips.prt';

PART_NAME
 C6740 'Q_CAP_DIFFBUS_C0201-DIFF BUS_0.22UF,6.3V,20%,X6S,SA':;

SECTION_NUMBER 1
 '@T6G_MB_LIB.T6G(SCH_1):PAGE461_I18@PURE_QUANTA.Q_CAP_DIFFBUS(CHIPS)':
 C_PATH='@t6g_mb_lib.t6g(sch_1):page461_i18@pure_quanta.q_cap_diffbus(chips)',
 P_PATH='@t6g_mb_lib.t6g(sch_1):page352_i18@pure_quanta.q_cap_diffbus(chips)',
 PATH='I18',
 DRAWING='@T6G_MB_LIB.T6G(SCH_1):PAGE461',
 PIN_NAMES_ROTATE='TRUE',
 TOLERANCE='20%',
 MATERIAL='X6S',
 PHYS_PAGE='352',
 XY='(-2450,775)',
 ROT='2',
 VER='2',
 PACK_TYPE='C0201',
 LOCATION='C6740',
 CDS_LIB='pure_quanta',
 CDS_PART_NAME='Q_CAP_DIFFBUS_C0201-DIFF BUS_0.22UF,6.3V,20%,X6S,SA',
 VOLTAGE='6.3V',
 PART_NUMBER='SP_CH4221MEE01',
 VALUE='DIFF BUS_0.22UF',
 PRIM_FILE='./archive_libs/logical/q_cap_diffbus/chips/chips.prt';

PART_NAME
 C6741 'Q_CAP_DIFFBUS_C0201-DIFF BUS_0.22UF,6.3V,20%,X6S,SA':;

SECTION_NUMBER 1
 '@T6G_MB_LIB.T6G(SCH_1):PAGE461_I105@PURE_QUANTA.Q_CAP_DIFFBUS(CHIPS)':
 C_PATH='@t6g_mb_lib.t6g(sch_1):page461_i105@pure_quanta.q_cap_diffbus(chips)',
 P_PATH='@t6g_mb_lib.t6g(sch_1):page352_i105@pure_quanta.q_cap_diffbus(chips)',
 PATH='I105',
 DRAWING='@T6G_MB_LIB.T6G(SCH_1):PAGE461',
 PIN_NAMES_ROTATE='TRUE',
 TOLERANCE='20%',
 MATERIAL='X6S',
 PHYS_PAGE='352',
 XY='(-7025,2100)',
 ROT='2',
 VER='2',
 PACK_TYPE='C0201',
 LOCATION='C6741',
 CDS_LIB='pure_quanta',
 CDS_PART_NAME='Q_CAP_DIFFBUS_C0201-DIFF BUS_0.22UF,6.3V,20%,X6S,SA',
 VOLTAGE='6.3V',
 PART_NUMBER='SP_CH4221MEE01',
 VALUE='DIFF BUS_0.22UF',
 PRIM_FILE='./archive_libs/logical/q_cap_diffbus/chips/chips.prt';

PART_NAME
 C6742 'Q_CAP_DIFFBUS_C0201-DIFF BUS_0.22UF,6.3V,20%,X6S,SA':;

SECTION_NUMBER 1
 '@T6G_MB_LIB.T6G(SCH_1):PAGE461_I104@PURE_QUANTA.Q_CAP_DIFFBUS(CHIPS)':
 C_PATH='@t6g_mb_lib.t6g(sch_1):page461_i104@pure_quanta.q_cap_diffbus(chips)',
 P_PATH='@t6g_mb_lib.t6g(sch_1):page352_i104@pure_quanta.q_cap_diffbus(chips)',
 PATH='I104',
 DRAWING='@T6G_MB_LIB.T6G(SCH_1):PAGE461',
 PIN_NAMES_ROTATE='TRUE',
 TOLERANCE='20%',
 MATERIAL='X6S',
 PHYS_PAGE='352',
 XY='(-7025,2050)',
 ROT='2',
 VER='2',
 PACK_TYPE='C0201',
 LOCATION='C6742',
 CDS_LIB='pure_quanta',
 CDS_PART_NAME='Q_CAP_DIFFBUS_C0201-DIFF BUS_0.22UF,6.3V,20%,X6S,SA',
 VOLTAGE='6.3V',
 PART_NUMBER='SP_CH4221MEE01',
 VALUE='DIFF BUS_0.22UF',
 PRIM_FILE='./archive_libs/logical/q_cap_diffbus/chips/chips.prt';

PART_NAME
 C6743 'Q_CAP_DIFFBUS_C0201-DIFF BUS_0.22UF,6.3V,20%,X6S,SA':;

SECTION_NUMBER 1
 '@T6G_MB_LIB.T6G(SCH_1):PAGE461_I101@PURE_QUANTA.Q_CAP_DIFFBUS(CHIPS)':
 C_PATH='@t6g_mb_lib.t6g(sch_1):page461_i101@pure_quanta.q_cap_diffbus(chips)',
 P_PATH='@t6g_mb_lib.t6g(sch_1):page352_i101@pure_quanta.q_cap_diffbus(chips)',
 PATH='I101',
 DRAWING='@T6G_MB_LIB.T6G(SCH_1):PAGE461',
 PIN_NAMES_ROTATE='TRUE',
 TOLERANCE='20%',
 MATERIAL='X6S',
 PHYS_PAGE='352',
 XY='(-7025,1900)',
 ROT='2',
 VER='2',
 PACK_TYPE='C0201',
 LOCATION='C6743',
 CDS_LIB='pure_quanta',
 CDS_PART_NAME='Q_CAP_DIFFBUS_C0201-DIFF BUS_0.22UF,6.3V,20%,X6S,SA',
 VOLTAGE='6.3V',
 PART_NUMBER='SP_CH4221MEE01',
 VALUE='DIFF BUS_0.22UF',
 PRIM_FILE='./archive_libs/logical/q_cap_diffbus/chips/chips.prt';

PART_NAME
 C6744 'Q_CAP_DIFFBUS_C0201-DIFF BUS_0.22UF,6.3V,20%,X6S,SA':;

SECTION_NUMBER 1
 '@T6G_MB_LIB.T6G(SCH_1):PAGE461_I100@PURE_QUANTA.Q_CAP_DIFFBUS(CHIPS)':
 C_PATH='@t6g_mb_lib.t6g(sch_1):page461_i100@pure_quanta.q_cap_diffbus(chips)',
 P_PATH='@t6g_mb_lib.t6g(sch_1):page352_i100@pure_quanta.q_cap_diffbus(chips)',
 PATH='I100',
 DRAWING='@T6G_MB_LIB.T6G(SCH_1):PAGE461',
 PIN_NAMES_ROTATE='TRUE',
 TOLERANCE='20%',
 MATERIAL='X6S',
 PHYS_PAGE='352',
 XY='(-7025,1850)',
 ROT='2',
 VER='2',
 PACK_TYPE='C0201',
 LOCATION='C6744',
 CDS_LIB='pure_quanta',
 CDS_PART_NAME='Q_CAP_DIFFBUS_C0201-DIFF BUS_0.22UF,6.3V,20%,X6S,SA',
 VOLTAGE='6.3V',
 PART_NUMBER='SP_CH4221MEE01',
 VALUE='DIFF BUS_0.22UF',
 PRIM_FILE='./archive_libs/logical/q_cap_diffbus/chips/chips.prt';

PART_NAME
 C6745 'Q_CAP_DIFFBUS_C0201-DIFF BUS_0.22UF,6.3V,20%,X6S,SA':;

SECTION_NUMBER 1
 '@T6G_MB_LIB.T6G(SCH_1):PAGE461_I99@PURE_QUANTA.Q_CAP_DIFFBUS(CHIPS)':
 C_PATH='@t6g_mb_lib.t6g(sch_1):page461_i99@pure_quanta.q_cap_diffbus(chips)',
 P_PATH='@t6g_mb_lib.t6g(sch_1):page352_i99@pure_quanta.q_cap_diffbus(chips)',
 PATH='I99',
 DRAWING='@T6G_MB_LIB.T6G(SCH_1):PAGE461',
 PIN_NAMES_ROTATE='TRUE',
 TOLERANCE='20%',
 MATERIAL='X6S',
 PHYS_PAGE='352',
 XY='(-7025,1700)',
 ROT='2',
 VER='2',
 PACK_TYPE='C0201',
 LOCATION='C6745',
 CDS_LIB='pure_quanta',
 CDS_PART_NAME='Q_CAP_DIFFBUS_C0201-DIFF BUS_0.22UF,6.3V,20%,X6S,SA',
 VOLTAGE='6.3V',
 PART_NUMBER='SP_CH4221MEE01',
 VALUE='DIFF BUS_0.22UF',
 PRIM_FILE='./archive_libs/logical/q_cap_diffbus/chips/chips.prt';

PART_NAME
 C6746 'Q_CAP_DIFFBUS_C0201-DIFF BUS_0.22UF,6.3V,20%,X6S,SA':;

SECTION_NUMBER 1
 '@T6G_MB_LIB.T6G(SCH_1):PAGE461_I98@PURE_QUANTA.Q_CAP_DIFFBUS(CHIPS)':
 C_PATH='@t6g_mb_lib.t6g(sch_1):page461_i98@pure_quanta.q_cap_diffbus(chips)',
 P_PATH='@t6g_mb_lib.t6g(sch_1):page352_i98@pure_quanta.q_cap_diffbus(chips)',
 PATH='I98',
 DRAWING='@T6G_MB_LIB.T6G(SCH_1):PAGE461',
 PIN_NAMES_ROTATE='TRUE',
 TOLERANCE='20%',
 MATERIAL='X6S',
 PHYS_PAGE='352',
 XY='(-7025,1650)',
 ROT='2',
 VER='2',
 PACK_TYPE='C0201',
 LOCATION='C6746',
 CDS_LIB='pure_quanta',
 CDS_PART_NAME='Q_CAP_DIFFBUS_C0201-DIFF BUS_0.22UF,6.3V,20%,X6S,SA',
 VOLTAGE='6.3V',
 PART_NUMBER='SP_CH4221MEE01',
 VALUE='DIFF BUS_0.22UF',
 PRIM_FILE='./archive_libs/logical/q_cap_diffbus/chips/chips.prt';

PART_NAME
 C6747 'Q_CAP_DIFFBUS_C0201-DIFF BUS_0.22UF,6.3V,20%,X6S,SA':;

SECTION_NUMBER 1
 '@T6G_MB_LIB.T6G(SCH_1):PAGE461_I97@PURE_QUANTA.Q_CAP_DIFFBUS(CHIPS)':
 C_PATH='@t6g_mb_lib.t6g(sch_1):page461_i97@pure_quanta.q_cap_diffbus(chips)',
 P_PATH='@t6g_mb_lib.t6g(sch_1):page352_i97@pure_quanta.q_cap_diffbus(chips)',
 PATH='I97',
 DRAWING='@T6G_MB_LIB.T6G(SCH_1):PAGE461',
 PIN_NAMES_ROTATE='TRUE',
 TOLERANCE='20%',
 MATERIAL='X6S',
 PHYS_PAGE='352',
 XY='(-7025,1500)',
 ROT='2',
 VER='2',
 PACK_TYPE='C0201',
 LOCATION='C6747',
 CDS_LIB='pure_quanta',
 CDS_PART_NAME='Q_CAP_DIFFBUS_C0201-DIFF BUS_0.22UF,6.3V,20%,X6S,SA',
 VOLTAGE='6.3V',
 PART_NUMBER='SP_CH4221MEE01',
 VALUE='DIFF BUS_0.22UF',
 PRIM_FILE='./archive_libs/logical/q_cap_diffbus/chips/chips.prt';

PART_NAME
 C6748 'Q_CAP_DIFFBUS_C0201-DIFF BUS_0.22UF,6.3V,20%,X6S,SA':;

SECTION_NUMBER 1
 '@T6G_MB_LIB.T6G(SCH_1):PAGE461_I96@PURE_QUANTA.Q_CAP_DIFFBUS(CHIPS)':
 C_PATH='@t6g_mb_lib.t6g(sch_1):page461_i96@pure_quanta.q_cap_diffbus(chips)',
 P_PATH='@t6g_mb_lib.t6g(sch_1):page352_i96@pure_quanta.q_cap_diffbus(chips)',
 PATH='I96',
 DRAWING='@T6G_MB_LIB.T6G(SCH_1):PAGE461',
 PIN_NAMES_ROTATE='TRUE',
 TOLERANCE='20%',
 MATERIAL='X6S',
 PHYS_PAGE='352',
 XY='(-7025,1450)',
 ROT='2',
 VER='2',
 PACK_TYPE='C0201',
 LOCATION='C6748',
 CDS_LIB='pure_quanta',
 CDS_PART_NAME='Q_CAP_DIFFBUS_C0201-DIFF BUS_0.22UF,6.3V,20%,X6S,SA',
 VOLTAGE='6.3V',
 PART_NUMBER='SP_CH4221MEE01',
 VALUE='DIFF BUS_0.22UF',
 PRIM_FILE='./archive_libs/logical/q_cap_diffbus/chips/chips.prt';

PART_NAME
 C6749 'Q_CAP_DIFFBUS_C0201-DIFF BUS_0.22UF,6.3V,20%,X6S,SA':;

SECTION_NUMBER 1
 '@T6G_MB_LIB.T6G(SCH_1):PAGE461_I95@PURE_QUANTA.Q_CAP_DIFFBUS(CHIPS)':
 C_PATH='@t6g_mb_lib.t6g(sch_1):page461_i95@pure_quanta.q_cap_diffbus(chips)',
 P_PATH='@t6g_mb_lib.t6g(sch_1):page352_i95@pure_quanta.q_cap_diffbus(chips)',
 PATH='I95',
 DRAWING='@T6G_MB_LIB.T6G(SCH_1):PAGE461',
 PIN_NAMES_ROTATE='TRUE',
 TOLERANCE='20%',
 MATERIAL='X6S',
 PHYS_PAGE='352',
 XY='(-7025,1300)',
 ROT='2',
 VER='2',
 PACK_TYPE='C0201',
 LOCATION='C6749',
 CDS_LIB='pure_quanta',
 CDS_PART_NAME='Q_CAP_DIFFBUS_C0201-DIFF BUS_0.22UF,6.3V,20%,X6S,SA',
 VOLTAGE='6.3V',
 PART_NUMBER='SP_CH4221MEE01',
 VALUE='DIFF BUS_0.22UF',
 PRIM_FILE='./archive_libs/logical/q_cap_diffbus/chips/chips.prt';

PART_NAME
 C6750 'Q_CAP_DIFFBUS_C0201-DIFF BUS_0.22UF,6.3V,20%,X6S,SA':;

SECTION_NUMBER 1
 '@T6G_MB_LIB.T6G(SCH_1):PAGE461_I94@PURE_QUANTA.Q_CAP_DIFFBUS(CHIPS)':
 C_PATH='@t6g_mb_lib.t6g(sch_1):page461_i94@pure_quanta.q_cap_diffbus(chips)',
 P_PATH='@t6g_mb_lib.t6g(sch_1):page352_i94@pure_quanta.q_cap_diffbus(chips)',
 PATH='I94',
 DRAWING='@T6G_MB_LIB.T6G(SCH_1):PAGE461',
 PIN_NAMES_ROTATE='TRUE',
 TOLERANCE='20%',
 MATERIAL='X6S',
 PHYS_PAGE='352',
 XY='(-7025,1250)',
 ROT='2',
 VER='2',
 PACK_TYPE='C0201',
 LOCATION='C6750',
 CDS_LIB='pure_quanta',
 CDS_PART_NAME='Q_CAP_DIFFBUS_C0201-DIFF BUS_0.22UF,6.3V,20%,X6S,SA',
 VOLTAGE='6.3V',
 PART_NUMBER='SP_CH4221MEE01',
 VALUE='DIFF BUS_0.22UF',
 PRIM_FILE='./archive_libs/logical/q_cap_diffbus/chips/chips.prt';

PART_NAME
 C6751 'Q_CAP_DIFFBUS_C0201-DIFF BUS_0.22UF,6.3V,20%,X6S,SA':;

SECTION_NUMBER 1
 '@T6G_MB_LIB.T6G(SCH_1):PAGE461_I93@PURE_QUANTA.Q_CAP_DIFFBUS(CHIPS)':
 C_PATH='@t6g_mb_lib.t6g(sch_1):page461_i93@pure_quanta.q_cap_diffbus(chips)',
 P_PATH='@t6g_mb_lib.t6g(sch_1):page352_i93@pure_quanta.q_cap_diffbus(chips)',
 PATH='I93',
 DRAWING='@T6G_MB_LIB.T6G(SCH_1):PAGE461',
 PIN_NAMES_ROTATE='TRUE',
 TOLERANCE='20%',
 MATERIAL='X6S',
 PHYS_PAGE='352',
 XY='(-7025,1100)',
 ROT='2',
 VER='2',
 PACK_TYPE='C0201',
 LOCATION='C6751',
 CDS_LIB='pure_quanta',
 CDS_PART_NAME='Q_CAP_DIFFBUS_C0201-DIFF BUS_0.22UF,6.3V,20%,X6S,SA',
 VOLTAGE='6.3V',
 PART_NUMBER='SP_CH4221MEE01',
 VALUE='DIFF BUS_0.22UF',
 PRIM_FILE='./archive_libs/logical/q_cap_diffbus/chips/chips.prt';

PART_NAME
 C6752 'Q_CAP_DIFFBUS_C0201-DIFF BUS_0.22UF,6.3V,20%,X6S,SA':;

SECTION_NUMBER 1
 '@T6G_MB_LIB.T6G(SCH_1):PAGE461_I92@PURE_QUANTA.Q_CAP_DIFFBUS(CHIPS)':
 C_PATH='@t6g_mb_lib.t6g(sch_1):page461_i92@pure_quanta.q_cap_diffbus(chips)',
 P_PATH='@t6g_mb_lib.t6g(sch_1):page352_i92@pure_quanta.q_cap_diffbus(chips)',
 PATH='I92',
 DRAWING='@T6G_MB_LIB.T6G(SCH_1):PAGE461',
 PIN_NAMES_ROTATE='TRUE',
 TOLERANCE='20%',
 MATERIAL='X6S',
 PHYS_PAGE='352',
 XY='(-7025,1050)',
 ROT='2',
 VER='2',
 PACK_TYPE='C0201',
 LOCATION='C6752',
 CDS_LIB='pure_quanta',
 CDS_PART_NAME='Q_CAP_DIFFBUS_C0201-DIFF BUS_0.22UF,6.3V,20%,X6S,SA',
 VOLTAGE='6.3V',
 PART_NUMBER='SP_CH4221MEE01',
 VALUE='DIFF BUS_0.22UF',
 PRIM_FILE='./archive_libs/logical/q_cap_diffbus/chips/chips.prt';

PART_NAME
 C6753 'Q_CAP_DIFFBUS_C0201-DIFF BUS_0.22UF,6.3V,20%,X6S,SA':;

SECTION_NUMBER 1
 '@T6G_MB_LIB.T6G(SCH_1):PAGE461_I91@PURE_QUANTA.Q_CAP_DIFFBUS(CHIPS)':
 C_PATH='@t6g_mb_lib.t6g(sch_1):page461_i91@pure_quanta.q_cap_diffbus(chips)',
 P_PATH='@t6g_mb_lib.t6g(sch_1):page352_i91@pure_quanta.q_cap_diffbus(chips)',
 PATH='I91',
 DRAWING='@T6G_MB_LIB.T6G(SCH_1):PAGE461',
 PIN_NAMES_ROTATE='TRUE',
 TOLERANCE='20%',
 MATERIAL='X6S',
 PHYS_PAGE='352',
 XY='(-7025,900)',
 ROT='2',
 VER='2',
 PACK_TYPE='C0201',
 LOCATION='C6753',
 CDS_LIB='pure_quanta',
 CDS_PART_NAME='Q_CAP_DIFFBUS_C0201-DIFF BUS_0.22UF,6.3V,20%,X6S,SA',
 VOLTAGE='6.3V',
 PART_NUMBER='SP_CH4221MEE01',
 VALUE='DIFF BUS_0.22UF',
 PRIM_FILE='./archive_libs/logical/q_cap_diffbus/chips/chips.prt';

PART_NAME
 C6754 'Q_CAP_DIFFBUS_C0201-DIFF BUS_0.22UF,6.3V,20%,X6S,SA':;

SECTION_NUMBER 1
 '@T6G_MB_LIB.T6G(SCH_1):PAGE461_I90@PURE_QUANTA.Q_CAP_DIFFBUS(CHIPS)':
 C_PATH='@t6g_mb_lib.t6g(sch_1):page461_i90@pure_quanta.q_cap_diffbus(chips)',
 P_PATH='@t6g_mb_lib.t6g(sch_1):page352_i90@pure_quanta.q_cap_diffbus(chips)',
 PATH='I90',
 DRAWING='@T6G_MB_LIB.T6G(SCH_1):PAGE461',
 PIN_NAMES_ROTATE='TRUE',
 TOLERANCE='20%',
 MATERIAL='X6S',
 PHYS_PAGE='352',
 XY='(-7025,850)',
 ROT='2',
 VER='2',
 PACK_TYPE='C0201',
 LOCATION='C6754',
 CDS_LIB='pure_quanta',
 CDS_PART_NAME='Q_CAP_DIFFBUS_C0201-DIFF BUS_0.22UF,6.3V,20%,X6S,SA',
 VOLTAGE='6.3V',
 PART_NUMBER='SP_CH4221MEE01',
 VALUE='DIFF BUS_0.22UF',
 PRIM_FILE='./archive_libs/logical/q_cap_diffbus/chips/chips.prt';

PART_NAME
 C6755 'Q_CAP_DIFFBUS_C0201-DIFF BUS_0.22UF,6.3V,20%,X6S,SA':;

SECTION_NUMBER 1
 '@T6G_MB_LIB.T6G(SCH_1):PAGE461_I89@PURE_QUANTA.Q_CAP_DIFFBUS(CHIPS)':
 C_PATH='@t6g_mb_lib.t6g(sch_1):page461_i89@pure_quanta.q_cap_diffbus(chips)',
 P_PATH='@t6g_mb_lib.t6g(sch_1):page352_i89@pure_quanta.q_cap_diffbus(chips)',
 PATH='I89',
 DRAWING='@T6G_MB_LIB.T6G(SCH_1):PAGE461',
 PIN_NAMES_ROTATE='TRUE',
 TOLERANCE='20%',
 MATERIAL='X6S',
 PHYS_PAGE='352',
 XY='(-7025,700)',
 ROT='2',
 VER='2',
 PACK_TYPE='C0201',
 LOCATION='C6755',
 CDS_LIB='pure_quanta',
 CDS_PART_NAME='Q_CAP_DIFFBUS_C0201-DIFF BUS_0.22UF,6.3V,20%,X6S,SA',
 VOLTAGE='6.3V',
 PART_NUMBER='SP_CH4221MEE01',
 VALUE='DIFF BUS_0.22UF',
 PRIM_FILE='./archive_libs/logical/q_cap_diffbus/chips/chips.prt';

PART_NAME
 C6756 'Q_CAP_DIFFBUS_C0201-DIFF BUS_0.22UF,6.3V,20%,X6S,SA':;

SECTION_NUMBER 1
 '@T6G_MB_LIB.T6G(SCH_1):PAGE461_I88@PURE_QUANTA.Q_CAP_DIFFBUS(CHIPS)':
 C_PATH='@t6g_mb_lib.t6g(sch_1):page461_i88@pure_quanta.q_cap_diffbus(chips)',
 P_PATH='@t6g_mb_lib.t6g(sch_1):page352_i88@pure_quanta.q_cap_diffbus(chips)',
 PATH='I88',
 DRAWING='@T6G_MB_LIB.T6G(SCH_1):PAGE461',
 PIN_NAMES_ROTATE='TRUE',
 TOLERANCE='20%',
 MATERIAL='X6S',
 PHYS_PAGE='352',
 XY='(-7025,650)',
 ROT='2',
 VER='2',
 PACK_TYPE='C0201',
 LOCATION='C6756',
 CDS_LIB='pure_quanta',
 CDS_PART_NAME='Q_CAP_DIFFBUS_C0201-DIFF BUS_0.22UF,6.3V,20%,X6S,SA',
 VOLTAGE='6.3V',
 PART_NUMBER='SP_CH4221MEE01',
 VALUE='DIFF BUS_0.22UF',
 PRIM_FILE='./archive_libs/logical/q_cap_diffbus/chips/chips.prt';

PART_NAME
 C6757 'Q_CAP_0402-0.1UF,25V,10%,EMPTY,CH4104K1B00':;

SECTION_NUMBER 1
 '@T6G_MB_LIB.T6G(SCH_1):PAGE469_I5@PURE_QUANTA.Q_CAP(CHIPS)':
 C_PATH='@t6g_mb_lib.t6g(sch_1):page469_i5@pure_quanta.q_cap(chips)',
 P_PATH='@t6g_mb_lib.t6g(sch_1):page360_i5@pure_quanta.q_cap(chips)',
 PATH='I5',
 DRAWING='@T6G_MB_LIB.T6G(SCH_1):PAGE469',
 TOLERANCE='10%',
 MATERIAL='EMPTY',
 PHYS_PAGE='360',
 XY='(-8450,3200)',
 ROT='2',
 VER='1',
 PACK_TYPE='0402',
 LOCATION='C6757',
 CDS_LIB='pure_quanta',
 CDS_PART_NAME='Q_CAP_0402-0.1UF,25V,10%,EMPTY,CH4104K1B00',
 VOLTAGE='25V',
 PART_NUMBER='CH4104K1B00',
 VALUE='0.1UF',
 PRIM_FILE='./archive_libs/logical/q_cap/chips/chips.prt';

PART_NAME
 C6758 'Q_CAP_0402-1000PF,50V,5%,X7R,TMP_QCH21006JB10':;

SECTION_NUMBER 1
 '@T6G_MB_LIB.T6G(SCH_1):PAGE469_I42@PURE_QUANTA.Q_CAP(CHIPS)':
 C_PATH='@t6g_mb_lib.t6g(sch_1):page469_i42@pure_quanta.q_cap(chips)',
 P_PATH='@t6g_mb_lib.t6g(sch_1):page360_i42@pure_quanta.q_cap(chips)',
 PATH='I42',
 DRAWING='@T6G_MB_LIB.T6G(SCH_1):PAGE469',
 TOLERANCE='5%',
 MATERIAL='X7R',
 PHYS_PAGE='360',
 XY='(-2725,3750)',
 ROT='0',
 VER='1',
 PACK_TYPE='0402',
 LOCATION='C6758',
 CDS_LIB='pure_quanta',
 CDS_PART_NAME='Q_CAP_0402-1000PF,50V,5%,X7R,TMP_QCH21006JB10',
 VOLTAGE='50V',
 PART_NUMBER='TMP_QCH21006JB10',
 VALUE='1000PF',
 PRIM_FILE='./archive_libs/logical/q_cap/chips/chips.prt';

PART_NAME
 C7000 'Q_CAPP_SMLF-470UF,2.5V,20%,SPCAP,CH747LM8818':;

SECTION_NUMBER 1
 '@T6G_MB_LIB.T6G(SCH_1):PAGE388_I98@PURE_QUANTA.Q_CAPP(CHIPS)':
 C_PATH='@t6g_mb_lib.t6g(sch_1):page388_i98@pure_quanta.q_capp(chips)',
 P_PATH='@t6g_mb_lib.t6g(sch_1):page279_i98@pure_quanta.q_capp(chips)',
 PATH='I98',
 DRAWING='@T6G_MB_LIB.T6G(SCH_1):PAGE388',
 TOLERANCE='20%',
 MATERIAL='SPCAP',
 PHYS_PAGE='279',
 XY='(-1450,5450)',
 ROT='0',
 VER='1',
 PACK_TYPE='SMLF',
 LOCATION='C7000',
 CDS_LIB='pure_quanta',
 CDS_PART_NAME='Q_CAPP_SMLF-470UF,2.5V,20%,SPCAP,CH747LM8818',
 VOLTAGE='2.5V',
 PART_NUMBER='CH747LM8818',
 VALUE='470UF',
 PRIM_FILE='./archive_libs/logical/q_capp/chips/chips.prt';

PART_NAME
 C7001 'Q_CAPP_SMLF-470UF,2.5V,20%,SPCAP,CH747LM8818':;

SECTION_NUMBER 1
 '@T6G_MB_LIB.T6G(SCH_1):PAGE388_I97@PURE_QUANTA.Q_CAPP(CHIPS)':
 C_PATH='@t6g_mb_lib.t6g(sch_1):page388_i97@pure_quanta.q_capp(chips)',
 P_PATH='@t6g_mb_lib.t6g(sch_1):page279_i97@pure_quanta.q_capp(chips)',
 PATH='I97',
 DRAWING='@T6G_MB_LIB.T6G(SCH_1):PAGE388',
 TOLERANCE='20%',
 MATERIAL='SPCAP',
 PHYS_PAGE='279',
 XY='(-1150,5450)',
 ROT='0',
 VER='1',
 PACK_TYPE='SMLF',
 LOCATION='C7001',
 CDS_LIB='pure_quanta',
 CDS_PART_NAME='Q_CAPP_SMLF-470UF,2.5V,20%,SPCAP,CH747LM8818',
 VOLTAGE='2.5V',
 PART_NUMBER='CH747LM8818',
 VALUE='470UF',
 PRIM_FILE='./archive_libs/logical/q_capp/chips/chips.prt';

PART_NAME
 C7002 'Q_CAP_C0805-47UF,4V,20%,X6S,CH647KMEA04':;

SECTION_NUMBER 1
 '@T6G_MB_LIB.T6G(SCH_1):PAGE388_I96@PURE_QUANTA.Q_CAP(CHIPS)':
 C_PATH='@t6g_mb_lib.t6g(sch_1):page388_i96@pure_quanta.q_cap(chips)',
 P_PATH='@t6g_mb_lib.t6g(sch_1):page279_i96@pure_quanta.q_cap(chips)',
 PATH='I96',
 DRAWING='@T6G_MB_LIB.T6G(SCH_1):PAGE388',
 TOLERANCE='20%',
 MATERIAL='X6S',
 PHYS_PAGE='279',
 XY='(-850,5450)',
 ROT='0',
 VER='1',
 PACK_TYPE='C0805',
 LOCATION='C7002',
 CDS_LIB='pure_quanta',
 CDS_PART_NAME='Q_CAP_C0805-47UF,4V,20%,X6S,CH647KMEA04',
 VOLTAGE='4V',
 PART_NUMBER='CH647KMEA04',
 VALUE='47UF',
 PRIM_FILE='./archive_libs/logical/q_cap/chips/chips.prt';

PART_NAME
 C7003 'Q_CAP_C0805-47UF,4V,20%,X6S,CH647KMEA04':;

SECTION_NUMBER 1
 '@T6G_MB_LIB.T6G(SCH_1):PAGE388_I95@PURE_QUANTA.Q_CAP(CHIPS)':
 C_PATH='@t6g_mb_lib.t6g(sch_1):page388_i95@pure_quanta.q_cap(chips)',
 P_PATH='@t6g_mb_lib.t6g(sch_1):page279_i95@pure_quanta.q_cap(chips)',
 PATH='I95',
 DRAWING='@T6G_MB_LIB.T6G(SCH_1):PAGE388',
 TOLERANCE='20%',
 MATERIAL='X6S',
 PHYS_PAGE='279',
 XY='(-450,5425)',
 ROT='0',
 VER='1',
 PACK_TYPE='C0805',
 LOCATION='C7003',
 CDS_LIB='pure_quanta',
 CDS_PART_NAME='Q_CAP_C0805-47UF,4V,20%,X6S,CH647KMEA04',
 VOLTAGE='4V',
 PART_NUMBER='CH647KMEA04',
 VALUE='47UF',
 PRIM_FILE='./archive_libs/logical/q_cap/chips/chips.prt';

PART_NAME
 C7004 'Q_CAPP_SMLF-470UF,2.5V,20%,SPCAP,CH747LM8818':;

SECTION_NUMBER 1
 '@T6G_MB_LIB.T6G(SCH_1):PAGE454_I94@PURE_QUANTA.Q_CAPP(CHIPS)':
 C_PATH='@t6g_mb_lib.t6g(sch_1):page454_i94@pure_quanta.q_capp(chips)',
 P_PATH='@t6g_mb_lib.t6g(sch_1):page345_i94@pure_quanta.q_capp(chips)',
 PATH='I94',
 DRAWING='@T6G_MB_LIB.T6G(SCH_1):PAGE454',
 TOLERANCE='20%',
 MATERIAL='SPCAP',
 PHYS_PAGE='345',
 XY='(-1500,5600)',
 ROT='0',
 VER='1',
 PACK_TYPE='SMLF',
 LOCATION='C7004',
 CDS_LIB='pure_quanta',
 CDS_PART_NAME='Q_CAPP_SMLF-470UF,2.5V,20%,SPCAP,CH747LM8818',
 VOLTAGE='2.5V',
 PART_NUMBER='CH747LM8818',
 VALUE='470UF',
 PRIM_FILE='./archive_libs/logical/q_capp/chips/chips.prt';

PART_NAME
 C7005 'Q_CAPP_SMLF-470UF,2.5V,20%,SPCAP,CH747LM8818':;

SECTION_NUMBER 1
 '@T6G_MB_LIB.T6G(SCH_1):PAGE454_I95@PURE_QUANTA.Q_CAPP(CHIPS)':
 C_PATH='@t6g_mb_lib.t6g(sch_1):page454_i95@pure_quanta.q_capp(chips)',
 P_PATH='@t6g_mb_lib.t6g(sch_1):page345_i95@pure_quanta.q_capp(chips)',
 PATH='I95',
 DRAWING='@T6G_MB_LIB.T6G(SCH_1):PAGE454',
 TOLERANCE='20%',
 MATERIAL='SPCAP',
 PHYS_PAGE='345',
 XY='(-1200,5600)',
 ROT='0',
 VER='1',
 PACK_TYPE='SMLF',
 LOCATION='C7005',
 CDS_LIB='pure_quanta',
 CDS_PART_NAME='Q_CAPP_SMLF-470UF,2.5V,20%,SPCAP,CH747LM8818',
 VOLTAGE='2.5V',
 PART_NUMBER='CH747LM8818',
 VALUE='470UF',
 PRIM_FILE='./archive_libs/logical/q_capp/chips/chips.prt';

PART_NAME
 C7006 'Q_CAP_C0805-47UF,4V,20%,X6S,CH647KMEA04':;

SECTION_NUMBER 1
 '@T6G_MB_LIB.T6G(SCH_1):PAGE454_I96@PURE_QUANTA.Q_CAP(CHIPS)':
 C_PATH='@t6g_mb_lib.t6g(sch_1):page454_i96@pure_quanta.q_cap(chips)',
 P_PATH='@t6g_mb_lib.t6g(sch_1):page345_i96@pure_quanta.q_cap(chips)',
 PATH='I96',
 DRAWING='@T6G_MB_LIB.T6G(SCH_1):PAGE454',
 TOLERANCE='20%',
 MATERIAL='X6S',
 PHYS_PAGE='345',
 XY='(-900,5600)',
 ROT='0',
 VER='1',
 PACK_TYPE='C0805',
 LOCATION='C7006',
 CDS_LIB='pure_quanta',
 CDS_PART_NAME='Q_CAP_C0805-47UF,4V,20%,X6S,CH647KMEA04',
 VOLTAGE='4V',
 PART_NUMBER='CH647KMEA04',
 VALUE='47UF',
 PRIM_FILE='./archive_libs/logical/q_cap/chips/chips.prt';

PART_NAME
 C7007 'Q_CAP_C0805-47UF,4V,20%,X6S,CH647KMEA04':;

SECTION_NUMBER 1
 '@T6G_MB_LIB.T6G(SCH_1):PAGE454_I97@PURE_QUANTA.Q_CAP(CHIPS)':
 C_PATH='@t6g_mb_lib.t6g(sch_1):page454_i97@pure_quanta.q_cap(chips)',
 P_PATH='@t6g_mb_lib.t6g(sch_1):page345_i97@pure_quanta.q_cap(chips)',
 PATH='I97',
 DRAWING='@T6G_MB_LIB.T6G(SCH_1):PAGE454',
 TOLERANCE='20%',
 MATERIAL='X6S',
 PHYS_PAGE='345',
 XY='(-500,5575)',
 ROT='0',
 VER='1',
 PACK_TYPE='C0805',
 LOCATION='C7007',
 CDS_LIB='pure_quanta',
 CDS_PART_NAME='Q_CAP_C0805-47UF,4V,20%,X6S,CH647KMEA04',
 VOLTAGE='4V',
 PART_NUMBER='CH647KMEA04',
 VALUE='47UF',
 PRIM_FILE='./archive_libs/logical/q_cap/chips/chips.prt';

PART_NAME
 C7008 'Q_CAPP_SMLF-470UF,2.5V,20%,SPCAP,CH747LM8818':;

SECTION_NUMBER 1
 '@T6G_MB_LIB.T6G(SCH_1):PAGE388_I99@PURE_QUANTA.Q_CAPP(CHIPS)':
 C_PATH='@t6g_mb_lib.t6g(sch_1):page388_i99@pure_quanta.q_capp(chips)',
 P_PATH='@t6g_mb_lib.t6g(sch_1):page279_i99@pure_quanta.q_capp(chips)',
 PATH='I99',
 DRAWING='@T6G_MB_LIB.T6G(SCH_1):PAGE388',
 TOLERANCE='20%',
 MATERIAL='SPCAP',
 PHYS_PAGE='279',
 XY='(-1050,2250)',
 ROT='0',
 VER='1',
 PACK_TYPE='SMLF',
 LOCATION='C7008',
 CDS_LIB='pure_quanta',
 CDS_PART_NAME='Q_CAPP_SMLF-470UF,2.5V,20%,SPCAP,CH747LM8818',
 VOLTAGE='2.5V',
 PART_NUMBER='CH747LM8818',
 VALUE='470UF',
 PRIM_FILE='./archive_libs/logical/q_capp/chips/chips.prt';

PART_NAME
 C7009 'Q_CAPP_SMLF-470UF,2.5V,20%,SPCAP,CH747LM8818':;

SECTION_NUMBER 1
 '@T6G_MB_LIB.T6G(SCH_1):PAGE388_I100@PURE_QUANTA.Q_CAPP(CHIPS)':
 C_PATH='@t6g_mb_lib.t6g(sch_1):page388_i100@pure_quanta.q_capp(chips)',
 P_PATH='@t6g_mb_lib.t6g(sch_1):page279_i100@pure_quanta.q_capp(chips)',
 PATH='I100',
 DRAWING='@T6G_MB_LIB.T6G(SCH_1):PAGE388',
 TOLERANCE='20%',
 MATERIAL='SPCAP',
 PHYS_PAGE='279',
 XY='(-750,2250)',
 ROT='0',
 VER='1',
 PACK_TYPE='SMLF',
 LOCATION='C7009',
 CDS_LIB='pure_quanta',
 CDS_PART_NAME='Q_CAPP_SMLF-470UF,2.5V,20%,SPCAP,CH747LM8818',
 VOLTAGE='2.5V',
 PART_NUMBER='CH747LM8818',
 VALUE='470UF',
 PRIM_FILE='./archive_libs/logical/q_capp/chips/chips.prt';

PART_NAME
 C7010 'Q_CAP_C0805-100UF,4V,20%,X6S,CH710KMEA01':;

SECTION_NUMBER 1
 '@T6G_MB_LIB.T6G(SCH_1):PAGE388_I101@PURE_QUANTA.Q_CAP(CHIPS)':
 C_PATH='@t6g_mb_lib.t6g(sch_1):page388_i101@pure_quanta.q_cap(chips)',
 P_PATH='@t6g_mb_lib.t6g(sch_1):page279_i101@pure_quanta.q_cap(chips)',
 PATH='I101',
 DRAWING='@T6G_MB_LIB.T6G(SCH_1):PAGE388',
 TOLERANCE='20%',
 MATERIAL='X6S',
 PHYS_PAGE='279',
 XY='(-475,2250)',
 ROT='0',
 VER='1',
 PACK_TYPE='C0805',
 LOCATION='C7010',
 CDS_LIB='pure_quanta',
 CDS_PART_NAME='Q_CAP_C0805-100UF,4V,20%,X6S,CH710KMEA01',
 VOLTAGE='4V',
 PART_NUMBER='CH710KMEA01',
 VALUE='100UF',
 PRIM_FILE='./archive_libs/logical/q_cap/chips/chips.prt';

PART_NAME
 C7011 'Q_CAPP_SMLF-470UF,2.5V,20%,SPCAP,CH747LM8818':;

SECTION_NUMBER 1
 '@T6G_MB_LIB.T6G(SCH_1):PAGE411_I95@PURE_QUANTA.Q_CAPP(CHIPS)':
 C_PATH='@t6g_mb_lib.t6g(sch_1):page411_i95@pure_quanta.q_capp(chips)',
 P_PATH='@t6g_mb_lib.t6g(sch_1):page290_i95@pure_quanta.q_capp(chips)',
 PATH='I95',
 DRAWING='@T6G_MB_LIB.T6G(SCH_1):PAGE411',
 TOLERANCE='20%',
 MATERIAL='SPCAP',
 PHYS_PAGE='290',
 XY='(-1275,1950)',
 ROT='0',
 VER='1',
 PACK_TYPE='SMLF',
 LOCATION='C7011',
 CDS_LIB='pure_quanta',
 CDS_PART_NAME='Q_CAPP_SMLF-470UF,2.5V,20%,SPCAP,CH747LM8818',
 VOLTAGE='2.5V',
 PART_NUMBER='CH747LM8818',
 VALUE='470UF',
 PRIM_FILE='./archive_libs/logical/q_capp/chips/chips.prt';

PART_NAME
 C7012 'Q_CAPP_SMLF-470UF,2.5V,20%,SPCAP,CH747LM8818':;

SECTION_NUMBER 1
 '@T6G_MB_LIB.T6G(SCH_1):PAGE411_I96@PURE_QUANTA.Q_CAPP(CHIPS)':
 C_PATH='@t6g_mb_lib.t6g(sch_1):page411_i96@pure_quanta.q_capp(chips)',
 P_PATH='@t6g_mb_lib.t6g(sch_1):page290_i96@pure_quanta.q_capp(chips)',
 PATH='I96',
 DRAWING='@T6G_MB_LIB.T6G(SCH_1):PAGE411',
 TOLERANCE='20%',
 MATERIAL='SPCAP',
 PHYS_PAGE='290',
 XY='(-975,1950)',
 ROT='0',
 VER='1',
 PACK_TYPE='SMLF',
 LOCATION='C7012',
 CDS_LIB='pure_quanta',
 CDS_PART_NAME='Q_CAPP_SMLF-470UF,2.5V,20%,SPCAP,CH747LM8818',
 VOLTAGE='2.5V',
 PART_NUMBER='CH747LM8818',
 VALUE='470UF',
 PRIM_FILE='./archive_libs/logical/q_capp/chips/chips.prt';

PART_NAME
 C7013 'Q_CAP_C0805-100UF,4V,20%,X6S,CH710KMEA01':;

SECTION_NUMBER 1
 '@T6G_MB_LIB.T6G(SCH_1):PAGE411_I97@PURE_QUANTA.Q_CAP(CHIPS)':
 C_PATH='@t6g_mb_lib.t6g(sch_1):page411_i97@pure_quanta.q_cap(chips)',
 P_PATH='@t6g_mb_lib.t6g(sch_1):page290_i97@pure_quanta.q_cap(chips)',
 PATH='I97',
 DRAWING='@T6G_MB_LIB.T6G(SCH_1):PAGE411',
 TOLERANCE='20%',
 MATERIAL='X6S',
 PHYS_PAGE='290',
 XY='(-675,1950)',
 ROT='0',
 VER='1',
 PACK_TYPE='C0805',
 LOCATION='C7013',
 CDS_LIB='pure_quanta',
 CDS_PART_NAME='Q_CAP_C0805-100UF,4V,20%,X6S,CH710KMEA01',
 VOLTAGE='4V',
 PART_NUMBER='CH710KMEA01',
 VALUE='100UF',
 PRIM_FILE='./archive_libs/logical/q_cap/chips/chips.prt';

PART_NAME
 C7014 'Q_CAPP_SMLF-470UF,2.5V,20%,SPCAP,CH747LM8818':;

SECTION_NUMBER 1
 '@T6G_MB_LIB.T6G(SCH_1):PAGE422_I94@PURE_QUANTA.Q_CAPP(CHIPS)':
 C_PATH='@t6g_mb_lib.t6g(sch_1):page422_i94@pure_quanta.q_capp(chips)',
 P_PATH='@t6g_mb_lib.t6g(sch_1):page301_i94@pure_quanta.q_capp(chips)',
 PATH='I94',
 DRAWING='@T6G_MB_LIB.T6G(SCH_1):PAGE422',
 TOLERANCE='20%',
 MATERIAL='SPCAP',
 PHYS_PAGE='301',
 XY='(-975,2525)',
 ROT='0',
 VER='1',
 PACK_TYPE='SMLF',
 LOCATION='C7014',
 CDS_LIB='pure_quanta',
 CDS_PART_NAME='Q_CAPP_SMLF-470UF,2.5V,20%,SPCAP,CH747LM8818',
 VOLTAGE='2.5V',
 PART_NUMBER='CH747LM8818',
 VALUE='470UF',
 PRIM_FILE='./archive_libs/logical/q_capp/chips/chips.prt';

PART_NAME
 C7015 'Q_CAPP_SMLF-470UF,2.5V,20%,SPCAP,CH747LM8818':;

SECTION_NUMBER 1
 '@T6G_MB_LIB.T6G(SCH_1):PAGE422_I95@PURE_QUANTA.Q_CAPP(CHIPS)':
 C_PATH='@t6g_mb_lib.t6g(sch_1):page422_i95@pure_quanta.q_capp(chips)',
 P_PATH='@t6g_mb_lib.t6g(sch_1):page301_i95@pure_quanta.q_capp(chips)',
 PATH='I95',
 DRAWING='@T6G_MB_LIB.T6G(SCH_1):PAGE422',
 TOLERANCE='20%',
 MATERIAL='SPCAP',
 PHYS_PAGE='301',
 XY='(-675,2525)',
 ROT='0',
 VER='1',
 PACK_TYPE='SMLF',
 LOCATION='C7015',
 CDS_LIB='pure_quanta',
 CDS_PART_NAME='Q_CAPP_SMLF-470UF,2.5V,20%,SPCAP,CH747LM8818',
 VOLTAGE='2.5V',
 PART_NUMBER='CH747LM8818',
 VALUE='470UF',
 PRIM_FILE='./archive_libs/logical/q_capp/chips/chips.prt';

PART_NAME
 C7016 'Q_CAP_C0805-100UF,4V,20%,X6S,CH710KMEA01':;

SECTION_NUMBER 1
 '@T6G_MB_LIB.T6G(SCH_1):PAGE422_I96@PURE_QUANTA.Q_CAP(CHIPS)':
 C_PATH='@t6g_mb_lib.t6g(sch_1):page422_i96@pure_quanta.q_cap(chips)',
 P_PATH='@t6g_mb_lib.t6g(sch_1):page301_i96@pure_quanta.q_cap(chips)',
 PATH='I96',
 DRAWING='@T6G_MB_LIB.T6G(SCH_1):PAGE422',
 TOLERANCE='20%',
 MATERIAL='X6S',
 PHYS_PAGE='301',
 XY='(-375,2525)',
 ROT='0',
 VER='1',
 PACK_TYPE='C0805',
 LOCATION='C7016',
 CDS_LIB='pure_quanta',
 CDS_PART_NAME='Q_CAP_C0805-100UF,4V,20%,X6S,CH710KMEA01',
 VOLTAGE='4V',
 PART_NUMBER='CH710KMEA01',
 VALUE='100UF',
 PRIM_FILE='./archive_libs/logical/q_cap/chips/chips.prt';

PART_NAME
 C7017 'Q_CAPP_SMLF-470UF,2.5V,20%,SPCAP,CH747LM8818':;

SECTION_NUMBER 1
 '@T6G_MB_LIB.T6G(SCH_1):PAGE433_I94@PURE_QUANTA.Q_CAPP(CHIPS)':
 C_PATH='@t6g_mb_lib.t6g(sch_1):page433_i94@pure_quanta.q_capp(chips)',
 P_PATH='@t6g_mb_lib.t6g(sch_1):page312_i94@pure_quanta.q_capp(chips)',
 PATH='I94',
 DRAWING='@T6G_MB_LIB.T6G(SCH_1):PAGE433',
 TOLERANCE='20%',
 MATERIAL='SPCAP',
 PHYS_PAGE='312',
 XY='(-1200,2450)',
 ROT='0',
 VER='1',
 PACK_TYPE='SMLF',
 LOCATION='C7017',
 CDS_LIB='pure_quanta',
 CDS_PART_NAME='Q_CAPP_SMLF-470UF,2.5V,20%,SPCAP,CH747LM8818',
 VOLTAGE='2.5V',
 PART_NUMBER='CH747LM8818',
 VALUE='470UF',
 PRIM_FILE='./archive_libs/logical/q_capp/chips/chips.prt';

PART_NAME
 C7018 'Q_CAPP_SMLF-470UF,2.5V,20%,SPCAP,CH747LM8818':;

SECTION_NUMBER 1
 '@T6G_MB_LIB.T6G(SCH_1):PAGE433_I95@PURE_QUANTA.Q_CAPP(CHIPS)':
 C_PATH='@t6g_mb_lib.t6g(sch_1):page433_i95@pure_quanta.q_capp(chips)',
 P_PATH='@t6g_mb_lib.t6g(sch_1):page312_i95@pure_quanta.q_capp(chips)',
 PATH='I95',
 DRAWING='@T6G_MB_LIB.T6G(SCH_1):PAGE433',
 TOLERANCE='20%',
 MATERIAL='SPCAP',
 PHYS_PAGE='312',
 XY='(-900,2450)',
 ROT='0',
 VER='1',
 PACK_TYPE='SMLF',
 LOCATION='C7018',
 CDS_LIB='pure_quanta',
 CDS_PART_NAME='Q_CAPP_SMLF-470UF,2.5V,20%,SPCAP,CH747LM8818',
 VOLTAGE='2.5V',
 PART_NUMBER='CH747LM8818',
 VALUE='470UF',
 PRIM_FILE='./archive_libs/logical/q_capp/chips/chips.prt';

PART_NAME
 C7019 'Q_CAP_C0805-100UF,4V,20%,X6S,CH710KMEA01':;

SECTION_NUMBER 1
 '@T6G_MB_LIB.T6G(SCH_1):PAGE433_I96@PURE_QUANTA.Q_CAP(CHIPS)':
 C_PATH='@t6g_mb_lib.t6g(sch_1):page433_i96@pure_quanta.q_cap(chips)',
 P_PATH='@t6g_mb_lib.t6g(sch_1):page312_i96@pure_quanta.q_cap(chips)',
 PATH='I96',
 DRAWING='@T6G_MB_LIB.T6G(SCH_1):PAGE433',
 TOLERANCE='20%',
 MATERIAL='X6S',
 PHYS_PAGE='312',
 XY='(-600,2450)',
 ROT='0',
 VER='1',
 PACK_TYPE='C0805',
 LOCATION='C7019',
 CDS_LIB='pure_quanta',
 CDS_PART_NAME='Q_CAP_C0805-100UF,4V,20%,X6S,CH710KMEA01',
 VOLTAGE='4V',
 PART_NUMBER='CH710KMEA01',
 VALUE='100UF',
 PRIM_FILE='./archive_libs/logical/q_cap/chips/chips.prt';

PART_NAME
 C7020 'Q_CAPP_SMLF-470UF,2.5V,20%,SPCAP,CH747LM8818':;

SECTION_NUMBER 1
 '@T6G_MB_LIB.T6G(SCH_1):PAGE398_I103@PURE_QUANTA.Q_CAPP(CHIPS)':
 C_PATH='@t6g_mb_lib.t6g(sch_1):page398_i103@pure_quanta.q_capp(chips)',
 P_PATH='@t6g_mb_lib.t6g(sch_1):page323_i103@pure_quanta.q_capp(chips)',
 PATH='I103',
 DRAWING='@T6G_MB_LIB.T6G(SCH_1):PAGE398',
 TOLERANCE='20%',
 MATERIAL='SPCAP',
 PHYS_PAGE='323',
 XY='(-1350,2550)',
 ROT='0',
 VER='1',
 PACK_TYPE='SMLF',
 LOCATION='C7020',
 CDS_LIB='pure_quanta',
 CDS_PART_NAME='Q_CAPP_SMLF-470UF,2.5V,20%,SPCAP,CH747LM8818',
 VOLTAGE='2.5V',
 PART_NUMBER='CH747LM8818',
 VALUE='470UF',
 PRIM_FILE='./archive_libs/logical/q_capp/chips/chips.prt';

PART_NAME
 C7021 'Q_CAPP_SMLF-470UF,2.5V,20%,SPCAP,CH747LM8818':;

SECTION_NUMBER 1
 '@T6G_MB_LIB.T6G(SCH_1):PAGE398_I104@PURE_QUANTA.Q_CAPP(CHIPS)':
 C_PATH='@t6g_mb_lib.t6g(sch_1):page398_i104@pure_quanta.q_capp(chips)',
 P_PATH='@t6g_mb_lib.t6g(sch_1):page323_i104@pure_quanta.q_capp(chips)',
 PATH='I104',
 DRAWING='@T6G_MB_LIB.T6G(SCH_1):PAGE398',
 TOLERANCE='20%',
 MATERIAL='SPCAP',
 PHYS_PAGE='323',
 XY='(-1050,2550)',
 ROT='0',
 VER='1',
 PACK_TYPE='SMLF',
 LOCATION='C7021',
 CDS_LIB='pure_quanta',
 CDS_PART_NAME='Q_CAPP_SMLF-470UF,2.5V,20%,SPCAP,CH747LM8818',
 VOLTAGE='2.5V',
 PART_NUMBER='CH747LM8818',
 VALUE='470UF',
 PRIM_FILE='./archive_libs/logical/q_capp/chips/chips.prt';

PART_NAME
 C7022 'Q_CAP_C0805-100UF,4V,20%,X6S,CH710KMEA01':;

SECTION_NUMBER 1
 '@T6G_MB_LIB.T6G(SCH_1):PAGE398_I105@PURE_QUANTA.Q_CAP(CHIPS)':
 C_PATH='@t6g_mb_lib.t6g(sch_1):page398_i105@pure_quanta.q_cap(chips)',
 P_PATH='@t6g_mb_lib.t6g(sch_1):page323_i105@pure_quanta.q_cap(chips)',
 PATH='I105',
 DRAWING='@T6G_MB_LIB.T6G(SCH_1):PAGE398',
 TOLERANCE='20%',
 MATERIAL='X6S',
 PHYS_PAGE='323',
 XY='(-750,2550)',
 ROT='0',
 VER='1',
 PACK_TYPE='C0805',
 LOCATION='C7022',
 CDS_LIB='pure_quanta',
 CDS_PART_NAME='Q_CAP_C0805-100UF,4V,20%,X6S,CH710KMEA01',
 VOLTAGE='4V',
 PART_NUMBER='CH710KMEA01',
 VALUE='100UF',
 PRIM_FILE='./archive_libs/logical/q_cap/chips/chips.prt';

PART_NAME
 C7023 'Q_CAPP_SMLF-470UF,2.5V,20%,SPCAP,CH747LM8818':;

SECTION_NUMBER 1
 '@T6G_MB_LIB.T6G(SCH_1):PAGE443_I94@PURE_QUANTA.Q_CAPP(CHIPS)':
 C_PATH='@t6g_mb_lib.t6g(sch_1):page443_i94@pure_quanta.q_capp(chips)',
 P_PATH='@t6g_mb_lib.t6g(sch_1):page334_i94@pure_quanta.q_capp(chips)',
 PATH='I94',
 DRAWING='@T6G_MB_LIB.T6G(SCH_1):PAGE443',
 TOLERANCE='20%',
 MATERIAL='SPCAP',
 PHYS_PAGE='334',
 XY='(-1100,2050)',
 ROT='0',
 VER='1',
 PACK_TYPE='SMLF',
 LOCATION='C7023',
 CDS_LIB='pure_quanta',
 CDS_PART_NAME='Q_CAPP_SMLF-470UF,2.5V,20%,SPCAP,CH747LM8818',
 VOLTAGE='2.5V',
 PART_NUMBER='CH747LM8818',
 VALUE='470UF',
 PRIM_FILE='./archive_libs/logical/q_capp/chips/chips.prt';

PART_NAME
 C7024 'Q_CAPP_SMLF-470UF,2.5V,20%,SPCAP,CH747LM8818':;

SECTION_NUMBER 1
 '@T6G_MB_LIB.T6G(SCH_1):PAGE443_I95@PURE_QUANTA.Q_CAPP(CHIPS)':
 C_PATH='@t6g_mb_lib.t6g(sch_1):page443_i95@pure_quanta.q_capp(chips)',
 P_PATH='@t6g_mb_lib.t6g(sch_1):page334_i95@pure_quanta.q_capp(chips)',
 PATH='I95',
 DRAWING='@T6G_MB_LIB.T6G(SCH_1):PAGE443',
 TOLERANCE='20%',
 MATERIAL='SPCAP',
 PHYS_PAGE='334',
 XY='(-800,2050)',
 ROT='0',
 VER='1',
 PACK_TYPE='SMLF',
 LOCATION='C7024',
 CDS_LIB='pure_quanta',
 CDS_PART_NAME='Q_CAPP_SMLF-470UF,2.5V,20%,SPCAP,CH747LM8818',
 VOLTAGE='2.5V',
 PART_NUMBER='CH747LM8818',
 VALUE='470UF',
 PRIM_FILE='./archive_libs/logical/q_capp/chips/chips.prt';

PART_NAME
 C7025 'Q_CAP_C0805-100UF,4V,20%,X6S,CH710KMEA01':;

SECTION_NUMBER 1
 '@T6G_MB_LIB.T6G(SCH_1):PAGE443_I96@PURE_QUANTA.Q_CAP(CHIPS)':
 C_PATH='@t6g_mb_lib.t6g(sch_1):page443_i96@pure_quanta.q_cap(chips)',
 P_PATH='@t6g_mb_lib.t6g(sch_1):page334_i96@pure_quanta.q_cap(chips)',
 PATH='I96',
 DRAWING='@T6G_MB_LIB.T6G(SCH_1):PAGE443',
 TOLERANCE='20%',
 MATERIAL='X6S',
 PHYS_PAGE='334',
 XY='(-500,2050)',
 ROT='0',
 VER='1',
 PACK_TYPE='C0805',
 LOCATION='C7025',
 CDS_LIB='pure_quanta',
 CDS_PART_NAME='Q_CAP_C0805-100UF,4V,20%,X6S,CH710KMEA01',
 VOLTAGE='4V',
 PART_NUMBER='CH710KMEA01',
 VALUE='100UF',
 PRIM_FILE='./archive_libs/logical/q_cap/chips/chips.prt';

PART_NAME
 C7026 'Q_CAPP_SMLF-470UF,2.5V,20%,SPCAP,CH747LM8818':;

SECTION_NUMBER 1
 '@T6G_MB_LIB.T6G(SCH_1):PAGE454_I98@PURE_QUANTA.Q_CAPP(CHIPS)':
 C_PATH='@t6g_mb_lib.t6g(sch_1):page454_i98@pure_quanta.q_capp(chips)',
 P_PATH='@t6g_mb_lib.t6g(sch_1):page345_i98@pure_quanta.q_capp(chips)',
 PATH='I98',
 DRAWING='@T6G_MB_LIB.T6G(SCH_1):PAGE454',
 TOLERANCE='20%',
 MATERIAL='SPCAP',
 PHYS_PAGE='345',
 XY='(-1025,2400)',
 ROT='0',
 VER='1',
 PACK_TYPE='SMLF',
 LOCATION='C7026',
 CDS_LIB='pure_quanta',
 CDS_PART_NAME='Q_CAPP_SMLF-470UF,2.5V,20%,SPCAP,CH747LM8818',
 VOLTAGE='2.5V',
 PART_NUMBER='CH747LM8818',
 VALUE='470UF',
 PRIM_FILE='./archive_libs/logical/q_capp/chips/chips.prt';

PART_NAME
 C7027 'Q_CAPP_SMLF-470UF,2.5V,20%,SPCAP,CH747LM8818':;

SECTION_NUMBER 1
 '@T6G_MB_LIB.T6G(SCH_1):PAGE454_I99@PURE_QUANTA.Q_CAPP(CHIPS)':
 C_PATH='@t6g_mb_lib.t6g(sch_1):page454_i99@pure_quanta.q_capp(chips)',
 P_PATH='@t6g_mb_lib.t6g(sch_1):page345_i99@pure_quanta.q_capp(chips)',
 PATH='I99',
 DRAWING='@T6G_MB_LIB.T6G(SCH_1):PAGE454',
 TOLERANCE='20%',
 MATERIAL='SPCAP',
 PHYS_PAGE='345',
 XY='(-725,2400)',
 ROT='0',
 VER='1',
 PACK_TYPE='SMLF',
 LOCATION='C7027',
 CDS_LIB='pure_quanta',
 CDS_PART_NAME='Q_CAPP_SMLF-470UF,2.5V,20%,SPCAP,CH747LM8818',
 VOLTAGE='2.5V',
 PART_NUMBER='CH747LM8818',
 VALUE='470UF',
 PRIM_FILE='./archive_libs/logical/q_capp/chips/chips.prt';

PART_NAME
 C7028 'Q_CAP_C0805-100UF,4V,20%,X6S,CH710KMEA01':;

SECTION_NUMBER 1
 '@T6G_MB_LIB.T6G(SCH_1):PAGE454_I100@PURE_QUANTA.Q_CAP(CHIPS)':
 C_PATH='@t6g_mb_lib.t6g(sch_1):page454_i100@pure_quanta.q_cap(chips)',
 P_PATH='@t6g_mb_lib.t6g(sch_1):page345_i100@pure_quanta.q_cap(chips)',
 PATH='I100',
 DRAWING='@T6G_MB_LIB.T6G(SCH_1):PAGE454',
 TOLERANCE='20%',
 MATERIAL='X6S',
 PHYS_PAGE='345',
 XY='(-425,2400)',
 ROT='0',
 VER='1',
 PACK_TYPE='C0805',
 LOCATION='C7028',
 CDS_LIB='pure_quanta',
 CDS_PART_NAME='Q_CAP_C0805-100UF,4V,20%,X6S,CH710KMEA01',
 VOLTAGE='4V',
 PART_NUMBER='CH710KMEA01',
 VALUE='100UF',
 PRIM_FILE='./archive_libs/logical/q_cap/chips/chips.prt';

PART_NAME
 C7029 'Q_CAPP_SMLF-470UF,2.5V,20%,SPCAP,CH747LM8818':;

SECTION_NUMBER 1
 '@T6G_MB_LIB.T6G(SCH_1):PAGE465_I94@PURE_QUANTA.Q_CAPP(CHIPS)':
 C_PATH='@t6g_mb_lib.t6g(sch_1):page465_i94@pure_quanta.q_capp(chips)',
 P_PATH='@t6g_mb_lib.t6g(sch_1):page356_i94@pure_quanta.q_capp(chips)',
 PATH='I94',
 DRAWING='@T6G_MB_LIB.T6G(SCH_1):PAGE465',
 TOLERANCE='20%',
 MATERIAL='SPCAP',
 PHYS_PAGE='356',
 XY='(-1075,2225)',
 ROT='0',
 VER='1',
 PACK_TYPE='SMLF',
 LOCATION='C7029',
 CDS_LIB='pure_quanta',
 CDS_PART_NAME='Q_CAPP_SMLF-470UF,2.5V,20%,SPCAP,CH747LM8818',
 VOLTAGE='2.5V',
 PART_NUMBER='CH747LM8818',
 VALUE='470UF',
 PRIM_FILE='./archive_libs/logical/q_capp/chips/chips.prt';

PART_NAME
 C7030 'Q_CAPP_SMLF-470UF,2.5V,20%,SPCAP,CH747LM8818':;

SECTION_NUMBER 1
 '@T6G_MB_LIB.T6G(SCH_1):PAGE465_I95@PURE_QUANTA.Q_CAPP(CHIPS)':
 C_PATH='@t6g_mb_lib.t6g(sch_1):page465_i95@pure_quanta.q_capp(chips)',
 P_PATH='@t6g_mb_lib.t6g(sch_1):page356_i95@pure_quanta.q_capp(chips)',
 PATH='I95',
 DRAWING='@T6G_MB_LIB.T6G(SCH_1):PAGE465',
 TOLERANCE='20%',
 MATERIAL='SPCAP',
 PHYS_PAGE='356',
 XY='(-775,2225)',
 ROT='0',
 VER='1',
 PACK_TYPE='SMLF',
 LOCATION='C7030',
 CDS_LIB='pure_quanta',
 CDS_PART_NAME='Q_CAPP_SMLF-470UF,2.5V,20%,SPCAP,CH747LM8818',
 VOLTAGE='2.5V',
 PART_NUMBER='CH747LM8818',
 VALUE='470UF',
 PRIM_FILE='./archive_libs/logical/q_capp/chips/chips.prt';

PART_NAME
 C7031 'Q_CAP_C0805-100UF,4V,20%,X6S,CH710KMEA01':;

SECTION_NUMBER 1
 '@T6G_MB_LIB.T6G(SCH_1):PAGE465_I96@PURE_QUANTA.Q_CAP(CHIPS)':
 C_PATH='@t6g_mb_lib.t6g(sch_1):page465_i96@pure_quanta.q_cap(chips)',
 P_PATH='@t6g_mb_lib.t6g(sch_1):page356_i96@pure_quanta.q_cap(chips)',
 PATH='I96',
 DRAWING='@T6G_MB_LIB.T6G(SCH_1):PAGE465',
 TOLERANCE='20%',
 MATERIAL='X6S',
 PHYS_PAGE='356',
 XY='(-475,2225)',
 ROT='0',
 VER='1',
 PACK_TYPE='C0805',
 LOCATION='C7031',
 CDS_LIB='pure_quanta',
 CDS_PART_NAME='Q_CAP_C0805-100UF,4V,20%,X6S,CH710KMEA01',
 VOLTAGE='4V',
 PART_NUMBER='CH710KMEA01',
 VALUE='100UF',
 PRIM_FILE='./archive_libs/logical/q_cap/chips/chips.prt';

PART_NAME
 C7032 'Q_CAPP_SMLF-470UF,2.5V,20%,SPCAP,CH747LM8818':;

SECTION_NUMBER 1
 '@T6G_MB_LIB.T6G(SCH_1):PAGE388_I102@PURE_QUANTA.Q_CAPP(CHIPS)':
 C_PATH='@t6g_mb_lib.t6g(sch_1):page388_i102@pure_quanta.q_capp(chips)',
 P_PATH='@t6g_mb_lib.t6g(sch_1):page279_i102@pure_quanta.q_capp(chips)',
 PATH='I102',
 DRAWING='@T6G_MB_LIB.T6G(SCH_1):PAGE388',
 TOLERANCE='20%',
 MATERIAL='SPCAP',
 PHYS_PAGE='279',
 XY='(-2000,4875)',
 ROT='0',
 VER='1',
 PACK_TYPE='SMLF',
 LOCATION='C7032',
 CDS_LIB='pure_quanta',
 CDS_PART_NAME='Q_CAPP_SMLF-470UF,2.5V,20%,SPCAP,CH747LM8818',
 VOLTAGE='2.5V',
 PART_NUMBER='CH747LM8818',
 VALUE='470UF',
 PRIM_FILE='./archive_libs/logical/q_capp/chips/chips.prt';

PART_NAME
 C7033 'Q_CAP_C0805-47UF,4V,20%,X6S,CH647KMEA04':;

SECTION_NUMBER 1
 '@T6G_MB_LIB.T6G(SCH_1):PAGE388_I103@PURE_QUANTA.Q_CAP(CHIPS)':
 C_PATH='@t6g_mb_lib.t6g(sch_1):page388_i103@pure_quanta.q_cap(chips)',
 P_PATH='@t6g_mb_lib.t6g(sch_1):page279_i103@pure_quanta.q_cap(chips)',
 PATH='I103',
 DRAWING='@T6G_MB_LIB.T6G(SCH_1):PAGE388',
 TOLERANCE='20%',
 MATERIAL='X6S',
 PHYS_PAGE='279',
 XY='(-1650,4875)',
 ROT='0',
 VER='1',
 PACK_TYPE='C0805',
 LOCATION='C7033',
 CDS_LIB='pure_quanta',
 CDS_PART_NAME='Q_CAP_C0805-47UF,4V,20%,X6S,CH647KMEA04',
 VOLTAGE='4V',
 PART_NUMBER='CH647KMEA04',
 VALUE='47UF',
 PRIM_FILE='./archive_libs/logical/q_cap/chips/chips.prt';

PART_NAME
 C7034 'Q_CAP_C0805-47UF,4V,20%,X6S,CH647KMEA04':;

SECTION_NUMBER 1
 '@T6G_MB_LIB.T6G(SCH_1):PAGE388_I104@PURE_QUANTA.Q_CAP(CHIPS)':
 C_PATH='@t6g_mb_lib.t6g(sch_1):page388_i104@pure_quanta.q_cap(chips)',
 P_PATH='@t6g_mb_lib.t6g(sch_1):page279_i104@pure_quanta.q_cap(chips)',
 PATH='I104',
 DRAWING='@T6G_MB_LIB.T6G(SCH_1):PAGE388',
 TOLERANCE='20%',
 MATERIAL='X6S',
 PHYS_PAGE='279',
 XY='(-1375,4875)',
 ROT='0',
 VER='1',
 PACK_TYPE='C0805',
 LOCATION='C7034',
 CDS_LIB='pure_quanta',
 CDS_PART_NAME='Q_CAP_C0805-47UF,4V,20%,X6S,CH647KMEA04',
 VOLTAGE='4V',
 PART_NUMBER='CH647KMEA04',
 VALUE='47UF',
 PRIM_FILE='./archive_libs/logical/q_cap/chips/chips.prt';

PART_NAME
 C7035 'Q_CAP_C0805-47UF,4V,20%,X6S,CH647KMEA04':;

SECTION_NUMBER 1
 '@T6G_MB_LIB.T6G(SCH_1):PAGE388_I105@PURE_QUANTA.Q_CAP(CHIPS)':
 C_PATH='@t6g_mb_lib.t6g(sch_1):page388_i105@pure_quanta.q_cap(chips)',
 P_PATH='@t6g_mb_lib.t6g(sch_1):page279_i105@pure_quanta.q_cap(chips)',
 PATH='I105',
 DRAWING='@T6G_MB_LIB.T6G(SCH_1):PAGE388',
 TOLERANCE='20%',
 MATERIAL='X6S',
 PHYS_PAGE='279',
 XY='(-1125,4875)',
 ROT='0',
 VER='1',
 PACK_TYPE='C0805',
 LOCATION='C7035',
 CDS_LIB='pure_quanta',
 CDS_PART_NAME='Q_CAP_C0805-47UF,4V,20%,X6S,CH647KMEA04',
 VOLTAGE='4V',
 PART_NUMBER='CH647KMEA04',
 VALUE='47UF',
 PRIM_FILE='./archive_libs/logical/q_cap/chips/chips.prt';

PART_NAME
 C7036 'Q_CAP_C0805-47UF,4V,20%,X6S,CH647KMEA04':;

SECTION_NUMBER 1
 '@T6G_MB_LIB.T6G(SCH_1):PAGE388_I106@PURE_QUANTA.Q_CAP(CHIPS)':
 C_PATH='@t6g_mb_lib.t6g(sch_1):page388_i106@pure_quanta.q_cap(chips)',
 P_PATH='@t6g_mb_lib.t6g(sch_1):page279_i106@pure_quanta.q_cap(chips)',
 PATH='I106',
 DRAWING='@T6G_MB_LIB.T6G(SCH_1):PAGE388',
 TOLERANCE='20%',
 MATERIAL='X6S',
 PHYS_PAGE='279',
 XY='(-850,4875)',
 ROT='0',
 VER='1',
 PACK_TYPE='C0805',
 LOCATION='C7036',
 CDS_LIB='pure_quanta',
 CDS_PART_NAME='Q_CAP_C0805-47UF,4V,20%,X6S,CH647KMEA04',
 VOLTAGE='4V',
 PART_NUMBER='CH647KMEA04',
 VALUE='47UF',
 PRIM_FILE='./archive_libs/logical/q_cap/chips/chips.prt';

PART_NAME
 C7037 'Q_CAPP_SMLF-470UF,2.5V,20%,SPCAP,CH747LM8818':;

SECTION_NUMBER 1
 '@T6G_MB_LIB.T6G(SCH_1):PAGE454_I101@PURE_QUANTA.Q_CAPP(CHIPS)':
 C_PATH='@t6g_mb_lib.t6g(sch_1):page454_i101@pure_quanta.q_capp(chips)',
 P_PATH='@t6g_mb_lib.t6g(sch_1):page345_i101@pure_quanta.q_capp(chips)',
 PATH='I101',
 DRAWING='@T6G_MB_LIB.T6G(SCH_1):PAGE454',
 TOLERANCE='20%',
 MATERIAL='SPCAP',
 PHYS_PAGE='345',
 XY='(-1575,5000)',
 ROT='0',
 VER='1',
 PACK_TYPE='SMLF',
 LOCATION='C7037',
 CDS_LIB='pure_quanta',
 CDS_PART_NAME='Q_CAPP_SMLF-470UF,2.5V,20%,SPCAP,CH747LM8818',
 VOLTAGE='2.5V',
 PART_NUMBER='CH747LM8818',
 VALUE='470UF',
 PRIM_FILE='./archive_libs/logical/q_capp/chips/chips.prt';

PART_NAME
 C7038 'Q_CAP_C0805-47UF,4V,20%,X6S,CH647KMEA04':;

SECTION_NUMBER 1
 '@T6G_MB_LIB.T6G(SCH_1):PAGE454_I102@PURE_QUANTA.Q_CAP(CHIPS)':
 C_PATH='@t6g_mb_lib.t6g(sch_1):page454_i102@pure_quanta.q_cap(chips)',
 P_PATH='@t6g_mb_lib.t6g(sch_1):page345_i102@pure_quanta.q_cap(chips)',
 PATH='I102',
 DRAWING='@T6G_MB_LIB.T6G(SCH_1):PAGE454',
 TOLERANCE='20%',
 MATERIAL='X6S',
 PHYS_PAGE='345',
 XY='(-1275,5000)',
 ROT='0',
 VER='1',
 PACK_TYPE='C0805',
 LOCATION='C7038',
 CDS_LIB='pure_quanta',
 CDS_PART_NAME='Q_CAP_C0805-47UF,4V,20%,X6S,CH647KMEA04',
 VOLTAGE='4V',
 PART_NUMBER='CH647KMEA04',
 VALUE='47UF',
 PRIM_FILE='./archive_libs/logical/q_cap/chips/chips.prt';

PART_NAME
 C7039 'Q_CAP_C0805-47UF,4V,20%,X6S,CH647KMEA04':;

SECTION_NUMBER 1
 '@T6G_MB_LIB.T6G(SCH_1):PAGE454_I103@PURE_QUANTA.Q_CAP(CHIPS)':
 C_PATH='@t6g_mb_lib.t6g(sch_1):page454_i103@pure_quanta.q_cap(chips)',
 P_PATH='@t6g_mb_lib.t6g(sch_1):page345_i103@pure_quanta.q_cap(chips)',
 PATH='I103',
 DRAWING='@T6G_MB_LIB.T6G(SCH_1):PAGE454',
 TOLERANCE='20%',
 MATERIAL='X6S',
 PHYS_PAGE='345',
 XY='(-1025,5000)',
 ROT='0',
 VER='1',
 PACK_TYPE='C0805',
 LOCATION='C7039',
 CDS_LIB='pure_quanta',
 CDS_PART_NAME='Q_CAP_C0805-47UF,4V,20%,X6S,CH647KMEA04',
 VOLTAGE='4V',
 PART_NUMBER='CH647KMEA04',
 VALUE='47UF',
 PRIM_FILE='./archive_libs/logical/q_cap/chips/chips.prt';

PART_NAME
 C7040 'Q_CAP_C0805-47UF,4V,20%,X6S,CH647KMEA04':;

SECTION_NUMBER 1
 '@T6G_MB_LIB.T6G(SCH_1):PAGE454_I104@PURE_QUANTA.Q_CAP(CHIPS)':
 C_PATH='@t6g_mb_lib.t6g(sch_1):page454_i104@pure_quanta.q_cap(chips)',
 P_PATH='@t6g_mb_lib.t6g(sch_1):page345_i104@pure_quanta.q_cap(chips)',
 PATH='I104',
 DRAWING='@T6G_MB_LIB.T6G(SCH_1):PAGE454',
 TOLERANCE='20%',
 MATERIAL='X6S',
 PHYS_PAGE='345',
 XY='(-800,5000)',
 ROT='0',
 VER='1',
 PACK_TYPE='C0805',
 LOCATION='C7040',
 CDS_LIB='pure_quanta',
 CDS_PART_NAME='Q_CAP_C0805-47UF,4V,20%,X6S,CH647KMEA04',
 VOLTAGE='4V',
 PART_NUMBER='CH647KMEA04',
 VALUE='47UF',
 PRIM_FILE='./archive_libs/logical/q_cap/chips/chips.prt';

PART_NAME
 C7041 'Q_CAP_C0805-47UF,4V,20%,X6S,CH647KMEA04':;

SECTION_NUMBER 1
 '@T6G_MB_LIB.T6G(SCH_1):PAGE454_I105@PURE_QUANTA.Q_CAP(CHIPS)':
 C_PATH='@t6g_mb_lib.t6g(sch_1):page454_i105@pure_quanta.q_cap(chips)',
 P_PATH='@t6g_mb_lib.t6g(sch_1):page345_i105@pure_quanta.q_cap(chips)',
 PATH='I105',
 DRAWING='@T6G_MB_LIB.T6G(SCH_1):PAGE454',
 TOLERANCE='20%',
 MATERIAL='X6S',
 PHYS_PAGE='345',
 XY='(-550,5000)',
 ROT='0',
 VER='1',
 PACK_TYPE='C0805',
 LOCATION='C7041',
 CDS_LIB='pure_quanta',
 CDS_PART_NAME='Q_CAP_C0805-47UF,4V,20%,X6S,CH647KMEA04',
 VOLTAGE='4V',
 PART_NUMBER='CH647KMEA04',
 VALUE='47UF',
 PRIM_FILE='./archive_libs/logical/q_cap/chips/chips.prt';

PART_NAME
 C7500 'Q_CAP_C0201-0.1UF,10V,10%,X7S,CH4102K6E00':;

SECTION_NUMBER 1
 '@T6G_MB_LIB.T6G(SCH_1):PAGE378_I88@PURE_QUANTA.Q_CAP(CHIPS)':
 C_PATH='@t6g_mb_lib.t6g(sch_1):page378_i88@pure_quanta.q_cap(chips)',
 P_PATH='@t6g_mb_lib.t6g(sch_1):page184_i88@pure_quanta.q_cap(chips)',
 PATH='I88',
 DRAWING='@T6G_MB_LIB.T6G(SCH_1):PAGE378',
 TOLERANCE='10%',
 MATERIAL='X7S',
 PHYS_PAGE='184',
 XY='(-5650,5350)',
 ROT='2',
 VER='1',
 PACK_TYPE='C0201',
 LOCATION='C7500',
 CDS_LIB='pure_quanta',
 CDS_PART_NAME='Q_CAP_C0201-0.1UF,10V,10%,X7S,CH4102K6E00',
 VOLTAGE='10V',
 PART_NUMBER='CH4102K6E00',
 VALUE='0.1UF',
 PRIM_FILE='./archive_libs/logical/q_cap/chips/chips.prt';

PART_NAME
 C7501 'Q_CAP_C0201-0.1UF,10V,10%,X7S,CH4102K6E00':;

SECTION_NUMBER 1
 '@T6G_MB_LIB.T6G(SCH_1):PAGE399_I11@PURE_QUANTA.Q_CAP(CHIPS)':
 C_PATH='@t6g_mb_lib.t6g(sch_1):page399_i11@pure_quanta.q_cap(chips)',
 P_PATH='@t6g_mb_lib.t6g(sch_1):page322_i11@pure_quanta.q_cap(chips)',
 PATH='I11',
 DRAWING='@T6G_MB_LIB.T6G(SCH_1):PAGE399',
 TOLERANCE='10%',
 MATERIAL='X7S',
 PHYS_PAGE='322',
 XY='(-4725,5700)',
 ROT='0',
 VER='1',
 PACK_TYPE='C0201',
 LOCATION='C7501',
 CDS_LIB='pure_quanta',
 CDS_PART_NAME='Q_CAP_C0201-0.1UF,10V,10%,X7S,CH4102K6E00',
 VOLTAGE='10V',
 PART_NUMBER='CH4102K6E00',
 VALUE='0.1UF',
 PRIM_FILE='./archive_libs/logical/q_cap/chips/chips.prt';

PART_NAME
 C7502 'Q_CAP_C0201-0.1UF,10V,10%,X7S,CH4102K6E00':;

SECTION_NUMBER 1
 '@T6G_MB_LIB.T6G(SCH_1):PAGE442_I22@PURE_QUANTA.Q_CAP(CHIPS)':
 C_PATH='@t6g_mb_lib.t6g(sch_1):page442_i22@pure_quanta.q_cap(chips)',
 P_PATH='@t6g_mb_lib.t6g(sch_1):page333_i22@pure_quanta.q_cap(chips)',
 PATH='I22',
 DRAWING='@T6G_MB_LIB.T6G(SCH_1):PAGE442',
 TOLERANCE='10%',
 MATERIAL='X7S',
 PHYS_PAGE='333',
 XY='(-4600,5625)',
 ROT='0',
 VER='1',
 PACK_TYPE='C0201',
 LOCATION='C7502',
 CDS_LIB='pure_quanta',
 CDS_PART_NAME='Q_CAP_C0201-0.1UF,10V,10%,X7S,CH4102K6E00',
 VOLTAGE='10V',
 PART_NUMBER='CH4102K6E00',
 VALUE='0.1UF',
 PRIM_FILE='./archive_libs/logical/q_cap/chips/chips.prt';

PART_NAME
 C7503 'Q_CAP_C0201-0.1UF,10V,10%,X7S,CH4102K6E00':;

SECTION_NUMBER 1
 '@T6G_MB_LIB.T6G(SCH_1):PAGE453_I23@PURE_QUANTA.Q_CAP(CHIPS)':
 C_PATH='@t6g_mb_lib.t6g(sch_1):page453_i23@pure_quanta.q_cap(chips)',
 P_PATH='@t6g_mb_lib.t6g(sch_1):page344_i23@pure_quanta.q_cap(chips)',
 PATH='I23',
 DRAWING='@T6G_MB_LIB.T6G(SCH_1):PAGE453',
 TOLERANCE='10%',
 MATERIAL='X7S',
 PHYS_PAGE='344',
 XY='(-5600,6025)',
 ROT='0',
 VER='1',
 PACK_TYPE='C0201',
 LOCATION='C7503',
 CDS_LIB='pure_quanta',
 CDS_PART_NAME='Q_CAP_C0201-0.1UF,10V,10%,X7S,CH4102K6E00',
 VOLTAGE='10V',
 PART_NUMBER='CH4102K6E00',
 VALUE='0.1UF',
 PRIM_FILE='./archive_libs/logical/q_cap/chips/chips.prt';

PART_NAME
 C7504 'Q_CAP_C0201-0.1UF,10V,10%,X7S,CH4102K6E00':;

SECTION_NUMBER 1
 '@T6G_MB_LIB.T6G(SCH_1):PAGE464_I19@PURE_QUANTA.Q_CAP(CHIPS)':
 C_PATH='@t6g_mb_lib.t6g(sch_1):page464_i19@pure_quanta.q_cap(chips)',
 P_PATH='@t6g_mb_lib.t6g(sch_1):page355_i19@pure_quanta.q_cap(chips)',
 PATH='I19',
 DRAWING='@T6G_MB_LIB.T6G(SCH_1):PAGE464',
 TOLERANCE='10%',
 MATERIAL='X7S',
 PHYS_PAGE='355',
 XY='(-5000,5875)',
 ROT='0',
 VER='1',
 PACK_TYPE='C0201',
 LOCATION='C7504',
 CDS_LIB='pure_quanta',
 CDS_PART_NAME='Q_CAP_C0201-0.1UF,10V,10%,X7S,CH4102K6E00',
 VOLTAGE='10V',
 PART_NUMBER='CH4102K6E00',
 VALUE='0.1UF',
 PRIM_FILE='./archive_libs/logical/q_cap/chips/chips.prt';

PART_NAME
 C7510 'Q_CAP_C0201-0.1UF,10V,10%,X7S,CH4102K6E00':;

SECTION_NUMBER 1
 '@T6G_MB_LIB.T6G(SCH_1):PAGE387_I21@PURE_QUANTA.Q_CAP(CHIPS)':
 C_PATH='@t6g_mb_lib.t6g(sch_1):page387_i21@pure_quanta.q_cap(chips)',
 P_PATH='@t6g_mb_lib.t6g(sch_1):page278_i21@pure_quanta.q_cap(chips)',
 PATH='I21',
 DRAWING='@T6G_MB_LIB.T6G(SCH_1):PAGE387',
 TOLERANCE='10%',
 MATERIAL='X7S',
 PHYS_PAGE='278',
 XY='(-5225,5025)',
 ROT='0',
 VER='1',
 PACK_TYPE='C0201',
 LOCATION='C7510',
 CDS_LIB='pure_quanta',
 CDS_PART_NAME='Q_CAP_C0201-0.1UF,10V,10%,X7S,CH4102K6E00',
 VOLTAGE='10V',
 PART_NUMBER='CH4102K6E00',
 VALUE='0.1UF',
 PRIM_FILE='./archive_libs/logical/q_cap/chips/chips.prt';

PART_NAME
 C8000 'Q_CAP_0402-1000PF,50V,5%,EMPTY,TMP_QCH21006JB10':;

SECTION_NUMBER 1
 '@T6G_MB_LIB.T6G(SCH_1):PAGE330_I36@PURE_QUANTA.Q_CAP(CHIPS)':
 C_PATH='@t6g_mb_lib.t6g(sch_1):page330_i36@pure_quanta.q_cap(chips)',
 P_PATH='@t6g_mb_lib.t6g(sch_1):page123_i36@pure_quanta.q_cap(chips)',
 PATH='I36',
 DRAWING='@T6G_MB_LIB.T6G(SCH_1):PAGE330',
 TOLERANCE='5%',
 MATERIAL='EMPTY',
 PHYS_PAGE='123',
 XY='(-4150,8125)',
 ROT='0',
 VER='1',
 PACK_TYPE='0402',
 LOCATION='C8000',
 CDS_LIB='pure_quanta',
 CDS_PART_NAME='Q_CAP_0402-1000PF,50V,5%,EMPTY,TMP_QCH21006JB10',
 VOLTAGE='50V',
 PART_NUMBER='TMP_QCH21006JB10',
 VALUE='1000PF',
 PRIM_FILE='./archive_libs/logical/q_cap/chips/chips.prt';

PART_NAME
 C8001 'Q_CAP_0402-0.1UF,25V,10%,EMPTY,CH4104K1B00':;

SECTION_NUMBER 1
 '@T6G_MB_LIB.T6G(SCH_1):PAGE258_I68@PURE_QUANTA.Q_CAP(CHIPS)':
 C_PATH='@t6g_mb_lib.t6g(sch_1):page258_i68@pure_quanta.q_cap(chips)',
 P_PATH='@t6g_mb_lib.t6g(sch_1):page143_i68@pure_quanta.q_cap(chips)',
 PATH='I68',
 DRAWING='@T6G_MB_LIB.T6G(SCH_1):PAGE258',
 SEC_TYPE='0402',
 TOLERANCE='10%',
 MATERIAL='EMPTY',
 PHYS_PAGE='143',
 XY='(-1200,2575)',
 ROT='2',
 VER='1',
 PACK_TYPE='0402',
 LOCATION='C8001',
 SEC='1',
 CDS_LIB='pure_quanta',
 CDS_PART_NAME='Q_CAP_0402-0.1UF,25V,10%,EMPTY,CH4104K1B00',
 VOLTAGE='25V',
 PART_NUMBER='CH4104K1B00',
 VALUE='0.1UF',
 PRIM_FILE='./archive_libs/logical/q_cap/chips/chips.prt';

PART_NAME
 C8002 'Q_CAP_0402-0.1UF,25V,10%,EMPTY,CH4104K1B00':;

SECTION_NUMBER 1
 '@T6G_MB_LIB.T6G(SCH_1):PAGE258_I70@PURE_QUANTA.Q_CAP(CHIPS)':
 C_PATH='@t6g_mb_lib.t6g(sch_1):page258_i70@pure_quanta.q_cap(chips)',
 P_PATH='@t6g_mb_lib.t6g(sch_1):page143_i70@pure_quanta.q_cap(chips)',
 PATH='I70',
 DRAWING='@T6G_MB_LIB.T6G(SCH_1):PAGE258',
 TOLERANCE='10%',
 MATERIAL='EMPTY',
 PHYS_PAGE='143',
 XY='(-1200,1675)',
 ROT='2',
 VER='1',
 PACK_TYPE='0402',
 LOCATION='C8002',
 CDS_LIB='pure_quanta',
 CDS_PART_NAME='Q_CAP_0402-0.1UF,25V,10%,EMPTY,CH4104K1B00',
 VOLTAGE='25V',
 PART_NUMBER='CH4104K1B00',
 VALUE='0.1UF',
 PRIM_FILE='./archive_libs/logical/q_cap/chips/chips.prt';

PART_NAME
 C8003 'Q_CAP_0402-0.1UF,25V,10%,EMPTY,CH4104K1B00':;

SECTION_NUMBER 1
 '@T6G_MB_LIB.T6G(SCH_1):PAGE258_I72@PURE_QUANTA.Q_CAP(CHIPS)':
 C_PATH='@t6g_mb_lib.t6g(sch_1):page258_i72@pure_quanta.q_cap(chips)',
 P_PATH='@t6g_mb_lib.t6g(sch_1):page143_i72@pure_quanta.q_cap(chips)',
 PATH='I72',
 DRAWING='@T6G_MB_LIB.T6G(SCH_1):PAGE258',
 TOLERANCE='10%',
 MATERIAL='EMPTY',
 PHYS_PAGE='143',
 XY='(-1175,475)',
 ROT='2',
 VER='1',
 PACK_TYPE='0402',
 LOCATION='C8003',
 CDS_LIB='pure_quanta',
 CDS_PART_NAME='Q_CAP_0402-0.1UF,25V,10%,EMPTY,CH4104K1B00',
 VOLTAGE='25V',
 PART_NUMBER='CH4104K1B00',
 VALUE='0.1UF',
 PRIM_FILE='./archive_libs/logical/q_cap/chips/chips.prt';

PART_NAME
 C8004 'Q_CAP_0402-0.1UF,25V,10%,EMPTY,CH4104K1B00':;

SECTION_NUMBER 1
 '@T6G_MB_LIB.T6G(SCH_1):PAGE258_I74@PURE_QUANTA.Q_CAP(CHIPS)':
 C_PATH='@t6g_mb_lib.t6g(sch_1):page258_i74@pure_quanta.q_cap(chips)',
 P_PATH='@t6g_mb_lib.t6g(sch_1):page143_i74@pure_quanta.q_cap(chips)',
 PATH='I74',
 DRAWING='@T6G_MB_LIB.T6G(SCH_1):PAGE258',
 TOLERANCE='10%',
 MATERIAL='EMPTY',
 PHYS_PAGE='143',
 XY='(-1175,-425)',
 ROT='2',
 VER='1',
 PACK_TYPE='0402',
 LOCATION='C8004',
 CDS_LIB='pure_quanta',
 CDS_PART_NAME='Q_CAP_0402-0.1UF,25V,10%,EMPTY,CH4104K1B00',
 VOLTAGE='25V',
 PART_NUMBER='CH4104K1B00',
 VALUE='0.1UF',
 PRIM_FILE='./archive_libs/logical/q_cap/chips/chips.prt';

PART_NAME
 C8005 'Q_CAP_0402-0.1UF,25V,10%,X7R,CH4104K1B00':;

SECTION_NUMBER 1
 '@T6G_MB_LIB.T6G(SCH_1):PAGE84_I101@PURE_QUANTA.Q_CAP(CHIPS)':
 C_PATH='@t6g_mb_lib.t6g(sch_1):page84_i101@pure_quanta.q_cap(chips)',
 P_PATH='@t6g_mb_lib.t6g(sch_1):page85_i101@pure_quanta.q_cap(chips)',
 PATH='I101',
 DRAWING='@T6G_MB_LIB.T6G(SCH_1):PAGE84',
 TOLERANCE='10%',
 MATERIAL='X7R',
 PHYS_PAGE='85',
 XY='(-925,3625)',
 ROT='0',
 VER='1',
 PACK_TYPE='0402',
 LOCATION='C8005',
 CDS_LIB='pure_quanta',
 CDS_PART_NAME='Q_CAP_0402-0.1UF,25V,10%,X7R,CH4104K1B00',
 VOLTAGE='25V',
 PART_NUMBER='CH4104K1B00',
 VALUE='0.1UF',
 PRIM_FILE='./archive_libs/logical/q_cap/chips/chips.prt';

PART_NAME
 C8006 'Q_CAP_0402-0.1UF,25V,10%,X7R,CH4104K1B00':;

SECTION_NUMBER 1
 '@T6G_MB_LIB.T6G(SCH_1):PAGE149_I163@PURE_QUANTA.Q_CAP(CHIPS)':
 C_PATH='@t6g_mb_lib.t6g(sch_1):page149_i163@pure_quanta.q_cap(chips)',
 P_PATH='@t6g_mb_lib.t6g(sch_1):page172_i163@pure_quanta.q_cap(chips)',
 PATH='I163',
 DRAWING='@T6G_MB_LIB.T6G(SCH_1):PAGE149',
 TOLERANCE='10%',
 MATERIAL='X7R',
 PHYS_PAGE='172',
 XY='(-8075,3150)',
 ROT='2',
 VER='1',
 PACK_TYPE='0402',
 LOCATION='C8006',
 CDS_LIB='pure_quanta',
 CDS_PART_NAME='Q_CAP_0402-0.1UF,25V,10%,X7R,CH4104K1B00',
 VOLTAGE='25V',
 PART_NUMBER='CH4104K1B00',
 VALUE='0.1UF',
 PRIM_FILE='./archive_libs/logical/q_cap/chips/chips.prt';

PART_NAME
 C8007 'Q_CAP_0402-0.1UF,25V,10%,X7R,CH4104K1B00':;

SECTION_NUMBER 1
 '@T6G_MB_LIB.T6G(SCH_1):PAGE130_I4@PURE_QUANTA.Q_CAP(CHIPS)':
 C_PATH='@t6g_mb_lib.t6g(sch_1):page130_i4@pure_quanta.q_cap(chips)',
 P_PATH='@t6g_mb_lib.t6g(sch_1):page153_i4@pure_quanta.q_cap(chips)',
 PATH='I4',
 DRAWING='@T6G_MB_LIB.T6G(SCH_1):PAGE130',
 TOLERANCE='10%',
 MATERIAL='X7R',
 PHYS_PAGE='153',
 XY='(-7325,5500)',
 ROT='2',
 VER='1',
 PACK_TYPE='0402',
 LOCATION='C8007',
 CDS_LIB='pure_quanta',
 CDS_PART_NAME='Q_CAP_0402-0.1UF,25V,10%,X7R,CH4104K1B00',
 VOLTAGE='25V',
 PART_NUMBER='CH4104K1B00',
 VALUE='0.1UF',
 PRIM_FILE='./archive_libs/logical/q_cap/chips/chips.prt';

PART_NAME
 C8008 'Q_CAP_0402-0.1UF,25V,10%,X7R,CH4104K1B00':;

SECTION_NUMBER 1
 '@T6G_MB_LIB.T6G(SCH_1):PAGE340_I79@PURE_QUANTA.Q_CAP(CHIPS)':
 C_PATH='@t6g_mb_lib.t6g(sch_1):page340_i79@pure_quanta.q_cap(chips)',
 P_PATH='@t6g_mb_lib.t6g(sch_1):page136_i79@pure_quanta.q_cap(chips)',
 PATH='I79',
 DRAWING='@T6G_MB_LIB.T6G(SCH_1):PAGE340',
 TOLERANCE='10%',
 MATERIAL='X7R',
 PHYS_PAGE='136',
 XY='(-4825,4425)',
 ROT='2',
 VER='1',
 PACK_TYPE='0402',
 LOCATION='C8008',
 CDS_LIB='pure_quanta',
 CDS_PART_NAME='Q_CAP_0402-0.1UF,25V,10%,X7R,CH4104K1B00',
 VOLTAGE='25V',
 PART_NUMBER='CH4104K1B00',
 VALUE='0.1UF',
 PRIM_FILE='./archive_libs/logical/q_cap/chips/chips.prt';

PART_NAME
 C8009 'Q_CAP_0402-0.1UF,25V,10%,X7R,CH4104K1B00':;

SECTION_NUMBER 1
 '@T6G_MB_LIB.T6G(SCH_1):PAGE257_I66@PURE_QUANTA.Q_CAP(CHIPS)':
 C_PATH='@t6g_mb_lib.t6g(sch_1):page257_i66@pure_quanta.q_cap(chips)',
 P_PATH='@t6g_mb_lib.t6g(sch_1):page142_i66@pure_quanta.q_cap(chips)',
 PATH='I66',
 DRAWING='@T6G_MB_LIB.T6G(SCH_1):PAGE257',
 TOLERANCE='10%',
 MATERIAL='X7R',
 PHYS_PAGE='142',
 XY='(-5150,-1400)',
 ROT='2',
 VER='1',
 PACK_TYPE='0402',
 LOCATION='C8009',
 CDS_LIB='pure_quanta',
 CDS_PART_NAME='Q_CAP_0402-0.1UF,25V,10%,X7R,CH4104K1B00',
 VOLTAGE='25V',
 PART_NUMBER='CH4104K1B00',
 VALUE='0.1UF',
 PRIM_FILE='./archive_libs/logical/q_cap/chips/chips.prt';

PART_NAME
 C8010 'Q_CAP_0402-0.1UF,25V,10%,X7R,CH4104K1B00':
 ROOM='E1S_P3V3_BOM2';

SECTION_NUMBER 1
 '@T6G_MB_LIB.T6G(SCH_1):PAGE323_I64@PURE_QUANTA.Q_CAP(CHIPS)':
 C_PATH='@t6g_mb_lib.t6g(sch_1):page323_i64@pure_quanta.q_cap(chips)',
 P_PATH='@t6g_mb_lib.t6g(sch_1):page147_i64@pure_quanta.q_cap(chips)',
 PATH='I64',
 DRAWING='@T6G_MB_LIB.T6G(SCH_1):PAGE323',
 TOLERANCE='10%',
 MATERIAL='X7R',
 PHYS_PAGE='147',
 XY='(-4000,-2250)',
 ROT='2',
 VER='1',
 PACK_TYPE='0402',
 LOCATION='C8010',
 CDS_LIB='pure_quanta',
 CDS_PART_NAME='Q_CAP_0402-0.1UF,25V,10%,X7R,CH4104K1B00',
 VOLTAGE='25V',
 ROOM='E1S_P3V3_BOM2',
 PART_NUMBER='CH4104K1B00',
 VALUE='0.1UF',
 PRIM_FILE='./archive_libs/logical/q_cap/chips/chips.prt';

PART_NAME
 C8011 'Q_CAP_0402-0.1UF,25V,10%,EMPTY,CH4104K1B00':;

SECTION_NUMBER 1
 '@T6G_MB_LIB.T6G(SCH_1):PAGE363_I469@PURE_QUANTA.Q_CAP(CHIPS)':
 C_PATH='@t6g_mb_lib.t6g(sch_1):page363_i469@pure_quanta.q_cap(chips)',
 P_PATH='@t6g_mb_lib.t6g(sch_1):page240_i469@pure_quanta.q_cap(chips)',
 PATH='I469',
 DRAWING='@T6G_MB_LIB.T6G(SCH_1):PAGE363',
 TOLERANCE='10%',
 MATERIAL='EMPTY',
 PHYS_PAGE='240',
 XY='(200,-700)',
 ROT='0',
 VER='2',
 PACK_TYPE='0402',
 LOCATION='C8011',
 CDS_LIB='pure_quanta',
 CDS_PART_NAME='Q_CAP_0402-0.1UF,25V,10%,EMPTY,CH4104K1B00',
 VOLTAGE='25V',
 PART_NUMBER='CH4104K1B00',
 VALUE='0.1UF',
 PRIM_FILE='./archive_libs/logical/q_cap/chips/chips.prt';

PART_NAME
 C8012 'Q_CAP_C0402-1UF,25V,10%,EMPTY,CH5104KEB02':;

SECTION_NUMBER 1
 '@T6G_MB_LIB.T6G(SCH_1):PAGE365_I25@PURE_QUANTA.Q_CAP(CHIPS)':
 C_PATH='@t6g_mb_lib.t6g(sch_1):page365_i25@pure_quanta.q_cap(chips)',
 P_PATH='@t6g_mb_lib.t6g(sch_1):page242_i25@pure_quanta.q_cap(chips)',
 PATH='I25',
 DRAWING='@T6G_MB_LIB.T6G(SCH_1):PAGE365',
 TOLERANCE='10%',
 MATERIAL='EMPTY',
 PHYS_PAGE='242',
 XY='(9450,900)',
 ROT='0',
 VER='1',
 PACK_TYPE='C0402',
 LOCATION='C8012',
 CDS_LIB='pure_quanta',
 CDS_PART_NAME='Q_CAP_C0402-1UF,25V,10%,EMPTY,CH5104KEB02',
 VOLTAGE='25V',
 PART_NUMBER='CH5104KEB02',
 VALUE='1UF',
 PRIM_FILE='./archive_libs/logical/q_cap/chips/chips.prt';

PART_NAME
 C8013 'Q_CAP_0402-0.1UF,25V,10%,EMPTY,CH4104K1B00':;

SECTION_NUMBER 1
 '@T6G_MB_LIB.T6G(SCH_1):PAGE365_I23@PURE_QUANTA.Q_CAP(CHIPS)':
 C_PATH='@t6g_mb_lib.t6g(sch_1):page365_i23@pure_quanta.q_cap(chips)',
 P_PATH='@t6g_mb_lib.t6g(sch_1):page242_i23@pure_quanta.q_cap(chips)',
 PATH='I23',
 DRAWING='@T6G_MB_LIB.T6G(SCH_1):PAGE365',
 TOLERANCE='10%',
 MATERIAL='EMPTY',
 PHYS_PAGE='242',
 XY='(12400,2050)',
 ROT='0',
 VER='1',
 PACK_TYPE='0402',
 LOCATION='C8013',
 CDS_LIB='pure_quanta',
 CDS_PART_NAME='Q_CAP_0402-0.1UF,25V,10%,EMPTY,CH4104K1B00',
 VOLTAGE='25V',
 PART_NUMBER='CH4104K1B00',
 VALUE='0.1UF',
 PRIM_FILE='./archive_libs/logical/q_cap/chips/chips.prt';

PART_NAME
 C8014 'Q_CAP_C0402-100NF,50V,10%,EMPTY,CH4106K1B01':
 ROOM='HSC BOM2';

SECTION_NUMBER 1
 '@T6G_MB_LIB.T6G(SCH_1):PAGE371_I87@PURE_QUANTA.Q_CAP(CHIPS)':
 C_PATH='@t6g_mb_lib.t6g(sch_1):page371_i87@pure_quanta.q_cap(chips)',
 P_PATH='@t6g_mb_lib.t6g(sch_1):page267_i87@pure_quanta.q_cap(chips)',
 PATH='I87',
 DRAWING='@T6G_MB_LIB.T6G(SCH_1):PAGE371',
 TOLERANCE='10%',
 MATERIAL='EMPTY',
 PHYS_PAGE='267',
 XY='(-7525,3075)',
 ROT='2',
 VER='1',
 PACK_TYPE='C0402',
 LOCATION='C8014',
 CDS_LIB='pure_quanta',
 CDS_PART_NAME='Q_CAP_C0402-100NF,50V,10%,EMPTY,CH4106K1B01',
 VOLTAGE='50V',
 ROOM='HSC BOM2',
 PART_NUMBER='CH4106K1B01',
 VALUE='100NF',
 PRIM_FILE='./archive_libs/logical/q_cap/chips/chips.prt';

PART_NAME
 C8015 'Q_CAP_C0402-100NF,50V,10%,EMPTY,CH4106K1B01':
 ROOM='HSC BOM2';

SECTION_NUMBER 1
 '@T6G_MB_LIB.T6G(SCH_1):PAGE371_I89@PURE_QUANTA.Q_CAP(CHIPS)':
 C_PATH='@t6g_mb_lib.t6g(sch_1):page371_i89@pure_quanta.q_cap(chips)',
 P_PATH='@t6g_mb_lib.t6g(sch_1):page267_i89@pure_quanta.q_cap(chips)',
 PATH='I89',
 DRAWING='@T6G_MB_LIB.T6G(SCH_1):PAGE371',
 TOLERANCE='10%',
 MATERIAL='EMPTY',
 PHYS_PAGE='267',
 XY='(-7100,3075)',
 ROT='2',
 VER='1',
 PACK_TYPE='C0402',
 LOCATION='C8015',
 CDS_LIB='pure_quanta',
 CDS_PART_NAME='Q_CAP_C0402-100NF,50V,10%,EMPTY,CH4106K1B01',
 VOLTAGE='50V',
 ROOM='HSC BOM2',
 PART_NUMBER='CH4106K1B01',
 VALUE='100NF',
 PRIM_FILE='./archive_libs/logical/q_cap/chips/chips.prt';

PART_NAME
 C8016 'Q_CAP_C0402-100NF,50V,10%,EMPTY,CH4106K1B01':
 ROOM='HSC BOM2';

SECTION_NUMBER 1
 '@T6G_MB_LIB.T6G(SCH_1):PAGE371_I95@PURE_QUANTA.Q_CAP(CHIPS)':
 C_PATH='@t6g_mb_lib.t6g(sch_1):page371_i95@pure_quanta.q_cap(chips)',
 P_PATH='@t6g_mb_lib.t6g(sch_1):page267_i95@pure_quanta.q_cap(chips)',
 PATH='I95',
 DRAWING='@T6G_MB_LIB.T6G(SCH_1):PAGE371',
 TOLERANCE='10%',
 MATERIAL='EMPTY',
 PHYS_PAGE='267',
 XY='(-6500,4100)',
 ROT='2',
 VER='1',
 PACK_TYPE='C0402',
 LOCATION='C8016',
 CDS_LIB='pure_quanta',
 CDS_PART_NAME='Q_CAP_C0402-100NF,50V,10%,EMPTY,CH4106K1B01',
 VOLTAGE='50V',
 ROOM='HSC BOM2',
 PART_NUMBER='CH4106K1B01',
 VALUE='100NF',
 PRIM_FILE='./archive_libs/logical/q_cap/chips/chips.prt';

PART_NAME
 C8017 'Q_CAP_C0402-100NF,50V,10%,EMPTY,CH4106K1B01':;

SECTION_NUMBER 1
 '@T6G_MB_LIB.T6G(SCH_1):PAGE372_I59@PURE_QUANTA.Q_CAP(CHIPS)':
 C_PATH='@t6g_mb_lib.t6g(sch_1):page372_i59@pure_quanta.q_cap(chips)',
 P_PATH='@t6g_mb_lib.t6g(sch_1):page268_i59@pure_quanta.q_cap(chips)',
 PATH='I59',
 DRAWING='@T6G_MB_LIB.T6G(SCH_1):PAGE372',
 TOLERANCE='10%',
 MATERIAL='EMPTY',
 PHYS_PAGE='268',
 XY='(-4100,3025)',
 ROT='2',
 VER='1',
 PACK_TYPE='C0402',
 LOCATION='C8017',
 CDS_LIB='pure_quanta',
 CDS_PART_NAME='Q_CAP_C0402-100NF,50V,10%,EMPTY,CH4106K1B01',
 VOLTAGE='50V',
 PART_NUMBER='CH4106K1B01',
 VALUE='100NF',
 PRIM_FILE='./archive_libs/logical/q_cap/chips/chips.prt';

PART_NAME
 C8018 'Q_CAP_C0402-100NF,50V,10%,EMPTY,CH4106K1B01':;

SECTION_NUMBER 1
 '@T6G_MB_LIB.T6G(SCH_1):PAGE372_I61@PURE_QUANTA.Q_CAP(CHIPS)':
 C_PATH='@t6g_mb_lib.t6g(sch_1):page372_i61@pure_quanta.q_cap(chips)',
 P_PATH='@t6g_mb_lib.t6g(sch_1):page268_i61@pure_quanta.q_cap(chips)',
 PATH='I61',
 DRAWING='@T6G_MB_LIB.T6G(SCH_1):PAGE372',
 TOLERANCE='10%',
 MATERIAL='EMPTY',
 PHYS_PAGE='268',
 XY='(-3675,3025)',
 ROT='2',
 VER='1',
 PACK_TYPE='C0402',
 LOCATION='C8018',
 CDS_LIB='pure_quanta',
 CDS_PART_NAME='Q_CAP_C0402-100NF,50V,10%,EMPTY,CH4106K1B01',
 VOLTAGE='50V',
 PART_NUMBER='CH4106K1B01',
 VALUE='100NF',
 PRIM_FILE='./archive_libs/logical/q_cap/chips/chips.prt';

PART_NAME
 C8019 'Q_CAP_C0402-100NF,50V,10%,X7R,CH4106K1B01':;

SECTION_NUMBER 1
 '@T6G_MB_LIB.T6G(SCH_1):PAGE372_I66@PURE_QUANTA.Q_CAP(CHIPS)':
 C_PATH='@t6g_mb_lib.t6g(sch_1):page372_i66@pure_quanta.q_cap(chips)',
 P_PATH='@t6g_mb_lib.t6g(sch_1):page268_i66@pure_quanta.q_cap(chips)',
 PATH='I66',
 DRAWING='@T6G_MB_LIB.T6G(SCH_1):PAGE372',
 TOLERANCE='10%',
 MATERIAL='X7R',
 PHYS_PAGE='268',
 XY='(-3075,4050)',
 ROT='2',
 VER='1',
 PACK_TYPE='C0402',
 LOCATION='C8019',
 CDS_LIB='pure_quanta',
 CDS_PART_NAME='Q_CAP_C0402-100NF,50V,10%,X7R,CH4106K1B01',
 VOLTAGE='50V',
 PART_NUMBER='CH4106K1B01',
 VALUE='100NF',
 PRIM_FILE='./archive_libs/logical/q_cap/chips/chips.prt';

PART_NAME
 C8020 'Q_CAP_C0402-100NF,50V,10%,EMPTY,CH4106K1B01':;

SECTION_NUMBER 1
 '@T6G_MB_LIB.T6G(SCH_1):PAGE372_I79@PURE_QUANTA.Q_CAP(CHIPS)':
 C_PATH='@t6g_mb_lib.t6g(sch_1):page372_i79@pure_quanta.q_cap(chips)',
 P_PATH='@t6g_mb_lib.t6g(sch_1):page268_i79@pure_quanta.q_cap(chips)',
 PATH='I79',
 DRAWING='@T6G_MB_LIB.T6G(SCH_1):PAGE372',
 TOLERANCE='10%',
 MATERIAL='EMPTY',
 PHYS_PAGE='268',
 XY='(-3775,1325)',
 ROT='2',
 VER='1',
 PACK_TYPE='C0402',
 LOCATION='C8020',
 CDS_LIB='pure_quanta',
 CDS_PART_NAME='Q_CAP_C0402-100NF,50V,10%,EMPTY,CH4106K1B01',
 VOLTAGE='50V',
 PART_NUMBER='CH4106K1B01',
 VALUE='100NF',
 PRIM_FILE='./archive_libs/logical/q_cap/chips/chips.prt';

PART_NAME
 C8021 'Q_CAP_C0402-100NF,50V,10%,EMPTY,CH4106K1B01':;

SECTION_NUMBER 1
 '@T6G_MB_LIB.T6G(SCH_1):PAGE372_I92@PURE_QUANTA.Q_CAP(CHIPS)':
 C_PATH='@t6g_mb_lib.t6g(sch_1):page372_i92@pure_quanta.q_cap(chips)',
 P_PATH='@t6g_mb_lib.t6g(sch_1):page268_i92@pure_quanta.q_cap(chips)',
 PATH='I92',
 DRAWING='@T6G_MB_LIB.T6G(SCH_1):PAGE372',
 TOLERANCE='10%',
 MATERIAL='EMPTY',
 PHYS_PAGE='268',
 XY='(-3350,1325)',
 ROT='2',
 VER='1',
 PACK_TYPE='C0402',
 LOCATION='C8021',
 CDS_LIB='pure_quanta',
 CDS_PART_NAME='Q_CAP_C0402-100NF,50V,10%,EMPTY,CH4106K1B01',
 VOLTAGE='50V',
 PART_NUMBER='CH4106K1B01',
 VALUE='100NF',
 PRIM_FILE='./archive_libs/logical/q_cap/chips/chips.prt';

PART_NAME
 C8022 'Q_CAP_C0402-100NF,50V,10%,X7R,CH4106K1B01':;

SECTION_NUMBER 1
 '@T6G_MB_LIB.T6G(SCH_1):PAGE372_I84@PURE_QUANTA.Q_CAP(CHIPS)':
 C_PATH='@t6g_mb_lib.t6g(sch_1):page372_i84@pure_quanta.q_cap(chips)',
 P_PATH='@t6g_mb_lib.t6g(sch_1):page268_i84@pure_quanta.q_cap(chips)',
 PATH='I84',
 DRAWING='@T6G_MB_LIB.T6G(SCH_1):PAGE372',
 TOLERANCE='10%',
 MATERIAL='X7R',
 PHYS_PAGE='268',
 XY='(-2750,2350)',
 ROT='2',
 VER='1',
 PACK_TYPE='C0402',
 LOCATION='C8022',
 CDS_LIB='pure_quanta',
 CDS_PART_NAME='Q_CAP_C0402-100NF,50V,10%,X7R,CH4106K1B01',
 VOLTAGE='50V',
 PART_NUMBER='CH4106K1B01',
 VALUE='100NF',
 PRIM_FILE='./archive_libs/logical/q_cap/chips/chips.prt';

PART_NAME
 C8066 'Q_CAP_0402-1000PF,50V,5%,X7R,TMP_QCH21006JB10':;

SECTION_NUMBER 1
 '@T6G_MB_LIB.T6G(SCH_1):PAGE175_I3@PURE_QUANTA.Q_CAP(CHIPS)':
 C_PATH='@t6g_mb_lib.t6g(sch_1):page175_i3@pure_quanta.q_cap(chips)',
 P_PATH='@t6g_mb_lib.t6g(sch_1):page200_i3@pure_quanta.q_cap(chips)',
 PATH='I3',
 DRAWING='@T6G_MB_LIB.T6G(SCH_1):PAGE175',
 TOLERANCE='5%',
 MATERIAL='X7R',
 PHYS_PAGE='200',
 XY='(-8000,1425)',
 ROT='0',
 VER='1',
 PACK_TYPE='0402',
 LOCATION='C8066',
 CDS_LIB='pure_quanta',
 CDS_PART_NAME='Q_CAP_0402-1000PF,50V,5%,X7R,TMP_QCH21006JB10',
 VOLTAGE='50V',
 PART_NUMBER='TMP_QCH21006JB10',
 VALUE='1000PF',
 PRIM_FILE='./archive_libs/logical/q_cap/chips/chips.prt';

PART_NAME
 C8069 'Q_CAP_0402-1000PF,50V,5%,X7R,TMP_QCH21006JB10':;

SECTION_NUMBER 1
 '@T6G_MB_LIB.T6G(SCH_1):PAGE175_I86@PURE_QUANTA.Q_CAP(CHIPS)':
 C_PATH='@t6g_mb_lib.t6g(sch_1):page175_i86@pure_quanta.q_cap(chips)',
 P_PATH='@t6g_mb_lib.t6g(sch_1):page200_i86@pure_quanta.q_cap(chips)',
 PATH='I86',
 DRAWING='@T6G_MB_LIB.T6G(SCH_1):PAGE175',
 TOLERANCE='5%',
 MATERIAL='X7R',
 PHYS_PAGE='200',
 XY='(-5650,6025)',
 ROT='0',
 VER='2',
 PACK_TYPE='0402',
 LOCATION='C8069',
 CDS_LIB='pure_quanta',
 CDS_PART_NAME='Q_CAP_0402-1000PF,50V,5%,X7R,TMP_QCH21006JB10',
 VOLTAGE='50V',
 PART_NUMBER='TMP_QCH21006JB10',
 VALUE='1000PF',
 PRIM_FILE='./archive_libs/logical/q_cap/chips/chips.prt';

PART_NAME
 C8070 'Q_CAP_0402-1000PF,50V,5%,EMPTY,TMP_QCH21006JB10':;

SECTION_NUMBER 1
 '@T6G_MB_LIB.T6G(SCH_1):PAGE175_I91@PURE_QUANTA.Q_CAP(CHIPS)':
 C_PATH='@t6g_mb_lib.t6g(sch_1):page175_i91@pure_quanta.q_cap(chips)',
 P_PATH='@t6g_mb_lib.t6g(sch_1):page200_i91@pure_quanta.q_cap(chips)',
 PATH='I91',
 DRAWING='@T6G_MB_LIB.T6G(SCH_1):PAGE175',
 TOLERANCE='5%',
 MATERIAL='EMPTY',
 PHYS_PAGE='200',
 XY='(-5625,6450)',
 ROT='0',
 VER='2',
 PACK_TYPE='0402',
 LOCATION='C8070',
 CDS_LIB='pure_quanta',
 CDS_PART_NAME='Q_CAP_0402-1000PF,50V,5%,EMPTY,TMP_QCH21006JB10',
 VOLTAGE='50V',
 PART_NUMBER='TMP_QCH21006JB10',
 VALUE='1000PF',
 PRIM_FILE='./archive_libs/logical/q_cap/chips/chips.prt';

PART_NAME
 C8072 'Q_CAP_0402-1000PF,50V,5%,EMPTY,TMP_QCH21006JB10':;

SECTION_NUMBER 1
 '@T6G_MB_LIB.T6G(SCH_1):PAGE175_I55@PURE_QUANTA.Q_CAP(CHIPS)':
 C_PATH='@t6g_mb_lib.t6g(sch_1):page175_i55@pure_quanta.q_cap(chips)',
 P_PATH='@t6g_mb_lib.t6g(sch_1):page200_i55@pure_quanta.q_cap(chips)',
 PATH='I55',
 DRAWING='@T6G_MB_LIB.T6G(SCH_1):PAGE175',
 TOLERANCE='5%',
 MATERIAL='EMPTY',
 PHYS_PAGE='200',
 XY='(-5575,1200)',
 ROT='0',
 VER='2',
 PACK_TYPE='0402',
 LOCATION='C8072',
 CDS_LIB='pure_quanta',
 CDS_PART_NAME='Q_CAP_0402-1000PF,50V,5%,EMPTY,TMP_QCH21006JB10',
 VOLTAGE='50V',
 PART_NUMBER='TMP_QCH21006JB10',
 VALUE='1000PF',
 PRIM_FILE='./archive_libs/logical/q_cap/chips/chips.prt';

PART_NAME
 C8246 'Q_CAP_0402-1000PF,50V,5%,EMPTY,TMP_QCH21006JB10':;

SECTION_NUMBER 1
 '@T6G_MB_LIB.T6G(SCH_1):PAGE185_I52@PURE_QUANTA.Q_CAP(CHIPS)':
 C_PATH='@t6g_mb_lib.t6g(sch_1):page185_i52@pure_quanta.q_cap(chips)',
 P_PATH='@t6g_mb_lib.t6g(sch_1):page210_i52@pure_quanta.q_cap(chips)',
 PATH='I52',
 DRAWING='@T6G_MB_LIB.T6G(SCH_1):PAGE185',
 TOLERANCE='5%',
 MATERIAL='EMPTY',
 PHYS_PAGE='210',
 XY='(-2425,3025)',
 ROT='0',
 VER='2',
 PACK_TYPE='0402',
 LOCATION='C8246',
 CDS_LIB='pure_quanta',
 CDS_PART_NAME='Q_CAP_0402-1000PF,50V,5%,EMPTY,TMP_QCH21006JB10',
 VOLTAGE='50V',
 PART_NUMBER='TMP_QCH21006JB10',
 VALUE='1000PF',
 PRIM_FILE='./archive_libs/logical/q_cap/chips/chips.prt';

PART_NAME
 C8356 'Q_CAP_0402-1000PF,50V,5%,X7R,TMP_QCH21006JB10':;

SECTION_NUMBER 1
 '@T6G_MB_LIB.T6G(SCH_1):PAGE192_I3@PURE_QUANTA.Q_CAP(CHIPS)':
 C_PATH='@t6g_mb_lib.t6g(sch_1):page192_i3@pure_quanta.q_cap(chips)',
 P_PATH='@t6g_mb_lib.t6g(sch_1):page217_i3@pure_quanta.q_cap(chips)',
 PATH='I3',
 DRAWING='@T6G_MB_LIB.T6G(SCH_1):PAGE192',
 TOLERANCE='5%',
 MATERIAL='X7R',
 PHYS_PAGE='217',
 XY='(-4325,2400)',
 ROT='0',
 VER='1',
 PACK_TYPE='0402',
 LOCATION='C8356',
 CDS_LIB='pure_quanta',
 CDS_PART_NAME='Q_CAP_0402-1000PF,50V,5%,X7R,TMP_QCH21006JB10',
 VOLTAGE='50V',
 PART_NUMBER='TMP_QCH21006JB10',
 VALUE='1000PF',
 PRIM_FILE='./archive_libs/logical/q_cap/chips/chips.prt';

PART_NAME
 C8359 'Q_CAP_0402-1000PF,50V,5%,X7R,TMP_QCH21006JB10':;

SECTION_NUMBER 1
 '@T6G_MB_LIB.T6G(SCH_1):PAGE192_I85@PURE_QUANTA.Q_CAP(CHIPS)':
 C_PATH='@t6g_mb_lib.t6g(sch_1):page192_i85@pure_quanta.q_cap(chips)',
 P_PATH='@t6g_mb_lib.t6g(sch_1):page217_i85@pure_quanta.q_cap(chips)',
 PATH='I85',
 DRAWING='@T6G_MB_LIB.T6G(SCH_1):PAGE192',
 TOLERANCE='5%',
 MATERIAL='X7R',
 PHYS_PAGE='217',
 XY='(-2050,6950)',
 ROT='0',
 VER='2',
 PACK_TYPE='0402',
 LOCATION='C8359',
 CDS_LIB='pure_quanta',
 CDS_PART_NAME='Q_CAP_0402-1000PF,50V,5%,X7R,TMP_QCH21006JB10',
 VOLTAGE='50V',
 PART_NUMBER='TMP_QCH21006JB10',
 VALUE='1000PF',
 PRIM_FILE='./archive_libs/logical/q_cap/chips/chips.prt';

PART_NAME
 C8360 'Q_CAP_0402-1000PF,50V,5%,EMPTY,TMP_QCH21006JB10':;

SECTION_NUMBER 1
 '@T6G_MB_LIB.T6G(SCH_1):PAGE192_I90@PURE_QUANTA.Q_CAP(CHIPS)':
 C_PATH='@t6g_mb_lib.t6g(sch_1):page192_i90@pure_quanta.q_cap(chips)',
 P_PATH='@t6g_mb_lib.t6g(sch_1):page217_i90@pure_quanta.q_cap(chips)',
 PATH='I90',
 DRAWING='@T6G_MB_LIB.T6G(SCH_1):PAGE192',
 TOLERANCE='5%',
 MATERIAL='EMPTY',
 PHYS_PAGE='217',
 XY='(-2025,7375)',
 ROT='0',
 VER='2',
 PACK_TYPE='0402',
 LOCATION='C8360',
 CDS_LIB='pure_quanta',
 CDS_PART_NAME='Q_CAP_0402-1000PF,50V,5%,EMPTY,TMP_QCH21006JB10',
 VOLTAGE='50V',
 PART_NUMBER='TMP_QCH21006JB10',
 VALUE='1000PF',
 PRIM_FILE='./archive_libs/logical/q_cap/chips/chips.prt';

PART_NAME
 C8362 'Q_CAP_0402-1000PF,50V,5%,EMPTY,TMP_QCH21006JB10':;

SECTION_NUMBER 1
 '@T6G_MB_LIB.T6G(SCH_1):PAGE192_I52@PURE_QUANTA.Q_CAP(CHIPS)':
 C_PATH='@t6g_mb_lib.t6g(sch_1):page192_i52@pure_quanta.q_cap(chips)',
 P_PATH='@t6g_mb_lib.t6g(sch_1):page217_i52@pure_quanta.q_cap(chips)',
 PATH='I52',
 DRAWING='@T6G_MB_LIB.T6G(SCH_1):PAGE192',
 TOLERANCE='5%',
 MATERIAL='EMPTY',
 PHYS_PAGE='217',
 XY='(-1975,2125)',
 ROT='0',
 VER='2',
 PACK_TYPE='0402',
 LOCATION='C8362',
 CDS_LIB='pure_quanta',
 CDS_PART_NAME='Q_CAP_0402-1000PF,50V,5%,EMPTY,TMP_QCH21006JB10',
 VOLTAGE='50V',
 PART_NUMBER='TMP_QCH21006JB10',
 VALUE='1000PF',
 PRIM_FILE='./archive_libs/logical/q_cap/chips/chips.prt';

PART_NAME
 C8641 'Q_CAP_0402-1000PF,50V,5%,EMPTY,TMP_QCH21006JB10':;

SECTION_NUMBER 1
 '@T6G_MB_LIB.T6G(SCH_1):PAGE199_I46@PURE_QUANTA.Q_CAP(CHIPS)':
 C_PATH='@t6g_mb_lib.t6g(sch_1):page199_i46@pure_quanta.q_cap(chips)',
 P_PATH='@t6g_mb_lib.t6g(sch_1):page224_i46@pure_quanta.q_cap(chips)',
 PATH='I46',
 DRAWING='@T6G_MB_LIB.T6G(SCH_1):PAGE199',
 TOLERANCE='5%',
 MATERIAL='EMPTY',
 PHYS_PAGE='224',
 XY='(-5325,6400)',
 ROT='0',
 VER='2',
 PACK_TYPE='0402',
 LOCATION='C8641',
 CDS_LIB='pure_quanta',
 CDS_PART_NAME='Q_CAP_0402-1000PF,50V,5%,EMPTY,TMP_QCH21006JB10',
 VOLTAGE='50V',
 PART_NUMBER='TMP_QCH21006JB10',
 VALUE='1000PF',
 PRIM_FILE='./archive_libs/logical/q_cap/chips/chips.prt';

PART_NAME
 C9000 'Q_CAP_0402-1000PF,50V,5%,EMPTY,TMP_QCH21006JB10':;

SECTION_NUMBER 1
 '@T6G_MB_LIB.T6G(SCH_1):PAGE330_I45@PURE_QUANTA.Q_CAP(CHIPS)':
 C_PATH='@t6g_mb_lib.t6g(sch_1):page330_i45@pure_quanta.q_cap(chips)',
 P_PATH='@t6g_mb_lib.t6g(sch_1):page123_i45@pure_quanta.q_cap(chips)',
 PATH='I45',
 DRAWING='@T6G_MB_LIB.T6G(SCH_1):PAGE330',
 TOLERANCE='5%',
 MATERIAL='EMPTY',
 PHYS_PAGE='123',
 XY='(-4000,6350)',
 ROT='0',
 VER='1',
 PACK_TYPE='0402',
 LOCATION='C9000',
 CDS_LIB='pure_quanta',
 CDS_PART_NAME='Q_CAP_0402-1000PF,50V,5%,EMPTY,TMP_QCH21006JB10',
 VOLTAGE='50V',
 PART_NUMBER='TMP_QCH21006JB10',
 VALUE='1000PF',
 PRIM_FILE='./archive_libs/logical/q_cap/chips/chips.prt';

PART_NAME
 C9001 'Q_CAP_0402-1000PF,50V,5%,EMPTY,TMP_QCH21006JB10':;

SECTION_NUMBER 1
 '@T6G_MB_LIB.T6G(SCH_1):PAGE330_I42@PURE_QUANTA.Q_CAP(CHIPS)':
 C_PATH='@t6g_mb_lib.t6g(sch_1):page330_i42@pure_quanta.q_cap(chips)',
 P_PATH='@t6g_mb_lib.t6g(sch_1):page123_i42@pure_quanta.q_cap(chips)',
 PATH='I42',
 DRAWING='@T6G_MB_LIB.T6G(SCH_1):PAGE330',
 TOLERANCE='5%',
 MATERIAL='EMPTY',
 PHYS_PAGE='123',
 XY='(-3950,4550)',
 ROT='0',
 VER='1',
 PACK_TYPE='0402',
 LOCATION='C9001',
 CDS_LIB='pure_quanta',
 CDS_PART_NAME='Q_CAP_0402-1000PF,50V,5%,EMPTY,TMP_QCH21006JB10',
 VOLTAGE='50V',
 PART_NUMBER='TMP_QCH21006JB10',
 VALUE='1000PF',
 PRIM_FILE='./archive_libs/logical/q_cap/chips/chips.prt';

PART_NAME
 C9002 'Q_CAP_0402-1000PF,50V,5%,EMPTY,TMP_QCH21006JB10':;

SECTION_NUMBER 1
 '@T6G_MB_LIB.T6G(SCH_1):PAGE330_I71@PURE_QUANTA.Q_CAP(CHIPS)':
 C_PATH='@t6g_mb_lib.t6g(sch_1):page330_i71@pure_quanta.q_cap(chips)',
 P_PATH='@t6g_mb_lib.t6g(sch_1):page123_i71@pure_quanta.q_cap(chips)',
 PATH='I71',
 DRAWING='@T6G_MB_LIB.T6G(SCH_1):PAGE330',
 TOLERANCE='5%',
 MATERIAL='EMPTY',
 PHYS_PAGE='123',
 XY='(775,8125)',
 ROT='0',
 VER='1',
 PACK_TYPE='0402',
 LOCATION='C9002',
 CDS_LIB='pure_quanta',
 CDS_PART_NAME='Q_CAP_0402-1000PF,50V,5%,EMPTY,TMP_QCH21006JB10',
 VOLTAGE='50V',
 PART_NUMBER='TMP_QCH21006JB10',
 VALUE='1000PF',
 PRIM_FILE='./archive_libs/logical/q_cap/chips/chips.prt';

PART_NAME
 C9003 'Q_CAP_C0402-1UF,25V,10%,EMPTY,CH5104KEB02':
 ROOM='HSC BOM2';

SECTION_NUMBER 1
 '@T6G_MB_LIB.T6G(SCH_1):PAGE371_I110@PURE_QUANTA.Q_CAP(CHIPS)':
 C_PATH='@t6g_mb_lib.t6g(sch_1):page371_i110@pure_quanta.q_cap(chips)',
 P_PATH='@t6g_mb_lib.t6g(sch_1):page267_i110@pure_quanta.q_cap(chips)',
 PATH='I110',
 DRAWING='@T6G_MB_LIB.T6G(SCH_1):PAGE371',
 TOLERANCE='10%',
 MATERIAL='EMPTY',
 PHYS_PAGE='267',
 XY='(-6375,6250)',
 ROT='2',
 VER='1',
 PACK_TYPE='C0402',
 LOCATION='C9003',
 CDS_LIB='pure_quanta',
 CDS_PART_NAME='Q_CAP_C0402-1UF,25V,10%,EMPTY,CH5104KEB02',
 VOLTAGE='25V',
 ROOM='HSC BOM2',
 PART_NUMBER='CH5104KEB02',
 VALUE='1UF',
 PRIM_FILE='./archive_libs/logical/q_cap/chips/chips.prt';

PART_NAME
 C9004 'Q_CAP_C0402-1UF,25V,10%,EMPTY,CH5104KEB02':;

SECTION_NUMBER 1
 '@T6G_MB_LIB.T6G(SCH_1):PAGE372_I99@PURE_QUANTA.Q_CAP(CHIPS)':
 C_PATH='@t6g_mb_lib.t6g(sch_1):page372_i99@pure_quanta.q_cap(chips)',
 P_PATH='@t6g_mb_lib.t6g(sch_1):page268_i99@pure_quanta.q_cap(chips)',
 PATH='I99',
 DRAWING='@T6G_MB_LIB.T6G(SCH_1):PAGE372',
 TOLERANCE='10%',
 MATERIAL='EMPTY',
 PHYS_PAGE='268',
 XY='(-4650,5525)',
 ROT='2',
 VER='1',
 PACK_TYPE='C0402',
 LOCATION='C9004',
 CDS_LIB='pure_quanta',
 CDS_PART_NAME='Q_CAP_C0402-1UF,25V,10%,EMPTY,CH5104KEB02',
 VOLTAGE='25V',
 PART_NUMBER='CH5104KEB02',
 VALUE='1UF',
 PRIM_FILE='./archive_libs/logical/q_cap/chips/chips.prt';

PART_NAME
 C9005 'Q_CAP_0402-0.1UF,25V,10%,X7R,CH4104K1B00':;

SECTION_NUMBER 1
 '@T6G_MB_LIB.T6G(SCH_1):PAGE84_I116@PURE_QUANTA.Q_CAP(CHIPS)':
 C_PATH='@t6g_mb_lib.t6g(sch_1):page84_i116@pure_quanta.q_cap(chips)',
 P_PATH='@t6g_mb_lib.t6g(sch_1):page85_i116@pure_quanta.q_cap(chips)',
 PATH='I116',
 DRAWING='@T6G_MB_LIB.T6G(SCH_1):PAGE84',
 TOLERANCE='10%',
 MATERIAL='X7R',
 PHYS_PAGE='85',
 XY='(-5550,4150)',
 ROT='0',
 VER='1',
 PACK_TYPE='0402',
 LOCATION='C9005',
 CDS_LIB='pure_quanta',
 CDS_PART_NAME='Q_CAP_0402-0.1UF,25V,10%,X7R,CH4104K1B00',
 VOLTAGE='25V',
 PART_NUMBER='CH4104K1B00',
 VALUE='0.1UF',
 PRIM_FILE='./archive_libs/logical/q_cap/chips/chips.prt';

PART_NAME
 C9007 'Q_CAP_0402-0.1UF,25V,10%,X7R,CH4104K1B00':;

SECTION_NUMBER 1
 '@T6G_MB_LIB.T6G(SCH_1):PAGE340_I27@PURE_QUANTA.Q_CAP(CHIPS)':
 C_PATH='@t6g_mb_lib.t6g(sch_1):page340_i27@pure_quanta.q_cap(chips)',
 P_PATH='@t6g_mb_lib.t6g(sch_1):page136_i27@pure_quanta.q_cap(chips)',
 PATH='I27',
 DRAWING='@T6G_MB_LIB.T6G(SCH_1):PAGE340',
 TOLERANCE='10%',
 MATERIAL='X7R',
 PHYS_PAGE='136',
 XY='(1050,6875)',
 ROT='0',
 VER='1',
 PACK_TYPE='0402',
 LOCATION='C9007',
 CDS_LIB='pure_quanta',
 CDS_PART_NAME='Q_CAP_0402-0.1UF,25V,10%,X7R,CH4104K1B00',
 VOLTAGE='25V',
 PART_NUMBER='CH4104K1B00',
 VALUE='0.1UF',
 PRIM_FILE='./archive_libs/logical/q_cap/chips/chips.prt';

PART_NAME
 C9008 'Q_CAP_0402-0.1UF,25V,10%,X7R,CH4104K1B00':;

SECTION_NUMBER 1
 '@T6G_MB_LIB.T6G(SCH_1):PAGE340_I75@PURE_QUANTA.Q_CAP(CHIPS)':
 C_PATH='@t6g_mb_lib.t6g(sch_1):page340_i75@pure_quanta.q_cap(chips)',
 P_PATH='@t6g_mb_lib.t6g(sch_1):page136_i75@pure_quanta.q_cap(chips)',
 PATH='I75',
 DRAWING='@T6G_MB_LIB.T6G(SCH_1):PAGE340',
 TOLERANCE='10%',
 MATERIAL='X7R',
 PHYS_PAGE='136',
 XY='(-50,5700)',
 ROT='2',
 VER='1',
 PACK_TYPE='0402',
 LOCATION='C9008',
 CDS_LIB='pure_quanta',
 CDS_PART_NAME='Q_CAP_0402-0.1UF,25V,10%,X7R,CH4104K1B00',
 VOLTAGE='25V',
 PART_NUMBER='CH4104K1B00',
 VALUE='0.1UF',
 PRIM_FILE='./archive_libs/logical/q_cap/chips/chips.prt';

PART_NAME
 C9050 'Q_CAP_0402-0.1UF,25V,10%,X7R,CH4104K1B00':;

SECTION_NUMBER 1
 '@T6G_MB_LIB.T6G(SCH_1):PAGE340_I94@PURE_QUANTA.Q_CAP(CHIPS)':
 C_PATH='@t6g_mb_lib.t6g(sch_1):page340_i94@pure_quanta.q_cap(chips)',
 P_PATH='@t6g_mb_lib.t6g(sch_1):page136_i94@pure_quanta.q_cap(chips)',
 PATH='I94',
 DRAWING='@T6G_MB_LIB.T6G(SCH_1):PAGE340',
 TOLERANCE='10%',
 MATERIAL='X7R',
 PHYS_PAGE='136',
 XY='(-3475,6575)',
 ROT='0',
 VER='1',
 PACK_TYPE='0402',
 LOCATION='C9050',
 CDS_LIB='pure_quanta',
 CDS_PART_NAME='Q_CAP_0402-0.1UF,25V,10%,X7R,CH4104K1B00',
 VOLTAGE='25V',
 PART_NUMBER='CH4104K1B00',
 VALUE='0.1UF',
 PRIM_FILE='./archive_libs/logical/q_cap/chips/chips.prt';

PART_NAME
 C9051 'Q_CAP_0402-0.1UF,25V,10%,X7R,CH4104K1B00':;

SECTION_NUMBER 1
 '@T6G_MB_LIB.T6G(SCH_1):PAGE257_I81@PURE_QUANTA.Q_CAP(CHIPS)':
 C_PATH='@t6g_mb_lib.t6g(sch_1):page257_i81@pure_quanta.q_cap(chips)',
 P_PATH='@t6g_mb_lib.t6g(sch_1):page142_i81@pure_quanta.q_cap(chips)',
 PATH='I81',
 DRAWING='@T6G_MB_LIB.T6G(SCH_1):PAGE257',
 TOLERANCE='10%',
 MATERIAL='X7R',
 PHYS_PAGE='142',
 XY='(-3850,975)',
 ROT='0',
 VER='1',
 PACK_TYPE='0402',
 LOCATION='C9051',
 CDS_LIB='pure_quanta',
 CDS_PART_NAME='Q_CAP_0402-0.1UF,25V,10%,X7R,CH4104K1B00',
 VOLTAGE='25V',
 PART_NUMBER='CH4104K1B00',
 VALUE='0.1UF',
 PRIM_FILE='./archive_libs/logical/q_cap/chips/chips.prt';

PART_NAME
 C9102 'Q_CAP_DIFFBUS_C0201-DIFF BUS_0.22UF,6.3V,20%,X6S,SA':;

SECTION_NUMBER 1
 '@T6G_MB_LIB.T6G(SCH_1):PAGE355_I138@PURE_QUANTA.Q_CAP_DIFFBUS(CHIPS)':
 C_PATH='@t6g_mb_lib.t6g(sch_1):page355_i138@pure_quanta.q_cap_diffbus(chips)',
 P_PATH='@t6g_mb_lib.t6g(sch_1):page67_i138@pure_quanta.q_cap_diffbus(chips)',
 PATH='I138',
 DRAWING='@T6G_MB_LIB.T6G(SCH_1):PAGE355',
 PIN_NAMES_ROTATE='TRUE',
 TOLERANCE='20%',
 MATERIAL='X6S',
 PHYS_PAGE='67',
 XY='(3150,-175)',
 ROT='2',
 VER='2',
 PACK_TYPE='C0201',
 LOCATION='C9102',
 CDS_LIB='pure_quanta',
 CDS_PART_NAME='Q_CAP_DIFFBUS_C0201-DIFF BUS_0.22UF,6.3V,20%,X6S,SA',
 VOLTAGE='6.3V',
 PART_NUMBER='SP_CH4221MEE01',
 VALUE='DIFF BUS_0.22UF',
 PRIM_FILE='./archive_libs/logical/q_cap_diffbus/chips/chips.prt';

PART_NAME
 C9103 'Q_CAP_DIFFBUS_C0201-DIFF BUS_0.22UF,6.3V,20%,X6S,SA':;

SECTION_NUMBER 1
 '@T6G_MB_LIB.T6G(SCH_1):PAGE355_I137@PURE_QUANTA.Q_CAP_DIFFBUS(CHIPS)':
 C_PATH='@t6g_mb_lib.t6g(sch_1):page355_i137@pure_quanta.q_cap_diffbus(chips)',
 P_PATH='@t6g_mb_lib.t6g(sch_1):page67_i137@pure_quanta.q_cap_diffbus(chips)',
 PATH='I137',
 DRAWING='@T6G_MB_LIB.T6G(SCH_1):PAGE355',
 PIN_NAMES_ROTATE='TRUE',
 TOLERANCE='20%',
 MATERIAL='X6S',
 PHYS_PAGE='67',
 XY='(3150,-225)',
 ROT='2',
 VER='2',
 PACK_TYPE='C0201',
 LOCATION='C9103',
 CDS_LIB='pure_quanta',
 CDS_PART_NAME='Q_CAP_DIFFBUS_C0201-DIFF BUS_0.22UF,6.3V,20%,X6S,SA',
 VOLTAGE='6.3V',
 PART_NUMBER='SP_CH4221MEE01',
 VALUE='DIFF BUS_0.22UF',
 PRIM_FILE='./archive_libs/logical/q_cap_diffbus/chips/chips.prt';

PART_NAME
 C9104 'Q_CAP_DIFFBUS_C0201-DIFF BUS_0.22UF,6.3V,20%,X6S,SA':;

SECTION_NUMBER 1
 '@T6G_MB_LIB.T6G(SCH_1):PAGE355_I162@PURE_QUANTA.Q_CAP_DIFFBUS(CHIPS)':
 C_PATH='@t6g_mb_lib.t6g(sch_1):page355_i162@pure_quanta.q_cap_diffbus(chips)',
 P_PATH='@t6g_mb_lib.t6g(sch_1):page67_i162@pure_quanta.q_cap_diffbus(chips)',
 PATH='I162',
 DRAWING='@T6G_MB_LIB.T6G(SCH_1):PAGE355',
 PIN_NAMES_ROTATE='TRUE',
 TOLERANCE='20%',
 MATERIAL='X6S',
 PHYS_PAGE='67',
 XY='(3150,25)',
 ROT='2',
 VER='2',
 PACK_TYPE='C0201',
 LOCATION='C9104',
 CDS_LIB='pure_quanta',
 CDS_PART_NAME='Q_CAP_DIFFBUS_C0201-DIFF BUS_0.22UF,6.3V,20%,X6S,SA',
 VOLTAGE='6.3V',
 PART_NUMBER='SP_CH4221MEE01',
 VALUE='DIFF BUS_0.22UF',
 PRIM_FILE='./archive_libs/logical/q_cap_diffbus/chips/chips.prt';

PART_NAME
 C9105 'Q_CAP_DIFFBUS_C0201-DIFF BUS_0.22UF,6.3V,20%,X6S,SA':;

SECTION_NUMBER 1
 '@T6G_MB_LIB.T6G(SCH_1):PAGE355_I161@PURE_QUANTA.Q_CAP_DIFFBUS(CHIPS)':
 C_PATH='@t6g_mb_lib.t6g(sch_1):page355_i161@pure_quanta.q_cap_diffbus(chips)',
 P_PATH='@t6g_mb_lib.t6g(sch_1):page67_i161@pure_quanta.q_cap_diffbus(chips)',
 PATH='I161',
 DRAWING='@T6G_MB_LIB.T6G(SCH_1):PAGE355',
 PIN_NAMES_ROTATE='TRUE',
 TOLERANCE='20%',
 MATERIAL='X6S',
 PHYS_PAGE='67',
 XY='(3150,-25)',
 ROT='2',
 VER='2',
 PACK_TYPE='C0201',
 LOCATION='C9105',
 CDS_LIB='pure_quanta',
 CDS_PART_NAME='Q_CAP_DIFFBUS_C0201-DIFF BUS_0.22UF,6.3V,20%,X6S,SA',
 VOLTAGE='6.3V',
 PART_NUMBER='SP_CH4221MEE01',
 VALUE='DIFF BUS_0.22UF',
 PRIM_FILE='./archive_libs/logical/q_cap_diffbus/chips/chips.prt';

PART_NAME
 C9226 'Q_CAP_C0402-0.22UF,25V,10%,X7R,CH4224K1B01':;

SECTION_NUMBER 1
 '@T6G_MB_LIB.T6G(SCH_1):PAGE273_I38@PURE_QUANTA.Q_CAP(CHIPS)':
 C_PATH='@t6g_mb_lib.t6g(sch_1):page273_i38@pure_quanta.q_cap(chips)',
 P_PATH='@t6g_mb_lib.t6g(sch_1):page188_i38@pure_quanta.q_cap(chips)',
 PATH='I38',
 DRAWING='@T6G_MB_LIB.T6G(SCH_1):PAGE273',
 TOLERANCE='10%',
 MATERIAL='X7R',
 PHYS_PAGE='188',
 XY='(-3950,6325)',
 ROT='0',
 VER='1',
 PACK_TYPE='C0402',
 LOCATION='C9226',
 CDS_LIB='pure_quanta',
 CDS_PART_NAME='Q_CAP_C0402-0.22UF,25V,10%,X7R,CH4224K1B01',
 VOLTAGE='25V',
 PART_NUMBER='CH4224K1B01',
 VALUE='0.22UF',
 PRIM_FILE='./archive_libs/logical/q_cap/chips/chips.prt';

PART_NAME
 C9922 'Q_CAP_C0603-22UF,6.3V,20%,X6S,CH6221ME900':;

SECTION_NUMBER 1
 '@T6G_MB_LIB.T6G(SCH_1):PAGE345_I79@PURE_QUANTA.Q_CAP(CHIPS)':
 C_PATH='@t6g_mb_lib.t6g(sch_1):page345_i79@pure_quanta.q_cap(chips)',
 P_PATH='@t6g_mb_lib.t6g(sch_1):page144_i79@pure_quanta.q_cap(chips)',
 PATH='I79',
 DRAWING='@T6G_MB_LIB.T6G(SCH_1):PAGE345',
 TOLERANCE='20%',
 MATERIAL='X6S',
 PHYS_PAGE='144',
 XY='(12025,4200)',
 ROT='0',
 VER='1',
 PACK_TYPE='C0603',
 LOCATION='C9922',
 CDS_LIB='pure_quanta',
 CDS_PART_NAME='Q_CAP_C0603-22UF,6.3V,20%,X6S,CH6221ME900',
 VOLTAGE='6.3V',
 PART_NUMBER='CH6221ME900',
 VALUE='22UF',
 PRIM_FILE='./archive_libs/logical/q_cap/chips/chips.prt';

PART_NAME
 C10179 'Q_CAP_C0402-22UF,4V,20%,X6S,CH622KMEB02':;

SECTION_NUMBER 1
 '@T6G_MB_LIB.T6G(SCH_1):PAGE68_I17@PURE_QUANTA.Q_CAP(CHIPS)':
 C_PATH='@t6g_mb_lib.t6g(sch_1):page68_i17@pure_quanta.q_cap(chips)',
 P_PATH='@t6g_mb_lib.t6g(sch_1):page69_i17@pure_quanta.q_cap(chips)',
 PATH='I17',
 DRAWING='@T6G_MB_LIB.T6G(SCH_1):PAGE68',
 TOLERANCE='20%',
 MATERIAL='X6S',
 PHYS_PAGE='69',
 XY='(-7650,2075)',
 ROT='0',
 VER='1',
 PACK_TYPE='C0402',
 LOCATION='C10179',
 CDS_LIB='pure_quanta',
 CDS_PART_NAME='Q_CAP_C0402-22UF,4V,20%,X6S,CH622KMEB02',
 VOLTAGE='4V',
 PART_NUMBER='CH622KMEB02',
 VALUE='22UF',
 PRIM_FILE='./archive_libs/logical/q_cap/chips/chips.prt';

PART_NAME
 D1 'BAT547F-BAT547F,SMLF,IC,BC0BAT54Z53':;

SECTION_NUMBER 1
 '@T6G_MB_LIB.T6G(SCH_1):PAGE273_I27@PURE_QUANTA.BAT547F(CHIPS)':
 C_PATH='@t6g_mb_lib.t6g(sch_1):page273_i27@pure_quanta.bat547f(chips)',
 P_PATH='@t6g_mb_lib.t6g(sch_1):page188_i27@pure_quanta.bat547f(chips)',
 PATH='I27',
 DRAWING='@T6G_MB_LIB.T6G(SCH_1):PAGE273',
 PIN_NAMES_ROTATE='TRUE',
 BOM_COST='VR_SYSTEM ',
 PART_TYPE='SMLF',
 MATERIAL='IC',
 PHYS_PAGE='188',
 XY='(-6775,3625)',
 ROT='0',
 VER='1',
 LOCATION='D1',
 CDS_LIB='pure_quanta',
 CDS_PART_NAME='BAT547F-BAT547F,SMLF,IC,BC0BAT54Z53',
 PART_NUMBER='BC0BAT54Z53',
 VALUE='BAT547F',
 PRIM_FILE='./archive_libs/logical/bat547f/chips/chips.prt';

PART_NAME
 D5 'Q_LED_SMLF-LED_BLUE,LTST-C281TBKT-5A,IC,BEBL0172Z00':;

SECTION_NUMBER 1
 '@T6G_MB_LIB.T6G(SCH_1):PAGE143_I8@PURE_QUANTA.Q_LED(CHIPS)':
 C_PATH='@t6g_mb_lib.t6g(sch_1):page143_i8@pure_quanta.q_led(chips)',
 P_PATH='@t6g_mb_lib.t6g(sch_1):page166_i8@pure_quanta.q_led(chips)',
 PATH='I8',
 DRAWING='@T6G_MB_LIB.T6G(SCH_1):PAGE143',
 COLOR='LED_BLUE',
 MANUF_PN='LTST-C281TBKT-5A',
 MATERIAL='IC',
 PHYS_PAGE='166',
 XY='(-2950,5075)',
 ROT='2',
 VER='1',
 PACK_TYPE='SMLF',
 LOCATION='D5',
 CDS_LIB='pure_quanta',
 CDS_PART_NAME='Q_LED_SMLF-LED_BLUE,LTST-C281TBKT-5A,IC,BEBL0172Z00',
 PART_NUMBER='BEBL0172Z00',
 PRIM_FILE='./archive_libs/logical/q_led/chips/chips.prt';

PART_NAME
 D6 'Q_LED_SMLF-LED_YELLOW,LTST-C190KSKT-P,IC,BEYL0159ZA':;

SECTION_NUMBER 1
 '@T6G_MB_LIB.T6G(SCH_1):PAGE143_I9@PURE_QUANTA.Q_LED(CHIPS)':
 C_PATH='@t6g_mb_lib.t6g(sch_1):page143_i9@pure_quanta.q_led(chips)',
 P_PATH='@t6g_mb_lib.t6g(sch_1):page166_i9@pure_quanta.q_led(chips)',
 PATH='I9',
 DRAWING='@T6G_MB_LIB.T6G(SCH_1):PAGE143',
 COLOR='LED_YELLOW',
 MANUF_PN='LTST-C190KSKT-P',
 MATERIAL='IC',
 PHYS_PAGE='166',
 XY='(-3100,3450)',
 ROT='2',
 VER='1',
 PACK_TYPE='SMLF',
 LOCATION='D6',
 CDS_LIB='pure_quanta',
 CDS_PART_NAME='Q_LED_SMLF-LED_YELLOW,LTST-C190KSKT-P,IC,BEYL0159ZA',
 PART_NUMBER='BEYL0159Z00',
 PRIM_FILE='./archive_libs/logical/q_led/chips/chips.prt';

PART_NAME
 D7 'Q_LED_SMLF-LED_YELLOW,LTST-C190KSKT-P,IC,BEYL0159ZA':;

SECTION_NUMBER 1
 '@T6G_MB_LIB.T6G(SCH_1):PAGE84_I96@PURE_QUANTA.Q_LED(CHIPS)':
 C_PATH='@t6g_mb_lib.t6g(sch_1):page84_i96@pure_quanta.q_led(chips)',
 P_PATH='@t6g_mb_lib.t6g(sch_1):page85_i96@pure_quanta.q_led(chips)',
 PATH='I96',
 DRAWING='@T6G_MB_LIB.T6G(SCH_1):PAGE84',
 COLOR='LED_YELLOW',
 MANUF_PN='LTST-C190KSKT-P',
 MATERIAL='IC',
 PHYS_PAGE='85',
 XY='(-2550,6050)',
 ROT='0',
 VER='1',
 PACK_TYPE='SMLF',
 LOCATION='D7',
 CDS_LIB='pure_quanta',
 CDS_PART_NAME='Q_LED_SMLF-LED_YELLOW,LTST-C190KSKT-P,IC,BEYL0159ZA',
 PART_NUMBER='BEYL0159Z00',
 PRIM_FILE='./archive_libs/logical/q_led/chips/chips.prt';

PART_NAME
 D8 'Q_LED_SMLF-LED_YELLOW,LTST-C190KSKT-P,IC,BEYL0159ZA':;

SECTION_NUMBER 1
 '@T6G_MB_LIB.T6G(SCH_1):PAGE84_I97@PURE_QUANTA.Q_LED(CHIPS)':
 C_PATH='@t6g_mb_lib.t6g(sch_1):page84_i97@pure_quanta.q_led(chips)',
 P_PATH='@t6g_mb_lib.t6g(sch_1):page85_i97@pure_quanta.q_led(chips)',
 PATH='I97',
 DRAWING='@T6G_MB_LIB.T6G(SCH_1):PAGE84',
 COLOR='LED_YELLOW',
 MANUF_PN='LTST-C190KSKT-P',
 MATERIAL='IC',
 PHYS_PAGE='85',
 XY='(-2525,5700)',
 ROT='0',
 VER='1',
 PACK_TYPE='SMLF',
 LOCATION='D8',
 CDS_LIB='pure_quanta',
 CDS_PART_NAME='Q_LED_SMLF-LED_YELLOW,LTST-C190KSKT-P,IC,BEYL0159ZA',
 PART_NUMBER='BEYL0159Z00',
 PRIM_FILE='./archive_libs/logical/q_led/chips/chips.prt';

PART_NAME
 D9 'Q_LED_SMLF-LED_BLUE,LTST-C281TBKT-5A,IC,BEBL0172Z00':;

SECTION_NUMBER 1
 '@T6G_MB_LIB.T6G(SCH_1):PAGE142_I79@PURE_QUANTA.Q_LED(CHIPS)':
 C_PATH='@t6g_mb_lib.t6g(sch_1):page142_i79@pure_quanta.q_led(chips)',
 P_PATH='@t6g_mb_lib.t6g(sch_1):page165_i79@pure_quanta.q_led(chips)',
 PATH='I79',
 DRAWING='@T6G_MB_LIB.T6G(SCH_1):PAGE142',
 COLOR='LED_BLUE',
 MANUF_PN='LTST-C281TBKT-5A',
 MATERIAL='IC',
 PHYS_PAGE='165',
 XY='(-4650,1575)',
 ROT='0',
 VER='1',
 PACK_TYPE='SMLF',
 LOCATION='D9',
 CDS_LIB='pure_quanta',
 CDS_PART_NAME='Q_LED_SMLF-LED_BLUE,LTST-C281TBKT-5A,IC,BEBL0172Z00',
 PART_NUMBER='BEBL0172Z00',
 PRIM_FILE='./archive_libs/logical/q_led/chips/chips.prt';

PART_NAME
 D46 'Q_LED_SMLF-LED_BLUE,LTST-C281TBKT-5A,IC,BEBL0172Z00':;

SECTION_NUMBER 1
 '@T6G_MB_LIB.T6G(SCH_1):PAGE143_I43@PURE_QUANTA.Q_LED(CHIPS)':
 C_PATH='@t6g_mb_lib.t6g(sch_1):page143_i43@pure_quanta.q_led(chips)',
 P_PATH='@t6g_mb_lib.t6g(sch_1):page166_i43@pure_quanta.q_led(chips)',
 PATH='I43',
 DRAWING='@T6G_MB_LIB.T6G(SCH_1):PAGE143',
 COLOR='LED_BLUE',
 MANUF_PN='LTST-C281TBKT-5A',
 MATERIAL='IC',
 PHYS_PAGE='166',
 XY='(-4125,1975)',
 ROT='2',
 VER='1',
 PACK_TYPE='SMLF',
 LOCATION='D46',
 CDS_LIB='pure_quanta',
 CDS_PART_NAME='Q_LED_SMLF-LED_BLUE,LTST-C281TBKT-5A,IC,BEBL0172Z00',
 PART_NUMBER='BEBL0172Z00',
 PRIM_FILE='./archive_libs/logical/q_led/chips/chips.prt';

PART_NAME
 D49 'Q_LED_SMLF-LED_BLUE,LTST-C281TBKT-5A,IC,BEBL0172Z00':;

SECTION_NUMBER 1
 '@T6G_MB_LIB.T6G(SCH_1):PAGE143_I38@PURE_QUANTA.Q_LED(CHIPS)':
 C_PATH='@t6g_mb_lib.t6g(sch_1):page143_i38@pure_quanta.q_led(chips)',
 P_PATH='@t6g_mb_lib.t6g(sch_1):page166_i38@pure_quanta.q_led(chips)',
 PATH='I38',
 DRAWING='@T6G_MB_LIB.T6G(SCH_1):PAGE143',
 COLOR='LED_BLUE',
 MANUF_PN='LTST-C281TBKT-5A',
 MATERIAL='IC',
 PHYS_PAGE='166',
 XY='(-4275,550)',
 ROT='2',
 VER='1',
 PACK_TYPE='SMLF',
 LOCATION='D49',
 CDS_LIB='pure_quanta',
 CDS_PART_NAME='Q_LED_SMLF-LED_BLUE,LTST-C281TBKT-5A,IC,BEBL0172Z00',
 PART_NUMBER='BEBL0172Z00',
 PRIM_FILE='./archive_libs/logical/q_led/chips/chips.prt';

PART_NAME
 D73 'Q_LED_SMLF-LED_BLUE,LTST-C281TBKT-5A,IC,BEBL0172Z00':;

SECTION_NUMBER 1
 '@T6G_MB_LIB.T6G(SCH_1):PAGE374_I19@PURE_QUANTA.Q_LED(CHIPS)':
 C_PATH='@t6g_mb_lib.t6g(sch_1):page374_i19@pure_quanta.q_led(chips)',
 P_PATH='@t6g_mb_lib.t6g(sch_1):page255_i19@pure_quanta.q_led(chips)',
 PATH='I19',
 DRAWING='@T6G_MB_LIB.T6G(SCH_1):PAGE374',
 COLOR='LED_BLUE',
 MANUF_PN='LTST-C281TBKT-5A',
 MATERIAL='IC',
 PHYS_PAGE='255',
 XY='(-6900,5725)',
 ROT='2',
 VER='1',
 PACK_TYPE='SMLF',
 LOCATION='D73',
 CDS_LIB='pure_quanta',
 CDS_PART_NAME='Q_LED_SMLF-LED_BLUE,LTST-C281TBKT-5A,IC,BEBL0172Z00',
 PART_NUMBER='BEBL0172Z00',
 PRIM_FILE='./archive_libs/logical/q_led/chips/chips.prt';

PART_NAME
 D74 'Q_LED_SMLF-LED_BLUE,LTST-C281TBKT-5A,IC,BEBL0172Z00':;

SECTION_NUMBER 1
 '@T6G_MB_LIB.T6G(SCH_1):PAGE374_I14@PURE_QUANTA.Q_LED(CHIPS)':
 C_PATH='@t6g_mb_lib.t6g(sch_1):page374_i14@pure_quanta.q_led(chips)',
 P_PATH='@t6g_mb_lib.t6g(sch_1):page255_i14@pure_quanta.q_led(chips)',
 PATH='I14',
 DRAWING='@T6G_MB_LIB.T6G(SCH_1):PAGE374',
 COLOR='LED_BLUE',
 MANUF_PN='LTST-C281TBKT-5A',
 MATERIAL='IC',
 PHYS_PAGE='255',
 XY='(-6900,4400)',
 ROT='2',
 VER='1',
 PACK_TYPE='SMLF',
 LOCATION='D74',
 CDS_LIB='pure_quanta',
 CDS_PART_NAME='Q_LED_SMLF-LED_BLUE,LTST-C281TBKT-5A,IC,BEBL0172Z00',
 PART_NUMBER='BEBL0172Z00',
 PRIM_FILE='./archive_libs/logical/q_led/chips/chips.prt';

PART_NAME
 D75 'Q_LED_SMLF-LED_BLUE,LTST-C281TBKT-5A,IC,BEBL0172Z00':;

SECTION_NUMBER 1
 '@T6G_MB_LIB.T6G(SCH_1):PAGE374_I13@PURE_QUANTA.Q_LED(CHIPS)':
 C_PATH='@t6g_mb_lib.t6g(sch_1):page374_i13@pure_quanta.q_led(chips)',
 P_PATH='@t6g_mb_lib.t6g(sch_1):page255_i13@pure_quanta.q_led(chips)',
 PATH='I13',
 DRAWING='@T6G_MB_LIB.T6G(SCH_1):PAGE374',
 COLOR='LED_BLUE',
 MANUF_PN='LTST-C281TBKT-5A',
 MATERIAL='IC',
 PHYS_PAGE='255',
 XY='(-6900,3175)',
 ROT='2',
 VER='1',
 PACK_TYPE='SMLF',
 LOCATION='D75',
 CDS_LIB='pure_quanta',
 CDS_PART_NAME='Q_LED_SMLF-LED_BLUE,LTST-C281TBKT-5A,IC,BEBL0172Z00',
 PART_NUMBER='BEBL0172Z00',
 PRIM_FILE='./archive_libs/logical/q_led/chips/chips.prt';

PART_NAME
 D76 'Q_LED_SMLF-LED_BLUE,LTST-C281TBKT-5A,IC,BEBL0172Z00':;

SECTION_NUMBER 1
 '@T6G_MB_LIB.T6G(SCH_1):PAGE374_I11@PURE_QUANTA.Q_LED(CHIPS)':
 C_PATH='@t6g_mb_lib.t6g(sch_1):page374_i11@pure_quanta.q_led(chips)',
 P_PATH='@t6g_mb_lib.t6g(sch_1):page255_i11@pure_quanta.q_led(chips)',
 PATH='I11',
 DRAWING='@T6G_MB_LIB.T6G(SCH_1):PAGE374',
 COLOR='LED_BLUE',
 MANUF_PN='LTST-C281TBKT-5A',
 MATERIAL='IC',
 PHYS_PAGE='255',
 XY='(-6900,1850)',
 ROT='2',
 VER='1',
 PACK_TYPE='SMLF',
 LOCATION='D76',
 CDS_LIB='pure_quanta',
 CDS_PART_NAME='Q_LED_SMLF-LED_BLUE,LTST-C281TBKT-5A,IC,BEBL0172Z00',
 PART_NUMBER='BEBL0172Z00',
 PRIM_FILE='./archive_libs/logical/q_led/chips/chips.prt';

PART_NAME
 D77 'Q_LED_SMLF-LED_BLUE,LTST-C281TBKT-5A,IC,BEBL0172Z00':;

SECTION_NUMBER 1
 '@T6G_MB_LIB.T6G(SCH_1):PAGE374_I36@PURE_QUANTA.Q_LED(CHIPS)':
 C_PATH='@t6g_mb_lib.t6g(sch_1):page374_i36@pure_quanta.q_led(chips)',
 P_PATH='@t6g_mb_lib.t6g(sch_1):page255_i36@pure_quanta.q_led(chips)',
 PATH='I36',
 DRAWING='@T6G_MB_LIB.T6G(SCH_1):PAGE374',
 COLOR='LED_BLUE',
 MANUF_PN='LTST-C281TBKT-5A',
 MATERIAL='IC',
 PHYS_PAGE='255',
 XY='(-2125,5725)',
 ROT='2',
 VER='1',
 PACK_TYPE='SMLF',
 LOCATION='D77',
 CDS_LIB='pure_quanta',
 CDS_PART_NAME='Q_LED_SMLF-LED_BLUE,LTST-C281TBKT-5A,IC,BEBL0172Z00',
 PART_NUMBER='BEBL0172Z00',
 PRIM_FILE='./archive_libs/logical/q_led/chips/chips.prt';

PART_NAME
 D78 'Q_LED_SMLF-LED_BLUE,LTST-C281TBKT-5A,IC,BEBL0172Z00':;

SECTION_NUMBER 1
 '@T6G_MB_LIB.T6G(SCH_1):PAGE374_I32@PURE_QUANTA.Q_LED(CHIPS)':
 C_PATH='@t6g_mb_lib.t6g(sch_1):page374_i32@pure_quanta.q_led(chips)',
 P_PATH='@t6g_mb_lib.t6g(sch_1):page255_i32@pure_quanta.q_led(chips)',
 PATH='I32',
 DRAWING='@T6G_MB_LIB.T6G(SCH_1):PAGE374',
 COLOR='LED_BLUE',
 MANUF_PN='LTST-C281TBKT-5A',
 MATERIAL='IC',
 PHYS_PAGE='255',
 XY='(-2125,4400)',
 ROT='2',
 VER='1',
 PACK_TYPE='SMLF',
 LOCATION='D78',
 CDS_LIB='pure_quanta',
 CDS_PART_NAME='Q_LED_SMLF-LED_BLUE,LTST-C281TBKT-5A,IC,BEBL0172Z00',
 PART_NUMBER='BEBL0172Z00',
 PRIM_FILE='./archive_libs/logical/q_led/chips/chips.prt';

PART_NAME
 D79 'Q_LED_SMLF-LED_BLUE,LTST-C281TBKT-5A,IC,BEBL0172Z00':;

SECTION_NUMBER 1
 '@T6G_MB_LIB.T6G(SCH_1):PAGE374_I30@PURE_QUANTA.Q_LED(CHIPS)':
 C_PATH='@t6g_mb_lib.t6g(sch_1):page374_i30@pure_quanta.q_led(chips)',
 P_PATH='@t6g_mb_lib.t6g(sch_1):page255_i30@pure_quanta.q_led(chips)',
 PATH='I30',
 DRAWING='@T6G_MB_LIB.T6G(SCH_1):PAGE374',
 COLOR='LED_BLUE',
 MANUF_PN='LTST-C281TBKT-5A',
 MATERIAL='IC',
 PHYS_PAGE='255',
 XY='(-2125,3150)',
 ROT='2',
 VER='1',
 PACK_TYPE='SMLF',
 LOCATION='D79',
 CDS_LIB='pure_quanta',
 CDS_PART_NAME='Q_LED_SMLF-LED_BLUE,LTST-C281TBKT-5A,IC,BEBL0172Z00',
 PART_NUMBER='BEBL0172Z00',
 PRIM_FILE='./archive_libs/logical/q_led/chips/chips.prt';

PART_NAME
 D80 'Q_LED_SMLF-LED_BLUE,LTST-C281TBKT-5A,IC,BEBL0172Z00':;

SECTION_NUMBER 1
 '@T6G_MB_LIB.T6G(SCH_1):PAGE375_I19@PURE_QUANTA.Q_LED(CHIPS)':
 C_PATH='@t6g_mb_lib.t6g(sch_1):page375_i19@pure_quanta.q_led(chips)',
 P_PATH='@t6g_mb_lib.t6g(sch_1):page256_i19@pure_quanta.q_led(chips)',
 PATH='I19',
 DRAWING='@T6G_MB_LIB.T6G(SCH_1):PAGE375',
 COLOR='LED_BLUE',
 MANUF_PN='LTST-C281TBKT-5A',
 MATERIAL='IC',
 PHYS_PAGE='256',
 XY='(-6850,6000)',
 ROT='2',
 VER='1',
 PACK_TYPE='SMLF',
 LOCATION='D80',
 CDS_LIB='pure_quanta',
 CDS_PART_NAME='Q_LED_SMLF-LED_BLUE,LTST-C281TBKT-5A,IC,BEBL0172Z00',
 PART_NUMBER='BEBL0172Z00',
 PRIM_FILE='./archive_libs/logical/q_led/chips/chips.prt';

PART_NAME
 D81 'Q_LED_SMLF-LED_BLUE,LTST-C281TBKT-5A,IC,BEBL0172Z00':;

SECTION_NUMBER 1
 '@T6G_MB_LIB.T6G(SCH_1):PAGE375_I17@PURE_QUANTA.Q_LED(CHIPS)':
 C_PATH='@t6g_mb_lib.t6g(sch_1):page375_i17@pure_quanta.q_led(chips)',
 P_PATH='@t6g_mb_lib.t6g(sch_1):page256_i17@pure_quanta.q_led(chips)',
 PATH='I17',
 DRAWING='@T6G_MB_LIB.T6G(SCH_1):PAGE375',
 COLOR='LED_BLUE',
 MANUF_PN='LTST-C281TBKT-5A',
 MATERIAL='IC',
 PHYS_PAGE='256',
 XY='(-6850,4675)',
 ROT='2',
 VER='1',
 PACK_TYPE='SMLF',
 LOCATION='D81',
 CDS_LIB='pure_quanta',
 CDS_PART_NAME='Q_LED_SMLF-LED_BLUE,LTST-C281TBKT-5A,IC,BEBL0172Z00',
 PART_NUMBER='BEBL0172Z00',
 PRIM_FILE='./archive_libs/logical/q_led/chips/chips.prt';

PART_NAME
 D82 'Q_LED_SMLF-LED_BLUE,LTST-C281TBKT-5A,IC,BEBL0172Z00':;

SECTION_NUMBER 1
 '@T6G_MB_LIB.T6G(SCH_1):PAGE375_I14@PURE_QUANTA.Q_LED(CHIPS)':
 C_PATH='@t6g_mb_lib.t6g(sch_1):page375_i14@pure_quanta.q_led(chips)',
 P_PATH='@t6g_mb_lib.t6g(sch_1):page256_i14@pure_quanta.q_led(chips)',
 PATH='I14',
 DRAWING='@T6G_MB_LIB.T6G(SCH_1):PAGE375',
 COLOR='LED_BLUE',
 MANUF_PN='LTST-C281TBKT-5A',
 MATERIAL='IC',
 PHYS_PAGE='256',
 XY='(-6850,3450)',
 ROT='2',
 VER='1',
 PACK_TYPE='SMLF',
 LOCATION='D82',
 CDS_LIB='pure_quanta',
 CDS_PART_NAME='Q_LED_SMLF-LED_BLUE,LTST-C281TBKT-5A,IC,BEBL0172Z00',
 PART_NUMBER='BEBL0172Z00',
 PRIM_FILE='./archive_libs/logical/q_led/chips/chips.prt';

PART_NAME
 D83 'Q_LED_SMLF-LED_BLUE,LTST-C281TBKT-5A,IC,BEBL0172Z00':;

SECTION_NUMBER 1
 '@T6G_MB_LIB.T6G(SCH_1):PAGE375_I13@PURE_QUANTA.Q_LED(CHIPS)':
 C_PATH='@t6g_mb_lib.t6g(sch_1):page375_i13@pure_quanta.q_led(chips)',
 P_PATH='@t6g_mb_lib.t6g(sch_1):page256_i13@pure_quanta.q_led(chips)',
 PATH='I13',
 DRAWING='@T6G_MB_LIB.T6G(SCH_1):PAGE375',
 COLOR='LED_BLUE',
 MANUF_PN='LTST-C281TBKT-5A',
 MATERIAL='IC',
 PHYS_PAGE='256',
 XY='(-6850,2125)',
 ROT='2',
 VER='1',
 PACK_TYPE='SMLF',
 LOCATION='D83',
 CDS_LIB='pure_quanta',
 CDS_PART_NAME='Q_LED_SMLF-LED_BLUE,LTST-C281TBKT-5A,IC,BEBL0172Z00',
 PART_NUMBER='BEBL0172Z00',
 PRIM_FILE='./archive_libs/logical/q_led/chips/chips.prt';

PART_NAME
 D84 'Q_LED_SMLF-LED_BLUE,LTST-C281TBKT-5A,IC,BEBL0172Z00':;

SECTION_NUMBER 1
 '@T6G_MB_LIB.T6G(SCH_1):PAGE375_I35@PURE_QUANTA.Q_LED(CHIPS)':
 C_PATH='@t6g_mb_lib.t6g(sch_1):page375_i35@pure_quanta.q_led(chips)',
 P_PATH='@t6g_mb_lib.t6g(sch_1):page256_i35@pure_quanta.q_led(chips)',
 PATH='I35',
 DRAWING='@T6G_MB_LIB.T6G(SCH_1):PAGE375',
 COLOR='LED_BLUE',
 MANUF_PN='LTST-C281TBKT-5A',
 MATERIAL='IC',
 PHYS_PAGE='256',
 XY='(-2175,6025)',
 ROT='2',
 VER='1',
 PACK_TYPE='SMLF',
 LOCATION='D84',
 CDS_LIB='pure_quanta',
 CDS_PART_NAME='Q_LED_SMLF-LED_BLUE,LTST-C281TBKT-5A,IC,BEBL0172Z00',
 PART_NUMBER='BEBL0172Z00',
 PRIM_FILE='./archive_libs/logical/q_led/chips/chips.prt';

PART_NAME
 D85 'Q_LED_SMLF-LED_BLUE,LTST-C281TBKT-5A,IC,BEBL0172Z00':;

SECTION_NUMBER 1
 '@T6G_MB_LIB.T6G(SCH_1):PAGE375_I33@PURE_QUANTA.Q_LED(CHIPS)':
 C_PATH='@t6g_mb_lib.t6g(sch_1):page375_i33@pure_quanta.q_led(chips)',
 P_PATH='@t6g_mb_lib.t6g(sch_1):page256_i33@pure_quanta.q_led(chips)',
 PATH='I33',
 DRAWING='@T6G_MB_LIB.T6G(SCH_1):PAGE375',
 COLOR='LED_BLUE',
 MANUF_PN='LTST-C281TBKT-5A',
 MATERIAL='IC',
 PHYS_PAGE='256',
 XY='(-2175,4700)',
 ROT='2',
 VER='1',
 PACK_TYPE='SMLF',
 LOCATION='D85',
 CDS_LIB='pure_quanta',
 CDS_PART_NAME='Q_LED_SMLF-LED_BLUE,LTST-C281TBKT-5A,IC,BEBL0172Z00',
 PART_NUMBER='BEBL0172Z00',
 PRIM_FILE='./archive_libs/logical/q_led/chips/chips.prt';

PART_NAME
 D88 'Q_LED_SMLF-LED_BLUE,LTST-C281TBKT-5A,IC,BEBL0172Z00':;

SECTION_NUMBER 1
 '@T6G_MB_LIB.T6G(SCH_1):PAGE254_I33@PURE_QUANTA.Q_LED(CHIPS)':
 C_PATH='@t6g_mb_lib.t6g(sch_1):page254_i33@pure_quanta.q_led(chips)',
 P_PATH='@t6g_mb_lib.t6g(sch_1):page254_i33@pure_quanta.q_led(chips)',
 PATH='I33',
 DRAWING='@T6G_MB_LIB.T6G(SCH_1):PAGE254',
 COLOR='LED_BLUE',
 MANUF_PN='LTST-C281TBKT-5A',
 MATERIAL='IC',
 PHYS_PAGE='254',
 XY='(-6675,1475)',
 ROT='2',
 VER='1',
 PACK_TYPE='SMLF',
 LOCATION='D88',
 CDS_LIB='pure_quanta',
 CDS_PART_NAME='Q_LED_SMLF-LED_BLUE,LTST-C281TBKT-5A,IC,BEBL0172Z00',
 PART_NUMBER='BEBL0172Z00',
 PRIM_FILE='./archive_libs/logical/q_led/chips/chips.prt';

PART_NAME
 D91 'Q_LED_SMLF-LED_BLUE,LTST-C281TBKT-5A,IC,BEBL0172Z00':;

SECTION_NUMBER 1
 '@T6G_MB_LIB.T6G(SCH_1):PAGE254_I23@PURE_QUANTA.Q_LED(CHIPS)':
 C_PATH='@t6g_mb_lib.t6g(sch_1):page254_i23@pure_quanta.q_led(chips)',
 P_PATH='@t6g_mb_lib.t6g(sch_1):page254_i23@pure_quanta.q_led(chips)',
 PATH='I23',
 DRAWING='@T6G_MB_LIB.T6G(SCH_1):PAGE254',
 COLOR='LED_BLUE',
 MANUF_PN='LTST-C281TBKT-5A',
 MATERIAL='IC',
 PHYS_PAGE='254',
 XY='(-6600,4550)',
 ROT='2',
 VER='1',
 PACK_TYPE='SMLF',
 LOCATION='D91',
 CDS_LIB='pure_quanta',
 CDS_PART_NAME='Q_LED_SMLF-LED_BLUE,LTST-C281TBKT-5A,IC,BEBL0172Z00',
 PART_NUMBER='BEBL0172Z00',
 PRIM_FILE='./archive_libs/logical/q_led/chips/chips.prt';

PART_NAME
 D93 'Q_LED_SMLF-LED_BLUE,LTST-C281TBKT-5A,IC,BEBL0172Z00':;

SECTION_NUMBER 1
 '@T6G_MB_LIB.T6G(SCH_1):PAGE254_I40@PURE_QUANTA.Q_LED(CHIPS)':
 C_PATH='@t6g_mb_lib.t6g(sch_1):page254_i40@pure_quanta.q_led(chips)',
 P_PATH='@t6g_mb_lib.t6g(sch_1):page254_i40@pure_quanta.q_led(chips)',
 PATH='I40',
 DRAWING='@T6G_MB_LIB.T6G(SCH_1):PAGE254',
 COLOR='LED_BLUE',
 MANUF_PN='LTST-C281TBKT-5A',
 MATERIAL='IC',
 PHYS_PAGE='254',
 XY='(-6625,3125)',
 ROT='2',
 VER='1',
 PACK_TYPE='SMLF',
 LOCATION='D93',
 CDS_LIB='pure_quanta',
 CDS_PART_NAME='Q_LED_SMLF-LED_BLUE,LTST-C281TBKT-5A,IC,BEBL0172Z00',
 PART_NUMBER='BEBL0172Z00',
 PRIM_FILE='./archive_libs/logical/q_led/chips/chips.prt';

PART_NAME
 D96 'Q_LED_SMLF-LED_BLUE,LTST-C281TBKT-5A,IC,BEBL0172Z00':;

SECTION_NUMBER 1
 '@T6G_MB_LIB.T6G(SCH_1):PAGE254_I14@PURE_QUANTA.Q_LED(CHIPS)':
 C_PATH='@t6g_mb_lib.t6g(sch_1):page254_i14@pure_quanta.q_led(chips)',
 P_PATH='@t6g_mb_lib.t6g(sch_1):page254_i14@pure_quanta.q_led(chips)',
 PATH='I14',
 DRAWING='@T6G_MB_LIB.T6G(SCH_1):PAGE254',
 COLOR='LED_BLUE',
 MANUF_PN='LTST-C281TBKT-5A',
 MATERIAL='IC',
 PHYS_PAGE='254',
 XY='(-6675,5925)',
 ROT='2',
 VER='1',
 PACK_TYPE='SMLF',
 LOCATION='D96',
 CDS_LIB='pure_quanta',
 CDS_PART_NAME='Q_LED_SMLF-LED_BLUE,LTST-C281TBKT-5A,IC,BEBL0172Z00',
 PART_NUMBER='BEBL0172Z00',
 PRIM_FILE='./archive_libs/logical/q_led/chips/chips.prt';

PART_NAME
 D98 'Q_LED_SMLF-LED_BLUE,LTST-C281TBKT-5A,IC,BEBL0172Z00':;

SECTION_NUMBER 1
 '@T6G_MB_LIB.T6G(SCH_1):PAGE254_I17@PURE_QUANTA.Q_LED(CHIPS)':
 C_PATH='@t6g_mb_lib.t6g(sch_1):page254_i17@pure_quanta.q_led(chips)',
 P_PATH='@t6g_mb_lib.t6g(sch_1):page254_i17@pure_quanta.q_led(chips)',
 PATH='I17',
 DRAWING='@T6G_MB_LIB.T6G(SCH_1):PAGE254',
 COLOR='LED_BLUE',
 MANUF_PN='LTST-C281TBKT-5A',
 MATERIAL='IC',
 PHYS_PAGE='254',
 XY='(-2050,2200)',
 ROT='2',
 VER='1',
 PACK_TYPE='SMLF',
 LOCATION='D98',
 CDS_LIB='pure_quanta',
 CDS_PART_NAME='Q_LED_SMLF-LED_BLUE,LTST-C281TBKT-5A,IC,BEBL0172Z00',
 PART_NUMBER='BEBL0172Z00',
 PRIM_FILE='./archive_libs/logical/q_led/chips/chips.prt';

PART_NAME
 D99 'Q_LED_SMLF-LED_BLUE,LTST-C281TBKT-5A,IC,BEBL0172Z00':;

SECTION_NUMBER 1
 '@T6G_MB_LIB.T6G(SCH_1):PAGE254_I3@PURE_QUANTA.Q_LED(CHIPS)':
 C_PATH='@t6g_mb_lib.t6g(sch_1):page254_i3@pure_quanta.q_led(chips)',
 P_PATH='@t6g_mb_lib.t6g(sch_1):page254_i3@pure_quanta.q_led(chips)',
 PATH='I3',
 DRAWING='@T6G_MB_LIB.T6G(SCH_1):PAGE254',
 COLOR='LED_BLUE',
 MANUF_PN='LTST-C281TBKT-5A',
 MATERIAL='IC',
 PHYS_PAGE='254',
 XY='(-2125,975)',
 ROT='2',
 VER='1',
 PACK_TYPE='SMLF',
 LOCATION='D99',
 CDS_LIB='pure_quanta',
 CDS_PART_NAME='Q_LED_SMLF-LED_BLUE,LTST-C281TBKT-5A,IC,BEBL0172Z00',
 PART_NUMBER='BEBL0172Z00',
 PRIM_FILE='./archive_libs/logical/q_led/chips/chips.prt';

PART_NAME
 D6000 'Q_LED_SMLF-LED_BLUE,LTST-C281TBKT-5A,IC,BEBL0172Z00':;

SECTION_NUMBER 1
 '@T6G_MB_LIB.T6G(SCH_1):PAGE254_I43@PURE_QUANTA.Q_LED(CHIPS)':
 C_PATH='@t6g_mb_lib.t6g(sch_1):page254_i43@pure_quanta.q_led(chips)',
 P_PATH='@t6g_mb_lib.t6g(sch_1):page254_i43@pure_quanta.q_led(chips)',
 PATH='I43',
 DRAWING='@T6G_MB_LIB.T6G(SCH_1):PAGE254',
 COLOR='LED_BLUE',
 MANUF_PN='LTST-C281TBKT-5A',
 MATERIAL='IC',
 PHYS_PAGE='254',
 XY='(-1875,3950)',
 ROT='2',
 VER='1',
 PACK_TYPE='SMLF',
 LOCATION='D6000',
 CDS_LIB='pure_quanta',
 CDS_PART_NAME='Q_LED_SMLF-LED_BLUE,LTST-C281TBKT-5A,IC,BEBL0172Z00',
 PART_NUMBER='BEBL0172Z00',
 PRIM_FILE='./archive_libs/logical/q_led/chips/chips.prt';

PART_NAME
 D8000 'Q_LED_SMLF-LED_BLUE,LTST-C281TBKT-5A,IC,BEBL0172Z00':;

SECTION_NUMBER 1
 '@T6G_MB_LIB.T6G(SCH_1):PAGE375_I42@PURE_QUANTA.Q_LED(CHIPS)':
 C_PATH='@t6g_mb_lib.t6g(sch_1):page375_i42@pure_quanta.q_led(chips)',
 P_PATH='@t6g_mb_lib.t6g(sch_1):page256_i42@pure_quanta.q_led(chips)',
 PATH='I42',
 DRAWING='@T6G_MB_LIB.T6G(SCH_1):PAGE375',
 SEC_TYPE='SMLF',
 COLOR='LED_BLUE',
 MANUF_PN='LTST-C281TBKT-5A',
 MATERIAL='IC',
 PHYS_PAGE='256',
 XY='(-4100,3575)',
 ROT='2',
 VER='1',
 PACK_TYPE='SMLF',
 LOCATION='D8000',
 SEC='1',
 CDS_LIB='pure_quanta',
 CDS_PART_NAME='Q_LED_SMLF-LED_BLUE,LTST-C281TBKT-5A,IC,BEBL0172Z00',
 PART_NUMBER='BEBL0172Z00',
 PRIM_FILE='./archive_libs/logical/q_led/chips/chips.prt';

PART_NAME
 D8001 'Q_LED_SMLF-LED_BLUE,LTST-C281TBKT-5A,IC,BEBL0172Z00':;

SECTION_NUMBER 1
 '@T6G_MB_LIB.T6G(SCH_1):PAGE375_I52@PURE_QUANTA.Q_LED(CHIPS)':
 C_PATH='@t6g_mb_lib.t6g(sch_1):page375_i52@pure_quanta.q_led(chips)',
 P_PATH='@t6g_mb_lib.t6g(sch_1):page256_i52@pure_quanta.q_led(chips)',
 PATH='I52',
 DRAWING='@T6G_MB_LIB.T6G(SCH_1):PAGE375',
 SEC_TYPE='SMLF',
 COLOR='LED_BLUE',
 MANUF_PN='LTST-C281TBKT-5A',
 MATERIAL='IC',
 PHYS_PAGE='256',
 XY='(-4025,2425)',
 ROT='2',
 VER='1',
 PACK_TYPE='SMLF',
 LOCATION='D8001',
 SEC='1',
 CDS_LIB='pure_quanta',
 CDS_PART_NAME='Q_LED_SMLF-LED_BLUE,LTST-C281TBKT-5A,IC,BEBL0172Z00',
 PART_NUMBER='BEBL0172Z00',
 PRIM_FILE='./archive_libs/logical/q_led/chips/chips.prt';

PART_NAME
 D8002 'Q_LED_SMLF-LED_YELLOW,LTST-C190KSKT-P,IC,BEYL0159ZA':;

SECTION_NUMBER 1
 '@T6G_MB_LIB.T6G(SCH_1):PAGE375_I56@PURE_QUANTA.Q_LED(CHIPS)':
 C_PATH='@t6g_mb_lib.t6g(sch_1):page375_i56@pure_quanta.q_led(chips)',
 P_PATH='@t6g_mb_lib.t6g(sch_1):page256_i56@pure_quanta.q_led(chips)',
 PATH='I56',
 DRAWING='@T6G_MB_LIB.T6G(SCH_1):PAGE375',
 SEC_TYPE='SMLF',
 COLOR='LED_YELLOW',
 MANUF_PN='LTST-C190KSKT-P',
 MATERIAL='IC',
 PHYS_PAGE='256',
 XY='(-1725,1500)',
 ROT='2',
 VER='1',
 PACK_TYPE='SMLF',
 LOCATION='D8002',
 SEC='1',
 CDS_LIB='pure_quanta',
 CDS_PART_NAME='Q_LED_SMLF-LED_YELLOW,LTST-C190KSKT-P,IC,BEYL0159ZA',
 PART_NUMBER='BEYL0159Z00',
 PRIM_FILE='./archive_libs/logical/q_led/chips/chips.prt';

PART_NAME
 D8003 'SCHOTTKY_12-B0530WS7F,SMLF,EMPTY,BC000530Z41':;

SECTION_NUMBER 1
 '@T6G_MB_LIB.T6G(SCH_1):PAGE85_I549@PURE_QUANTA.SCHOTTKY_12(CHIPS)':
 C_PATH='@t6g_mb_lib.t6g(sch_1):page85_i549@pure_quanta.schottky_12(chips)',
 P_PATH='@t6g_mb_lib.t6g(sch_1):page86_i549@pure_quanta.schottky_12(chips)',
 PATH='I549',
 DRAWING='@T6G_MB_LIB.T6G(SCH_1):PAGE85',
 SEC_TYPE='',
 PART_TYPE='SMLF',
 MATERIAL='EMPTY',
 PHYS_PAGE='86',
 XY='(-3000,1350)',
 ROT='0',
 VER='1',
 LOCATION='D8003',
 SEC='1',
 CDS_LIB='pure_quanta',
 CDS_PART_NAME='SCHOTTKY_12-B0530WS7F,SMLF,EMPTY,BC000530Z41',
 PART_NUMBER='BC000530Z41',
 VALUE='B0530WS7F',
 PRIM_FILE='./archive_libs/logical/schottky_12/chips/chips.prt';

PART_NAME
 D8004 'SCHOTTKY_12-B0530WS7F,SMLF,EMPTY,BC000530Z41':;

SECTION_NUMBER 1
 '@T6G_MB_LIB.T6G(SCH_1):PAGE91_I251@PURE_QUANTA.SCHOTTKY_12(CHIPS)':
 C_PATH='@t6g_mb_lib.t6g(sch_1):page91_i251@pure_quanta.schottky_12(chips)',
 P_PATH='@t6g_mb_lib.t6g(sch_1):page92_i251@pure_quanta.schottky_12(chips)',
 PATH='I251',
 DRAWING='@T6G_MB_LIB.T6G(SCH_1):PAGE91',
 PART_TYPE='SMLF',
 MATERIAL='EMPTY',
 PHYS_PAGE='92',
 XY='(-1825,1225)',
 ROT='0',
 VER='1',
 LOCATION='D8004',
 CDS_LIB='pure_quanta',
 CDS_PART_NAME='SCHOTTKY_12-B0530WS7F,SMLF,EMPTY,BC000530Z41',
 PART_NUMBER='BC000530Z41',
 VALUE='B0530WS7F',
 PRIM_FILE='./archive_libs/logical/schottky_12/chips/chips.prt';

PART_NAME
 D8005 'SCHOTTKY_12-B0530WS7F,SMLF,EMPTY,BC000530Z41':;

SECTION_NUMBER 1
 '@T6G_MB_LIB.T6G(SCH_1):PAGE97_I253@PURE_QUANTA.SCHOTTKY_12(CHIPS)':
 C_PATH='@t6g_mb_lib.t6g(sch_1):page97_i253@pure_quanta.schottky_12(chips)',
 P_PATH='@t6g_mb_lib.t6g(sch_1):page98_i253@pure_quanta.schottky_12(chips)',
 PATH='I253',
 DRAWING='@T6G_MB_LIB.T6G(SCH_1):PAGE97',
 PART_TYPE='SMLF',
 MATERIAL='EMPTY',
 PHYS_PAGE='98',
 XY='(-2475,1375)',
 ROT='0',
 VER='1',
 LOCATION='D8005',
 CDS_LIB='pure_quanta',
 CDS_PART_NAME='SCHOTTKY_12-B0530WS7F,SMLF,EMPTY,BC000530Z41',
 PART_NUMBER='BC000530Z41',
 VALUE='B0530WS7F',
 PRIM_FILE='./archive_libs/logical/schottky_12/chips/chips.prt';

PART_NAME
 D8006 'SCHOTTKY_12-B0530WS7F,SMLF,EMPTY,BC000530Z41':;

SECTION_NUMBER 1
 '@T6G_MB_LIB.T6G(SCH_1):PAGE103_I253@PURE_QUANTA.SCHOTTKY_12(CHIPS)':
 C_PATH='@t6g_mb_lib.t6g(sch_1):page103_i253@pure_quanta.schottky_12(chips)',
 P_PATH='@t6g_mb_lib.t6g(sch_1):page104_i253@pure_quanta.schottky_12(chips)',
 PATH='I253',
 DRAWING='@T6G_MB_LIB.T6G(SCH_1):PAGE103',
 PART_TYPE='SMLF',
 MATERIAL='EMPTY',
 PHYS_PAGE='104',
 XY='(-2325,1200)',
 ROT='0',
 VER='1',
 LOCATION='D8006',
 CDS_LIB='pure_quanta',
 CDS_PART_NAME='SCHOTTKY_12-B0530WS7F,SMLF,EMPTY,BC000530Z41',
 PART_NUMBER='BC000530Z41',
 VALUE='B0530WS7F',
 PRIM_FILE='./archive_libs/logical/schottky_12/chips/chips.prt';

PART_NAME
 DB1 'TDR_3P_TH2-EMPTY,N_A':;

SECTION_NUMBER 1
 '@T6G_MB_LIB.T6G(SCH_1):PAGE265_I16@PURE_QUANTA.TDR_3P(CHIPS)':
 C_PATH='@t6g_mb_lib.t6g(sch_1):page265_i16@pure_quanta.tdr_3p(chips)',
 P_PATH='@t6g_mb_lib.t6g(sch_1):page260_i16@pure_quanta.tdr_3p(chips)',
 PATH='I16',
 DRAWING='@T6G_MB_LIB.T6G(SCH_1):PAGE265',
 MATERIAL='EMPTY',
 PHYS_PAGE='260',
 XY='(-8650,5875)',
 ROT='0',
 VER='2',
 PACK_TYPE='TH2',
 LOCATION='DB1',
 CDS_LIB='pure_quanta',
 CDS_PART_NAME='TDR_3P_TH2-EMPTY,N_A',
 PART_NUMBER='N_A',
 PRIM_FILE='./archive_libs/logical/tdr_3p/chips/chips.prt';

PART_NAME
 DB2 'TDR_3P_TH2-EMPTY,N_A':;

SECTION_NUMBER 1
 '@T6G_MB_LIB.T6G(SCH_1):PAGE265_I15@PURE_QUANTA.TDR_3P(CHIPS)':
 C_PATH='@t6g_mb_lib.t6g(sch_1):page265_i15@pure_quanta.tdr_3p(chips)',
 P_PATH='@t6g_mb_lib.t6g(sch_1):page260_i15@pure_quanta.tdr_3p(chips)',
 PATH='I15',
 DRAWING='@T6G_MB_LIB.T6G(SCH_1):PAGE265',
 MATERIAL='EMPTY',
 PHYS_PAGE='260',
 XY='(-8650,5350)',
 ROT='0',
 VER='2',
 PACK_TYPE='TH2',
 LOCATION='DB2',
 CDS_LIB='pure_quanta',
 CDS_PART_NAME='TDR_3P_TH2-EMPTY,N_A',
 PART_NUMBER='N_A',
 PRIM_FILE='./archive_libs/logical/tdr_3p/chips/chips.prt';

PART_NAME
 DB3 'TDR_3P_TH2-EMPTY,N_A':;

SECTION_NUMBER 1
 '@T6G_MB_LIB.T6G(SCH_1):PAGE265_I13@PURE_QUANTA.TDR_3P(CHIPS)':
 C_PATH='@t6g_mb_lib.t6g(sch_1):page265_i13@pure_quanta.tdr_3p(chips)',
 P_PATH='@t6g_mb_lib.t6g(sch_1):page260_i13@pure_quanta.tdr_3p(chips)',
 PATH='I13',
 DRAWING='@T6G_MB_LIB.T6G(SCH_1):PAGE265',
 MATERIAL='EMPTY',
 PHYS_PAGE='260',
 XY='(-8650,4825)',
 ROT='0',
 VER='2',
 PACK_TYPE='TH2',
 LOCATION='DB3',
 CDS_LIB='pure_quanta',
 CDS_PART_NAME='TDR_3P_TH2-EMPTY,N_A',
 PART_NUMBER='N_A',
 PRIM_FILE='./archive_libs/logical/tdr_3p/chips/chips.prt';

PART_NAME
 DB4 'TDR_3P_TH2-EMPTY,N_A':;

SECTION_NUMBER 1
 '@T6G_MB_LIB.T6G(SCH_1):PAGE265_I12@PURE_QUANTA.TDR_3P(CHIPS)':
 C_PATH='@t6g_mb_lib.t6g(sch_1):page265_i12@pure_quanta.tdr_3p(chips)',
 P_PATH='@t6g_mb_lib.t6g(sch_1):page260_i12@pure_quanta.tdr_3p(chips)',
 PATH='I12',
 DRAWING='@T6G_MB_LIB.T6G(SCH_1):PAGE265',
 MATERIAL='EMPTY',
 PHYS_PAGE='260',
 XY='(-8650,4300)',
 ROT='0',
 VER='2',
 PACK_TYPE='TH2',
 LOCATION='DB4',
 CDS_LIB='pure_quanta',
 CDS_PART_NAME='TDR_3P_TH2-EMPTY,N_A',
 PART_NUMBER='N_A',
 PRIM_FILE='./archive_libs/logical/tdr_3p/chips/chips.prt';

PART_NAME
 DB5 'TDR_3P_TH2-EMPTY,N_A':;

SECTION_NUMBER 1
 '@T6G_MB_LIB.T6G(SCH_1):PAGE265_I9@PURE_QUANTA.TDR_3P(CHIPS)':
 C_PATH='@t6g_mb_lib.t6g(sch_1):page265_i9@pure_quanta.tdr_3p(chips)',
 P_PATH='@t6g_mb_lib.t6g(sch_1):page260_i9@pure_quanta.tdr_3p(chips)',
 PATH='I9',
 DRAWING='@T6G_MB_LIB.T6G(SCH_1):PAGE265',
 MATERIAL='EMPTY',
 PHYS_PAGE='260',
 XY='(-8650,3775)',
 ROT='0',
 VER='2',
 PACK_TYPE='TH2',
 LOCATION='DB5',
 CDS_LIB='pure_quanta',
 CDS_PART_NAME='TDR_3P_TH2-EMPTY,N_A',
 PART_NUMBER='N_A',
 PRIM_FILE='./archive_libs/logical/tdr_3p/chips/chips.prt';

PART_NAME
 DB6 'TDR_3P_TH2-EMPTY,N_A':;

SECTION_NUMBER 1
 '@T6G_MB_LIB.T6G(SCH_1):PAGE265_I2@PURE_QUANTA.TDR_3P(CHIPS)':
 C_PATH='@t6g_mb_lib.t6g(sch_1):page265_i2@pure_quanta.tdr_3p(chips)',
 P_PATH='@t6g_mb_lib.t6g(sch_1):page260_i2@pure_quanta.tdr_3p(chips)',
 PATH='I2',
 DRAWING='@T6G_MB_LIB.T6G(SCH_1):PAGE265',
 MATERIAL='EMPTY',
 PHYS_PAGE='260',
 XY='(-8700,2175)',
 ROT='0',
 VER='2',
 PACK_TYPE='TH2',
 LOCATION='DB6',
 CDS_LIB='pure_quanta',
 CDS_PART_NAME='TDR_3P_TH2-EMPTY,N_A',
 PART_NUMBER='N_A',
 PRIM_FILE='./archive_libs/logical/tdr_3p/chips/chips.prt';

PART_NAME
 DB7 'TDR_3P_TH2-EMPTY,N_A':;

SECTION_NUMBER 1
 '@T6G_MB_LIB.T6G(SCH_1):PAGE265_I44@PURE_QUANTA.TDR_3P(CHIPS)':
 C_PATH='@t6g_mb_lib.t6g(sch_1):page265_i44@pure_quanta.tdr_3p(chips)',
 P_PATH='@t6g_mb_lib.t6g(sch_1):page260_i44@pure_quanta.tdr_3p(chips)',
 PATH='I44',
 DRAWING='@T6G_MB_LIB.T6G(SCH_1):PAGE265',
 MATERIAL='EMPTY',
 PHYS_PAGE='260',
 XY='(-6950,5875)',
 ROT='0',
 VER='2',
 PACK_TYPE='TH2',
 LOCATION='DB7',
 CDS_LIB='pure_quanta',
 CDS_PART_NAME='TDR_3P_TH2-EMPTY,N_A',
 PART_NUMBER='N_A',
 PRIM_FILE='./archive_libs/logical/tdr_3p/chips/chips.prt';

PART_NAME
 DB8 'TDR_3P_TH2-EMPTY,N_A':;

SECTION_NUMBER 1
 '@T6G_MB_LIB.T6G(SCH_1):PAGE265_I42@PURE_QUANTA.TDR_3P(CHIPS)':
 C_PATH='@t6g_mb_lib.t6g(sch_1):page265_i42@pure_quanta.tdr_3p(chips)',
 P_PATH='@t6g_mb_lib.t6g(sch_1):page260_i42@pure_quanta.tdr_3p(chips)',
 PATH='I42',
 DRAWING='@T6G_MB_LIB.T6G(SCH_1):PAGE265',
 MATERIAL='EMPTY',
 PHYS_PAGE='260',
 XY='(-6950,5350)',
 ROT='0',
 VER='2',
 PACK_TYPE='TH2',
 LOCATION='DB8',
 CDS_LIB='pure_quanta',
 CDS_PART_NAME='TDR_3P_TH2-EMPTY,N_A',
 PART_NUMBER='N_A',
 PRIM_FILE='./archive_libs/logical/tdr_3p/chips/chips.prt';

PART_NAME
 DB9 'TDR_3P_TH2-EMPTY,N_A':;

SECTION_NUMBER 1
 '@T6G_MB_LIB.T6G(SCH_1):PAGE265_I40@PURE_QUANTA.TDR_3P(CHIPS)':
 C_PATH='@t6g_mb_lib.t6g(sch_1):page265_i40@pure_quanta.tdr_3p(chips)',
 P_PATH='@t6g_mb_lib.t6g(sch_1):page260_i40@pure_quanta.tdr_3p(chips)',
 PATH='I40',
 DRAWING='@T6G_MB_LIB.T6G(SCH_1):PAGE265',
 MATERIAL='EMPTY',
 PHYS_PAGE='260',
 XY='(-6950,4825)',
 ROT='0',
 VER='2',
 PACK_TYPE='TH2',
 LOCATION='DB9',
 CDS_LIB='pure_quanta',
 CDS_PART_NAME='TDR_3P_TH2-EMPTY,N_A',
 PART_NUMBER='N_A',
 PRIM_FILE='./archive_libs/logical/tdr_3p/chips/chips.prt';

PART_NAME
 DB10 'TDR_3P_TH2-EMPTY,N_A':;

SECTION_NUMBER 1
 '@T6G_MB_LIB.T6G(SCH_1):PAGE265_I38@PURE_QUANTA.TDR_3P(CHIPS)':
 C_PATH='@t6g_mb_lib.t6g(sch_1):page265_i38@pure_quanta.tdr_3p(chips)',
 P_PATH='@t6g_mb_lib.t6g(sch_1):page260_i38@pure_quanta.tdr_3p(chips)',
 PATH='I38',
 DRAWING='@T6G_MB_LIB.T6G(SCH_1):PAGE265',
 MATERIAL='EMPTY',
 PHYS_PAGE='260',
 XY='(-6950,4300)',
 ROT='0',
 VER='2',
 PACK_TYPE='TH2',
 LOCATION='DB10',
 CDS_LIB='pure_quanta',
 CDS_PART_NAME='TDR_3P_TH2-EMPTY,N_A',
 PART_NUMBER='N_A',
 PRIM_FILE='./archive_libs/logical/tdr_3p/chips/chips.prt';

PART_NAME
 DB11 'TDR_3P_TH2-EMPTY,N_A':;

SECTION_NUMBER 1
 '@T6G_MB_LIB.T6G(SCH_1):PAGE265_I25@PURE_QUANTA.TDR_3P(CHIPS)':
 C_PATH='@t6g_mb_lib.t6g(sch_1):page265_i25@pure_quanta.tdr_3p(chips)',
 P_PATH='@t6g_mb_lib.t6g(sch_1):page260_i25@pure_quanta.tdr_3p(chips)',
 PATH='I25',
 DRAWING='@T6G_MB_LIB.T6G(SCH_1):PAGE265',
 MATERIAL='EMPTY',
 PHYS_PAGE='260',
 XY='(-6950,3775)',
 ROT='0',
 VER='2',
 PACK_TYPE='TH2',
 LOCATION='DB11',
 CDS_LIB='pure_quanta',
 CDS_PART_NAME='TDR_3P_TH2-EMPTY,N_A',
 PART_NUMBER='N_A',
 PRIM_FILE='./archive_libs/logical/tdr_3p/chips/chips.prt';

PART_NAME
 DB12 'TDR_3P_TH2-EMPTY,N_A':;

SECTION_NUMBER 1
 '@T6G_MB_LIB.T6G(SCH_1):PAGE265_I18@PURE_QUANTA.TDR_3P(CHIPS)':
 C_PATH='@t6g_mb_lib.t6g(sch_1):page265_i18@pure_quanta.tdr_3p(chips)',
 P_PATH='@t6g_mb_lib.t6g(sch_1):page260_i18@pure_quanta.tdr_3p(chips)',
 PATH='I18',
 DRAWING='@T6G_MB_LIB.T6G(SCH_1):PAGE265',
 MATERIAL='EMPTY',
 PHYS_PAGE='260',
 XY='(-7000,2175)',
 ROT='0',
 VER='2',
 PACK_TYPE='TH2',
 LOCATION='DB12',
 CDS_LIB='pure_quanta',
 CDS_PART_NAME='TDR_3P_TH2-EMPTY,N_A',
 PART_NUMBER='N_A',
 PRIM_FILE='./archive_libs/logical/tdr_3p/chips/chips.prt';

PART_NAME
 DB13 'TDR_3P_TH2-EMPTY,N_A':;

SECTION_NUMBER 1
 '@T6G_MB_LIB.T6G(SCH_1):PAGE265_I8@PURE_QUANTA.TDR_3P(CHIPS)':
 C_PATH='@t6g_mb_lib.t6g(sch_1):page265_i8@pure_quanta.tdr_3p(chips)',
 P_PATH='@t6g_mb_lib.t6g(sch_1):page260_i8@pure_quanta.tdr_3p(chips)',
 PATH='I8',
 DRAWING='@T6G_MB_LIB.T6G(SCH_1):PAGE265',
 MATERIAL='EMPTY',
 PHYS_PAGE='260',
 XY='(-8675,3250)',
 ROT='0',
 VER='2',
 PACK_TYPE='TH2',
 LOCATION='DB13',
 CDS_LIB='pure_quanta',
 CDS_PART_NAME='TDR_3P_TH2-EMPTY,N_A',
 PART_NUMBER='N_A',
 PRIM_FILE='./archive_libs/logical/tdr_3p/chips/chips.prt';

PART_NAME
 DB14 'TDR_3P_TH2-EMPTY,N_A':;

SECTION_NUMBER 1
 '@T6G_MB_LIB.T6G(SCH_1):PAGE265_I5@PURE_QUANTA.TDR_3P(CHIPS)':
 C_PATH='@t6g_mb_lib.t6g(sch_1):page265_i5@pure_quanta.tdr_3p(chips)',
 P_PATH='@t6g_mb_lib.t6g(sch_1):page260_i5@pure_quanta.tdr_3p(chips)',
 PATH='I5',
 DRAWING='@T6G_MB_LIB.T6G(SCH_1):PAGE265',
 MATERIAL='EMPTY',
 PHYS_PAGE='260',
 XY='(-8675,2725)',
 ROT='0',
 VER='2',
 PACK_TYPE='TH2',
 LOCATION='DB14',
 CDS_LIB='pure_quanta',
 CDS_PART_NAME='TDR_3P_TH2-EMPTY,N_A',
 PART_NUMBER='N_A',
 PRIM_FILE='./archive_libs/logical/tdr_3p/chips/chips.prt';

PART_NAME
 DB15 'TDR_3P_TH2-EMPTY,N_A':;

SECTION_NUMBER 1
 '@T6G_MB_LIB.T6G(SCH_1):PAGE265_I22@PURE_QUANTA.TDR_3P(CHIPS)':
 C_PATH='@t6g_mb_lib.t6g(sch_1):page265_i22@pure_quanta.tdr_3p(chips)',
 P_PATH='@t6g_mb_lib.t6g(sch_1):page260_i22@pure_quanta.tdr_3p(chips)',
 PATH='I22',
 DRAWING='@T6G_MB_LIB.T6G(SCH_1):PAGE265',
 MATERIAL='EMPTY',
 PHYS_PAGE='260',
 XY='(-6975,3250)',
 ROT='0',
 VER='2',
 PACK_TYPE='TH2',
 LOCATION='DB15',
 CDS_LIB='pure_quanta',
 CDS_PART_NAME='TDR_3P_TH2-EMPTY,N_A',
 PART_NUMBER='N_A',
 PRIM_FILE='./archive_libs/logical/tdr_3p/chips/chips.prt';

PART_NAME
 DB16 'TDR_3P_TH2-EMPTY,N_A':;

SECTION_NUMBER 1
 '@T6G_MB_LIB.T6G(SCH_1):PAGE265_I20@PURE_QUANTA.TDR_3P(CHIPS)':
 C_PATH='@t6g_mb_lib.t6g(sch_1):page265_i20@pure_quanta.tdr_3p(chips)',
 P_PATH='@t6g_mb_lib.t6g(sch_1):page260_i20@pure_quanta.tdr_3p(chips)',
 PATH='I20',
 DRAWING='@T6G_MB_LIB.T6G(SCH_1):PAGE265',
 MATERIAL='EMPTY',
 PHYS_PAGE='260',
 XY='(-6975,2725)',
 ROT='0',
 VER='2',
 PACK_TYPE='TH2',
 LOCATION='DB16',
 CDS_LIB='pure_quanta',
 CDS_PART_NAME='TDR_3P_TH2-EMPTY,N_A',
 PART_NUMBER='N_A',
 PRIM_FILE='./archive_libs/logical/tdr_3p/chips/chips.prt';

PART_NAME
 FS1 'Q_FUSE_SMLF-20A/125V,IC,DKK00XFU000':;

SECTION_NUMBER 1
 '@T6G_MB_LIB.T6G(SCH_1):PAGE372_I6@PURE_QUANTA.Q_FUSE(CHIPS)':
 C_PATH='@t6g_mb_lib.t6g(sch_1):page372_i6@pure_quanta.q_fuse(chips)',
 P_PATH='@t6g_mb_lib.t6g(sch_1):page268_i6@pure_quanta.q_fuse(chips)',
 PATH='I6',
 DRAWING='@T6G_MB_LIB.T6G(SCH_1):PAGE372',
 MATERIAL='IC',
 PHYS_PAGE='268',
 XY='(-8075,5875)',
 ROT='3',
 VER='1',
 PACK_TYPE='SMLF',
 LOCATION='FS1',
 CDS_LIB='pure_quanta',
 CDS_PART_NAME='Q_FUSE_SMLF-20A/125V,IC,DKK00XFU000',
 PART_NUMBER='DKK00XFU000',
 VALUE='20A/125V',
 PRIM_FILE='./archive_libs/logical/q_fuse/chips/chips.prt';

PART_NAME
 H2 'HOLE_TH-EMPTY,HOLE1226':;

SECTION_NUMBER 1
 '@T6G_MB_LIB.T6G(SCH_1):PAGE212_I170@PURE_QUANTA.HOLE(CHIPS)':
 C_PATH='@t6g_mb_lib.t6g(sch_1):page212_i170@pure_quanta.hole(chips)',
 P_PATH='@t6g_mb_lib.t6g(sch_1):page230_i170@pure_quanta.hole(chips)',
 PATH='I170',
 DRAWING='@T6G_MB_LIB.T6G(SCH_1):PAGE212',
 MATERIAL='EMPTY',
 PHYS_PAGE='230',
 XY='(-8775,2175)',
 ROT='0',
 VER='1',
 PACK_TYPE='TH',
 LOCATION='H2',
 CDS_LIB='pure_quanta',
 CDS_PART_NAME='HOLE_TH-EMPTY,HOLE1226',
 PART_NUMBER='HOLE1226',
 PRIM_FILE='./archive_libs/logical/hole/chips/chips.prt';

PART_NAME
 H3 'HOLE_TH-EMPTY,HOLE1226':;

SECTION_NUMBER 1
 '@T6G_MB_LIB.T6G(SCH_1):PAGE212_I195@PURE_QUANTA.HOLE(CHIPS)':
 C_PATH='@t6g_mb_lib.t6g(sch_1):page212_i195@pure_quanta.hole(chips)',
 P_PATH='@t6g_mb_lib.t6g(sch_1):page230_i195@pure_quanta.hole(chips)',
 PATH='I195',
 DRAWING='@T6G_MB_LIB.T6G(SCH_1):PAGE212',
 MATERIAL='EMPTY',
 PHYS_PAGE='230',
 XY='(-7125,2125)',
 ROT='0',
 VER='1',
 PACK_TYPE='TH',
 LOCATION='H3',
 CDS_LIB='pure_quanta',
 CDS_PART_NAME='HOLE_TH-EMPTY,HOLE1226',
 PART_NUMBER='HOLE1226',
 PRIM_FILE='./archive_libs/logical/hole/chips/chips.prt';

PART_NAME
 H5 'HOLE_TH-EMPTY,HOLE1226':;

SECTION_NUMBER 1
 '@T6G_MB_LIB.T6G(SCH_1):PAGE212_I193@PURE_QUANTA.HOLE(CHIPS)':
 C_PATH='@t6g_mb_lib.t6g(sch_1):page212_i193@pure_quanta.hole(chips)',
 P_PATH='@t6g_mb_lib.t6g(sch_1):page230_i193@pure_quanta.hole(chips)',
 PATH='I193',
 DRAWING='@T6G_MB_LIB.T6G(SCH_1):PAGE212',
 MATERIAL='EMPTY',
 PHYS_PAGE='230',
 XY='(-6575,2125)',
 ROT='0',
 VER='1',
 PACK_TYPE='TH',
 LOCATION='H5',
 CDS_LIB='pure_quanta',
 CDS_PART_NAME='HOLE_TH-EMPTY,HOLE1226',
 PART_NUMBER='HOLE1226',
 PRIM_FILE='./archive_libs/logical/hole/chips/chips.prt';

PART_NAME
 H8 'HOLE_TH-EMPTY,HOLE1226':;

SECTION_NUMBER 1
 '@T6G_MB_LIB.T6G(SCH_1):PAGE212_I176@PURE_QUANTA.HOLE(CHIPS)':
 C_PATH='@t6g_mb_lib.t6g(sch_1):page212_i176@pure_quanta.hole(chips)',
 P_PATH='@t6g_mb_lib.t6g(sch_1):page230_i176@pure_quanta.hole(chips)',
 PATH='I176',
 DRAWING='@T6G_MB_LIB.T6G(SCH_1):PAGE212',
 MATERIAL='EMPTY',
 PHYS_PAGE='230',
 XY='(-8175,2125)',
 ROT='0',
 VER='1',
 PACK_TYPE='TH',
 LOCATION='H8',
 CDS_LIB='pure_quanta',
 CDS_PART_NAME='HOLE_TH-EMPTY,HOLE1226',
 PART_NUMBER='HOLE1226',
 PRIM_FILE='./archive_libs/logical/hole/chips/chips.prt';

PART_NAME
 H10 'HOLE_TH-EMPTY,HOLE1226':;

SECTION_NUMBER 1
 '@T6G_MB_LIB.T6G(SCH_1):PAGE212_I178@PURE_QUANTA.HOLE(CHIPS)':
 C_PATH='@t6g_mb_lib.t6g(sch_1):page212_i178@pure_quanta.hole(chips)',
 P_PATH='@t6g_mb_lib.t6g(sch_1):page230_i178@pure_quanta.hole(chips)',
 PATH='I178',
 DRAWING='@T6G_MB_LIB.T6G(SCH_1):PAGE212',
 MATERIAL='EMPTY',
 PHYS_PAGE='230',
 XY='(-7675,2100)',
 ROT='0',
 VER='1',
 PACK_TYPE='TH',
 LOCATION='H10',
 CDS_LIB='pure_quanta',
 CDS_PART_NAME='HOLE_TH-EMPTY,HOLE1226',
 PART_NUMBER='HOLE1226',
 PRIM_FILE='./archive_libs/logical/hole/chips/chips.prt';

PART_NAME
 H11 'HOLE_TH-EMPTY,HOLE1226':;

SECTION_NUMBER 1
 '@T6G_MB_LIB.T6G(SCH_1):PAGE212_I87@PURE_QUANTA.HOLE(CHIPS)':
 C_PATH='@t6g_mb_lib.t6g(sch_1):page212_i87@pure_quanta.hole(chips)',
 P_PATH='@t6g_mb_lib.t6g(sch_1):page230_i87@pure_quanta.hole(chips)',
 PATH='I87',
 DRAWING='@T6G_MB_LIB.T6G(SCH_1):PAGE212',
 MATERIAL='EMPTY',
 PHYS_PAGE='230',
 XY='(-5050,2775)',
 ROT='0',
 VER='1',
 PACK_TYPE='TH',
 LOCATION='H11',
 CDS_LIB='pure_quanta',
 CDS_PART_NAME='HOLE_TH-EMPTY,HOLE1226',
 PART_NUMBER='HOLE1226',
 PRIM_FILE='./archive_libs/logical/hole/chips/chips.prt';

PART_NAME
 H12 'HOLE_TH-EMPTY,HOLE1226':;

SECTION_NUMBER 1
 '@T6G_MB_LIB.T6G(SCH_1):PAGE212_I187@PURE_QUANTA.HOLE(CHIPS)':
 C_PATH='@t6g_mb_lib.t6g(sch_1):page212_i187@pure_quanta.hole(chips)',
 P_PATH='@t6g_mb_lib.t6g(sch_1):page230_i187@pure_quanta.hole(chips)',
 PATH='I187',
 DRAWING='@T6G_MB_LIB.T6G(SCH_1):PAGE212',
 MATERIAL='EMPTY',
 PHYS_PAGE='230',
 XY='(-6025,2125)',
 ROT='0',
 VER='1',
 PACK_TYPE='TH',
 LOCATION='H12',
 CDS_LIB='pure_quanta',
 CDS_PART_NAME='HOLE_TH-EMPTY,HOLE1226',
 PART_NUMBER='HOLE1226',
 PRIM_FILE='./archive_libs/logical/hole/chips/chips.prt';

PART_NAME
 H13 'HOLE_TH-EMPTY,HOLE1226':;

SECTION_NUMBER 1
 '@T6G_MB_LIB.T6G(SCH_1):PAGE212_I55@PURE_QUANTA.HOLE(CHIPS)':
 C_PATH='@t6g_mb_lib.t6g(sch_1):page212_i55@pure_quanta.hole(chips)',
 P_PATH='@t6g_mb_lib.t6g(sch_1):page230_i55@pure_quanta.hole(chips)',
 PATH='I55',
 DRAWING='@T6G_MB_LIB.T6G(SCH_1):PAGE212',
 MATERIAL='EMPTY',
 PHYS_PAGE='230',
 XY='(-5575,2775)',
 ROT='0',
 VER='1',
 PACK_TYPE='TH',
 LOCATION='H13',
 CDS_LIB='pure_quanta',
 CDS_PART_NAME='HOLE_TH-EMPTY,HOLE1226',
 PART_NUMBER='HOLE1226',
 PRIM_FILE='./archive_libs/logical/hole/chips/chips.prt';

PART_NAME
 H21 'HOLE_TH-EMPTY,HOLE1226':;

SECTION_NUMBER 1
 '@T6G_MB_LIB.T6G(SCH_1):PAGE212_I5@PURE_QUANTA.HOLE(CHIPS)':
 C_PATH='@t6g_mb_lib.t6g(sch_1):page212_i5@pure_quanta.hole(chips)',
 P_PATH='@t6g_mb_lib.t6g(sch_1):page230_i5@pure_quanta.hole(chips)',
 PATH='I5',
 DRAWING='@T6G_MB_LIB.T6G(SCH_1):PAGE212',
 MATERIAL='EMPTY',
 PHYS_PAGE='230',
 XY='(-8850,3400)',
 ROT='0',
 VER='1',
 PACK_TYPE='TH',
 LOCATION='H21',
 CDS_LIB='pure_quanta',
 CDS_PART_NAME='HOLE_TH-EMPTY,HOLE1226',
 PART_NUMBER='HOLE1226',
 PRIM_FILE='./archive_libs/logical/hole/chips/chips.prt';

PART_NAME
 H22 'HOLE_TH-EMPTY,HOLE1226':;

SECTION_NUMBER 1
 '@T6G_MB_LIB.T6G(SCH_1):PAGE212_I26@PURE_QUANTA.HOLE(CHIPS)':
 C_PATH='@t6g_mb_lib.t6g(sch_1):page212_i26@pure_quanta.hole(chips)',
 P_PATH='@t6g_mb_lib.t6g(sch_1):page230_i26@pure_quanta.hole(chips)',
 PATH='I26',
 DRAWING='@T6G_MB_LIB.T6G(SCH_1):PAGE212',
 MATERIAL='EMPTY',
 PHYS_PAGE='230',
 XY='(-8250,2800)',
 ROT='0',
 VER='1',
 PACK_TYPE='TH',
 LOCATION='H22',
 CDS_LIB='pure_quanta',
 CDS_PART_NAME='HOLE_TH-EMPTY,HOLE1226',
 PART_NUMBER='HOLE1226',
 PRIM_FILE='./archive_libs/logical/hole/chips/chips.prt';

PART_NAME
 H27 'HOLE_TH-EMPTY,DUMMY50':;

SECTION_NUMBER 1
 '@T6G_MB_LIB.T6G(SCH_1):PAGE212_I41@PURE_QUANTA.HOLE(CHIPS)':
 C_PATH='@t6g_mb_lib.t6g(sch_1):page212_i41@pure_quanta.hole(chips)',
 P_PATH='@t6g_mb_lib.t6g(sch_1):page230_i41@pure_quanta.hole(chips)',
 PATH='I41',
 DRAWING='@T6G_MB_LIB.T6G(SCH_1):PAGE212',
 MATERIAL='EMPTY',
 PHYS_PAGE='230',
 XY='(-6225,4275)',
 ROT='0',
 VER='1',
 PACK_TYPE='TH',
 LOCATION='H27',
 CDS_LIB='pure_quanta',
 CDS_PART_NAME='HOLE_TH-EMPTY,DUMMY50',
 PART_NUMBER='DUMMY50',
 PRIM_FILE='./archive_libs/logical/hole/chips/chips.prt';

PART_NAME
 H28 'HOLE_TH-EMPTY,DUMMY50':;

SECTION_NUMBER 1
 '@T6G_MB_LIB.T6G(SCH_1):PAGE212_I50@PURE_QUANTA.HOLE(CHIPS)':
 C_PATH='@t6g_mb_lib.t6g(sch_1):page212_i50@pure_quanta.hole(chips)',
 P_PATH='@t6g_mb_lib.t6g(sch_1):page230_i50@pure_quanta.hole(chips)',
 PATH='I50',
 DRAWING='@T6G_MB_LIB.T6G(SCH_1):PAGE212',
 MATERIAL='EMPTY',
 PHYS_PAGE='230',
 XY='(-5725,4275)',
 ROT='0',
 VER='1',
 PACK_TYPE='TH',
 LOCATION='H28',
 CDS_LIB='pure_quanta',
 CDS_PART_NAME='HOLE_TH-EMPTY,DUMMY50',
 PART_NUMBER='DUMMY50',
 PRIM_FILE='./archive_libs/logical/hole/chips/chips.prt';

PART_NAME
 H29 'HOLE_TH-EMPTY,DUMMY50':;

SECTION_NUMBER 1
 '@T6G_MB_LIB.T6G(SCH_1):PAGE212_I51@PURE_QUANTA.HOLE(CHIPS)':
 C_PATH='@t6g_mb_lib.t6g(sch_1):page212_i51@pure_quanta.hole(chips)',
 P_PATH='@t6g_mb_lib.t6g(sch_1):page230_i51@pure_quanta.hole(chips)',
 PATH='I51',
 DRAWING='@T6G_MB_LIB.T6G(SCH_1):PAGE212',
 MATERIAL='EMPTY',
 PHYS_PAGE='230',
 XY='(-5200,4275)',
 ROT='0',
 VER='1',
 PACK_TYPE='TH',
 LOCATION='H29',
 CDS_LIB='pure_quanta',
 CDS_PART_NAME='HOLE_TH-EMPTY,DUMMY50',
 PART_NUMBER='DUMMY50',
 PRIM_FILE='./archive_libs/logical/hole/chips/chips.prt';

PART_NAME
 H30 'HOLE_TH-EMPTY,DUMMY50':;

SECTION_NUMBER 1
 '@T6G_MB_LIB.T6G(SCH_1):PAGE212_I56@PURE_QUANTA.HOLE(CHIPS)':
 C_PATH='@t6g_mb_lib.t6g(sch_1):page212_i56@pure_quanta.hole(chips)',
 P_PATH='@t6g_mb_lib.t6g(sch_1):page230_i56@pure_quanta.hole(chips)',
 PATH='I56',
 DRAWING='@T6G_MB_LIB.T6G(SCH_1):PAGE212',
 MATERIAL='EMPTY',
 PHYS_PAGE='230',
 XY='(-4700,4275)',
 ROT='0',
 VER='1',
 PACK_TYPE='TH',
 LOCATION='H30',
 CDS_LIB='pure_quanta',
 CDS_PART_NAME='HOLE_TH-EMPTY,DUMMY50',
 PART_NUMBER='DUMMY50',
 PRIM_FILE='./archive_libs/logical/hole/chips/chips.prt';

PART_NAME
 H31 'HOLE_TH-EMPTY,HOLE1248':;

SECTION_NUMBER 1
 '@T6G_MB_LIB.T6G(SCH_1):PAGE212_I91@PURE_QUANTA.HOLE(CHIPS)':
 C_PATH='@t6g_mb_lib.t6g(sch_1):page212_i91@pure_quanta.hole(chips)',
 P_PATH='@t6g_mb_lib.t6g(sch_1):page230_i91@pure_quanta.hole(chips)',
 PATH='I91',
 DRAWING='@T6G_MB_LIB.T6G(SCH_1):PAGE212',
 MATERIAL='EMPTY',
 PHYS_PAGE='230',
 XY='(-3950,3275)',
 ROT='0',
 VER='1',
 PACK_TYPE='TH',
 LOCATION='H31',
 CDS_LIB='pure_quanta',
 CDS_PART_NAME='HOLE_TH-EMPTY,HOLE1248',
 PART_NUMBER='HOLE1248',
 PRIM_FILE='./archive_libs/logical/hole/chips/chips.prt';

PART_NAME
 H32 'HOLE_TH-EMPTY,HOLE1248':;

SECTION_NUMBER 1
 '@T6G_MB_LIB.T6G(SCH_1):PAGE212_I93@PURE_QUANTA.HOLE(CHIPS)':
 C_PATH='@t6g_mb_lib.t6g(sch_1):page212_i93@pure_quanta.hole(chips)',
 P_PATH='@t6g_mb_lib.t6g(sch_1):page230_i93@pure_quanta.hole(chips)',
 PATH='I93',
 DRAWING='@T6G_MB_LIB.T6G(SCH_1):PAGE212',
 MATERIAL='EMPTY',
 PHYS_PAGE='230',
 XY='(-3450,3275)',
 ROT='0',
 VER='1',
 PACK_TYPE='TH',
 LOCATION='H32',
 CDS_LIB='pure_quanta',
 CDS_PART_NAME='HOLE_TH-EMPTY,HOLE1248',
 PART_NUMBER='HOLE1248',
 PRIM_FILE='./archive_libs/logical/hole/chips/chips.prt';

PART_NAME
 H33 'HOLE_TH-EMPTY,HOLE1226':;

SECTION_NUMBER 1
 '@T6G_MB_LIB.T6G(SCH_1):PAGE212_I36@PURE_QUANTA.HOLE(CHIPS)':
 C_PATH='@t6g_mb_lib.t6g(sch_1):page212_i36@pure_quanta.hole(chips)',
 P_PATH='@t6g_mb_lib.t6g(sch_1):page230_i36@pure_quanta.hole(chips)',
 PATH='I36',
 DRAWING='@T6G_MB_LIB.T6G(SCH_1):PAGE212',
 MATERIAL='EMPTY',
 PHYS_PAGE='230',
 XY='(-7750,3400)',
 ROT='0',
 VER='1',
 PACK_TYPE='TH',
 LOCATION='H33',
 CDS_LIB='pure_quanta',
 CDS_PART_NAME='HOLE_TH-EMPTY,HOLE1226',
 PART_NUMBER='HOLE1226',
 PRIM_FILE='./archive_libs/logical/hole/chips/chips.prt';

PART_NAME
 H34 'HOLE_TH-EMPTY,HOLE1226':;

SECTION_NUMBER 1
 '@T6G_MB_LIB.T6G(SCH_1):PAGE212_I31@PURE_QUANTA.HOLE(CHIPS)':
 C_PATH='@t6g_mb_lib.t6g(sch_1):page212_i31@pure_quanta.hole(chips)',
 P_PATH='@t6g_mb_lib.t6g(sch_1):page230_i31@pure_quanta.hole(chips)',
 PATH='I31',
 DRAWING='@T6G_MB_LIB.T6G(SCH_1):PAGE212',
 MATERIAL='EMPTY',
 PHYS_PAGE='230',
 XY='(-7150,2800)',
 ROT='0',
 VER='1',
 PACK_TYPE='TH',
 LOCATION='H34',
 CDS_LIB='pure_quanta',
 CDS_PART_NAME='HOLE_TH-EMPTY,HOLE1226',
 PART_NUMBER='HOLE1226',
 PRIM_FILE='./archive_libs/logical/hole/chips/chips.prt';

PART_NAME
 H37 'HOLE_TH-EMPTY,HOLE1226':;

SECTION_NUMBER 1
 '@T6G_MB_LIB.T6G(SCH_1):PAGE212_I38@PURE_QUANTA.HOLE(CHIPS)':
 C_PATH='@t6g_mb_lib.t6g(sch_1):page212_i38@pure_quanta.hole(chips)',
 P_PATH='@t6g_mb_lib.t6g(sch_1):page230_i38@pure_quanta.hole(chips)',
 PATH='I38',
 DRAWING='@T6G_MB_LIB.T6G(SCH_1):PAGE212',
 MATERIAL='EMPTY',
 PHYS_PAGE='230',
 XY='(-7175,3400)',
 ROT='0',
 VER='1',
 PACK_TYPE='TH',
 LOCATION='H37',
 CDS_LIB='pure_quanta',
 CDS_PART_NAME='HOLE_TH-EMPTY,HOLE1226',
 PART_NUMBER='HOLE1226',
 PRIM_FILE='./archive_libs/logical/hole/chips/chips.prt';

PART_NAME
 H38 'HOLE_TH-EMPTY,HOLE1226':;

SECTION_NUMBER 1
 '@T6G_MB_LIB.T6G(SCH_1):PAGE212_I33@PURE_QUANTA.HOLE(CHIPS)':
 C_PATH='@t6g_mb_lib.t6g(sch_1):page212_i33@pure_quanta.hole(chips)',
 P_PATH='@t6g_mb_lib.t6g(sch_1):page230_i33@pure_quanta.hole(chips)',
 PATH='I33',
 DRAWING='@T6G_MB_LIB.T6G(SCH_1):PAGE212',
 MATERIAL='EMPTY',
 PHYS_PAGE='230',
 XY='(-6575,2800)',
 ROT='0',
 VER='1',
 PACK_TYPE='TH',
 LOCATION='H38',
 CDS_LIB='pure_quanta',
 CDS_PART_NAME='HOLE_TH-EMPTY,HOLE1226',
 PART_NUMBER='HOLE1226',
 PRIM_FILE='./archive_libs/logical/hole/chips/chips.prt';

PART_NAME
 H43 'HOLE_TH-EMPTY,HOLE1226':;

SECTION_NUMBER 1
 '@T6G_MB_LIB.T6G(SCH_1):PAGE212_I40@PURE_QUANTA.HOLE(CHIPS)':
 C_PATH='@t6g_mb_lib.t6g(sch_1):page212_i40@pure_quanta.hole(chips)',
 P_PATH='@t6g_mb_lib.t6g(sch_1):page230_i40@pure_quanta.hole(chips)',
 PATH='I40',
 DRAWING='@T6G_MB_LIB.T6G(SCH_1):PAGE212',
 MATERIAL='EMPTY',
 PHYS_PAGE='230',
 XY='(-6675,3400)',
 ROT='0',
 VER='1',
 PACK_TYPE='TH',
 LOCATION='H43',
 CDS_LIB='pure_quanta',
 CDS_PART_NAME='HOLE_TH-EMPTY,HOLE1226',
 PART_NUMBER='HOLE1226',
 PRIM_FILE='./archive_libs/logical/hole/chips/chips.prt';

PART_NAME
 H44 'HOLE_TH-EMPTY,HOLE1226':;

SECTION_NUMBER 1
 '@T6G_MB_LIB.T6G(SCH_1):PAGE212_I45@PURE_QUANTA.HOLE(CHIPS)':
 C_PATH='@t6g_mb_lib.t6g(sch_1):page212_i45@pure_quanta.hole(chips)',
 P_PATH='@t6g_mb_lib.t6g(sch_1):page230_i45@pure_quanta.hole(chips)',
 PATH='I45',
 DRAWING='@T6G_MB_LIB.T6G(SCH_1):PAGE212',
 MATERIAL='EMPTY',
 PHYS_PAGE='230',
 XY='(-6075,2800)',
 ROT='0',
 VER='1',
 PACK_TYPE='TH',
 LOCATION='H44',
 CDS_LIB='pure_quanta',
 CDS_PART_NAME='HOLE_TH-EMPTY,HOLE1226',
 PART_NUMBER='HOLE1226',
 PRIM_FILE='./archive_libs/logical/hole/chips/chips.prt';

PART_NAME
 H49 'HOLE_TH-EMPTY,HOLE1226':;

SECTION_NUMBER 1
 '@T6G_MB_LIB.T6G(SCH_1):PAGE212_I46@PURE_QUANTA.HOLE(CHIPS)':
 C_PATH='@t6g_mb_lib.t6g(sch_1):page212_i46@pure_quanta.hole(chips)',
 P_PATH='@t6g_mb_lib.t6g(sch_1):page230_i46@pure_quanta.hole(chips)',
 PATH='I46',
 DRAWING='@T6G_MB_LIB.T6G(SCH_1):PAGE212',
 MATERIAL='EMPTY',
 PHYS_PAGE='230',
 XY='(-6125,3400)',
 ROT='0',
 VER='1',
 PACK_TYPE='TH',
 LOCATION='H49',
 CDS_LIB='pure_quanta',
 CDS_PART_NAME='HOLE_TH-EMPTY,HOLE1226',
 PART_NUMBER='HOLE1226',
 PRIM_FILE='./archive_libs/logical/hole/chips/chips.prt';

PART_NAME
 H50 'HOLE_TH-EMPTY,HOLE1226':;

SECTION_NUMBER 1
 '@T6G_MB_LIB.T6G(SCH_1):PAGE212_I49@PURE_QUANTA.HOLE(CHIPS)':
 C_PATH='@t6g_mb_lib.t6g(sch_1):page212_i49@pure_quanta.hole(chips)',
 P_PATH='@t6g_mb_lib.t6g(sch_1):page230_i49@pure_quanta.hole(chips)',
 PATH='I49',
 DRAWING='@T6G_MB_LIB.T6G(SCH_1):PAGE212',
 MATERIAL='EMPTY',
 PHYS_PAGE='230',
 XY='(-5600,3400)',
 ROT='0',
 VER='1',
 PACK_TYPE='TH',
 LOCATION='H50',
 CDS_LIB='pure_quanta',
 CDS_PART_NAME='HOLE_TH-EMPTY,HOLE1226',
 PART_NUMBER='HOLE1226',
 PRIM_FILE='./archive_libs/logical/hole/chips/chips.prt';

PART_NAME
 H53 'HOLE_TH-EMPTY,HOLE1226':;

SECTION_NUMBER 1
 '@T6G_MB_LIB.T6G(SCH_1):PAGE212_I4@PURE_QUANTA.HOLE(CHIPS)':
 C_PATH='@t6g_mb_lib.t6g(sch_1):page212_i4@pure_quanta.hole(chips)',
 P_PATH='@t6g_mb_lib.t6g(sch_1):page230_i4@pure_quanta.hole(chips)',
 PATH='I4',
 DRAWING='@T6G_MB_LIB.T6G(SCH_1):PAGE212',
 MATERIAL='EMPTY',
 PHYS_PAGE='230',
 XY='(-8875,2825)',
 ROT='0',
 VER='1',
 PACK_TYPE='TH',
 LOCATION='H53',
 CDS_LIB='pure_quanta',
 CDS_PART_NAME='HOLE_TH-EMPTY,HOLE1226',
 PART_NUMBER='HOLE1226',
 PRIM_FILE='./archive_libs/logical/hole/chips/chips.prt';

PART_NAME
 H54 'HOLE_TH-EMPTY,HOLE1226':;

SECTION_NUMBER 1
 '@T6G_MB_LIB.T6G(SCH_1):PAGE212_I52@PURE_QUANTA.HOLE(CHIPS)':
 C_PATH='@t6g_mb_lib.t6g(sch_1):page212_i52@pure_quanta.hole(chips)',
 P_PATH='@t6g_mb_lib.t6g(sch_1):page230_i52@pure_quanta.hole(chips)',
 PATH='I52',
 DRAWING='@T6G_MB_LIB.T6G(SCH_1):PAGE212',
 MATERIAL='EMPTY',
 PHYS_PAGE='230',
 XY='(-5025,3400)',
 ROT='0',
 VER='1',
 PACK_TYPE='TH',
 LOCATION='H54',
 CDS_LIB='pure_quanta',
 CDS_PART_NAME='HOLE_TH-EMPTY,HOLE1226',
 PART_NUMBER='HOLE1226',
 PRIM_FILE='./archive_libs/logical/hole/chips/chips.prt';

PART_NAME
 H74 'HOLE_TH-EMPTY,HOLE1247':;

SECTION_NUMBER 1
 '@T6G_MB_LIB.T6G(SCH_1):PAGE212_I88@PURE_QUANTA.HOLE(CHIPS)':
 C_PATH='@t6g_mb_lib.t6g(sch_1):page212_i88@pure_quanta.hole(chips)',
 P_PATH='@t6g_mb_lib.t6g(sch_1):page230_i88@pure_quanta.hole(chips)',
 PATH='I88',
 DRAWING='@T6G_MB_LIB.T6G(SCH_1):PAGE212',
 MATERIAL='EMPTY',
 PHYS_PAGE='230',
 XY='(-4000,4325)',
 ROT='0',
 VER='1',
 PACK_TYPE='TH',
 LOCATION='H74',
 CDS_LIB='pure_quanta',
 CDS_PART_NAME='HOLE_TH-EMPTY,HOLE1247',
 PART_NUMBER='HOLE1247',
 PRIM_FILE='./archive_libs/logical/hole/chips/chips.prt';

PART_NAME
 H75 'HOLE_TH-EMPTY,HOLE1247':;

SECTION_NUMBER 1
 '@T6G_MB_LIB.T6G(SCH_1):PAGE212_I89@PURE_QUANTA.HOLE(CHIPS)':
 C_PATH='@t6g_mb_lib.t6g(sch_1):page212_i89@pure_quanta.hole(chips)',
 P_PATH='@t6g_mb_lib.t6g(sch_1):page230_i89@pure_quanta.hole(chips)',
 PATH='I89',
 DRAWING='@T6G_MB_LIB.T6G(SCH_1):PAGE212',
 MATERIAL='EMPTY',
 PHYS_PAGE='230',
 XY='(-3500,4325)',
 ROT='0',
 VER='1',
 PACK_TYPE='TH',
 LOCATION='H75',
 CDS_LIB='pure_quanta',
 CDS_PART_NAME='HOLE_TH-EMPTY,HOLE1247',
 PART_NUMBER='HOLE1247',
 PRIM_FILE='./archive_libs/logical/hole/chips/chips.prt';

PART_NAME
 H76 'HOLE_TH-EMPTY,HOLE1187':;

SECTION_NUMBER 1
 '@T6G_MB_LIB.T6G(SCH_1):PAGE212_I10@PURE_QUANTA.HOLE(CHIPS)':
 C_PATH='@t6g_mb_lib.t6g(sch_1):page212_i10@pure_quanta.hole(chips)',
 P_PATH='@t6g_mb_lib.t6g(sch_1):page230_i10@pure_quanta.hole(chips)',
 PATH='I10',
 DRAWING='@T6G_MB_LIB.T6G(SCH_1):PAGE212',
 MATERIAL='EMPTY',
 PHYS_PAGE='230',
 XY='(-8725,4225)',
 ROT='0',
 VER='1',
 PACK_TYPE='TH',
 LOCATION='H76',
 CDS_LIB='pure_quanta',
 CDS_PART_NAME='HOLE_TH-EMPTY,HOLE1187',
 PART_NUMBER='HOLE1187',
 PRIM_FILE='./archive_libs/logical/hole/chips/chips.prt';

PART_NAME
 H77 'HOLE_TH-EMPTY,HOLE1187':;

SECTION_NUMBER 1
 '@T6G_MB_LIB.T6G(SCH_1):PAGE212_I12@PURE_QUANTA.HOLE(CHIPS)':
 C_PATH='@t6g_mb_lib.t6g(sch_1):page212_i12@pure_quanta.hole(chips)',
 P_PATH='@t6g_mb_lib.t6g(sch_1):page230_i12@pure_quanta.hole(chips)',
 PATH='I12',
 DRAWING='@T6G_MB_LIB.T6G(SCH_1):PAGE212',
 MATERIAL='EMPTY',
 PHYS_PAGE='230',
 XY='(-8175,4225)',
 ROT='0',
 VER='1',
 PACK_TYPE='TH',
 LOCATION='H77',
 CDS_LIB='pure_quanta',
 CDS_PART_NAME='HOLE_TH-EMPTY,HOLE1187',
 PART_NUMBER='HOLE1187',
 PRIM_FILE='./archive_libs/logical/hole/chips/chips.prt';

PART_NAME
 H86 'HOLE_TH-EMPTY,HOLE596':;

SECTION_NUMBER 1
 '@T6G_MB_LIB.T6G(SCH_1):PAGE212_I125@PURE_QUANTA.HOLE(CHIPS)':
 C_PATH='@t6g_mb_lib.t6g(sch_1):page212_i125@pure_quanta.hole(chips)',
 P_PATH='@t6g_mb_lib.t6g(sch_1):page230_i125@pure_quanta.hole(chips)',
 PATH='I125',
 DRAWING='@T6G_MB_LIB.T6G(SCH_1):PAGE212',
 MATERIAL='EMPTY',
 PHYS_PAGE='230',
 XY='(-8800,5875)',
 ROT='0',
 VER='1',
 PACK_TYPE='TH',
 LOCATION='H86',
 CDS_LIB='pure_quanta',
 CDS_PART_NAME='HOLE_TH-EMPTY,HOLE596',
 PART_NUMBER='HOLE596',
 PRIM_FILE='./archive_libs/logical/hole/chips/chips.prt';

PART_NAME
 H87 'HOLE_TH-EMPTY,HOLE596':;

SECTION_NUMBER 1
 '@T6G_MB_LIB.T6G(SCH_1):PAGE212_I127@PURE_QUANTA.HOLE(CHIPS)':
 C_PATH='@t6g_mb_lib.t6g(sch_1):page212_i127@pure_quanta.hole(chips)',
 P_PATH='@t6g_mb_lib.t6g(sch_1):page230_i127@pure_quanta.hole(chips)',
 PATH='I127',
 DRAWING='@T6G_MB_LIB.T6G(SCH_1):PAGE212',
 MATERIAL='EMPTY',
 PHYS_PAGE='230',
 XY='(-8775,5325)',
 ROT='0',
 VER='1',
 PACK_TYPE='TH',
 LOCATION='H87',
 CDS_LIB='pure_quanta',
 CDS_PART_NAME='HOLE_TH-EMPTY,HOLE596',
 PART_NUMBER='HOLE596',
 PRIM_FILE='./archive_libs/logical/hole/chips/chips.prt';

PART_NAME
 H88 'HOLE_TH-EMPTY,HOLE596':;

SECTION_NUMBER 1
 '@T6G_MB_LIB.T6G(SCH_1):PAGE212_I129@PURE_QUANTA.HOLE(CHIPS)':
 C_PATH='@t6g_mb_lib.t6g(sch_1):page212_i129@pure_quanta.hole(chips)',
 P_PATH='@t6g_mb_lib.t6g(sch_1):page230_i129@pure_quanta.hole(chips)',
 PATH='I129',
 DRAWING='@T6G_MB_LIB.T6G(SCH_1):PAGE212',
 MATERIAL='EMPTY',
 PHYS_PAGE='230',
 XY='(-8175,5900)',
 ROT='0',
 VER='1',
 PACK_TYPE='TH',
 LOCATION='H88',
 CDS_LIB='pure_quanta',
 CDS_PART_NAME='HOLE_TH-EMPTY,HOLE596',
 PART_NUMBER='HOLE596',
 PRIM_FILE='./archive_libs/logical/hole/chips/chips.prt';

PART_NAME
 H89 'HOLE_TH-EMPTY,HOLE596':;

SECTION_NUMBER 1
 '@T6G_MB_LIB.T6G(SCH_1):PAGE212_I132@PURE_QUANTA.HOLE(CHIPS)':
 C_PATH='@t6g_mb_lib.t6g(sch_1):page212_i132@pure_quanta.hole(chips)',
 P_PATH='@t6g_mb_lib.t6g(sch_1):page230_i132@pure_quanta.hole(chips)',
 PATH='I132',
 DRAWING='@T6G_MB_LIB.T6G(SCH_1):PAGE212',
 MATERIAL='EMPTY',
 PHYS_PAGE='230',
 XY='(-8150,5325)',
 ROT='0',
 VER='1',
 PACK_TYPE='TH',
 LOCATION='H89',
 CDS_LIB='pure_quanta',
 CDS_PART_NAME='HOLE_TH-EMPTY,HOLE596',
 PART_NUMBER='HOLE596',
 PRIM_FILE='./archive_libs/logical/hole/chips/chips.prt';

PART_NAME
 H90 'HOLE_TH-EMPTY,HOLE372':;

SECTION_NUMBER 1
 '@T6G_MB_LIB.T6G(SCH_1):PAGE212_I167@PURE_QUANTA.HOLE(CHIPS)':
 C_PATH='@t6g_mb_lib.t6g(sch_1):page212_i167@pure_quanta.hole(chips)',
 P_PATH='@t6g_mb_lib.t6g(sch_1):page230_i167@pure_quanta.hole(chips)',
 PATH='I167',
 DRAWING='@T6G_MB_LIB.T6G(SCH_1):PAGE212',
 MATERIAL='EMPTY',
 PHYS_PAGE='230',
 XY='(-825,6025)',
 ROT='0',
 VER='1',
 PACK_TYPE='TH',
 LOCATION='H90',
 CDS_LIB='pure_quanta',
 CDS_PART_NAME='HOLE_TH-EMPTY,HOLE372',
 PART_NUMBER='HOLE372',
 PRIM_FILE='./archive_libs/logical/hole/chips/chips.prt';

PART_NAME
 H91 'HOLE_TH-EMPTY,HOLE596':;

SECTION_NUMBER 1
 '@T6G_MB_LIB.T6G(SCH_1):PAGE212_I133@PURE_QUANTA.HOLE(CHIPS)':
 C_PATH='@t6g_mb_lib.t6g(sch_1):page212_i133@pure_quanta.hole(chips)',
 P_PATH='@t6g_mb_lib.t6g(sch_1):page230_i133@pure_quanta.hole(chips)',
 PATH='I133',
 DRAWING='@T6G_MB_LIB.T6G(SCH_1):PAGE212',
 MATERIAL='EMPTY',
 PHYS_PAGE='230',
 XY='(-7475,5900)',
 ROT='0',
 VER='1',
 PACK_TYPE='TH',
 LOCATION='H91',
 CDS_LIB='pure_quanta',
 CDS_PART_NAME='HOLE_TH-EMPTY,HOLE596',
 PART_NUMBER='HOLE596',
 PRIM_FILE='./archive_libs/logical/hole/chips/chips.prt';

PART_NAME
 H92 'HOLE_TH-EMPTY,HOLE596':;

SECTION_NUMBER 1
 '@T6G_MB_LIB.T6G(SCH_1):PAGE212_I135@PURE_QUANTA.HOLE(CHIPS)':
 C_PATH='@t6g_mb_lib.t6g(sch_1):page212_i135@pure_quanta.hole(chips)',
 P_PATH='@t6g_mb_lib.t6g(sch_1):page230_i135@pure_quanta.hole(chips)',
 PATH='I135',
 DRAWING='@T6G_MB_LIB.T6G(SCH_1):PAGE212',
 MATERIAL='EMPTY',
 PHYS_PAGE='230',
 XY='(-7475,5350)',
 ROT='0',
 VER='1',
 PACK_TYPE='TH',
 LOCATION='H92',
 CDS_LIB='pure_quanta',
 CDS_PART_NAME='HOLE_TH-EMPTY,HOLE596',
 PART_NUMBER='HOLE596',
 PRIM_FILE='./archive_libs/logical/hole/chips/chips.prt';

PART_NAME
 H93 'HOLE_TH-EMPTY,HOLE596':;

SECTION_NUMBER 1
 '@T6G_MB_LIB.T6G(SCH_1):PAGE212_I138@PURE_QUANTA.HOLE(CHIPS)':
 C_PATH='@t6g_mb_lib.t6g(sch_1):page212_i138@pure_quanta.hole(chips)',
 P_PATH='@t6g_mb_lib.t6g(sch_1):page230_i138@pure_quanta.hole(chips)',
 PATH='I138',
 DRAWING='@T6G_MB_LIB.T6G(SCH_1):PAGE212',
 MATERIAL='EMPTY',
 PHYS_PAGE='230',
 XY='(-6850,5900)',
 ROT='0',
 VER='1',
 PACK_TYPE='TH',
 LOCATION='H93',
 CDS_LIB='pure_quanta',
 CDS_PART_NAME='HOLE_TH-EMPTY,HOLE596',
 PART_NUMBER='HOLE596',
 PRIM_FILE='./archive_libs/logical/hole/chips/chips.prt';

PART_NAME
 H94 'HOLE_TH-EMPTY,HOLE596':;

SECTION_NUMBER 1
 '@T6G_MB_LIB.T6G(SCH_1):PAGE212_I140@PURE_QUANTA.HOLE(CHIPS)':
 C_PATH='@t6g_mb_lib.t6g(sch_1):page212_i140@pure_quanta.hole(chips)',
 P_PATH='@t6g_mb_lib.t6g(sch_1):page230_i140@pure_quanta.hole(chips)',
 PATH='I140',
 DRAWING='@T6G_MB_LIB.T6G(SCH_1):PAGE212',
 MATERIAL='EMPTY',
 PHYS_PAGE='230',
 XY='(-6800,5325)',
 ROT='0',
 VER='1',
 PACK_TYPE='TH',
 LOCATION='H94',
 CDS_LIB='pure_quanta',
 CDS_PART_NAME='HOLE_TH-EMPTY,HOLE596',
 PART_NUMBER='HOLE596',
 PRIM_FILE='./archive_libs/logical/hole/chips/chips.prt';

PART_NAME
 H95 'HOLE_TH-EMPTY,HOLE596':;

SECTION_NUMBER 1
 '@T6G_MB_LIB.T6G(SCH_1):PAGE212_I141@PURE_QUANTA.HOLE(CHIPS)':
 C_PATH='@t6g_mb_lib.t6g(sch_1):page212_i141@pure_quanta.hole(chips)',
 P_PATH='@t6g_mb_lib.t6g(sch_1):page230_i141@pure_quanta.hole(chips)',
 PATH='I141',
 DRAWING='@T6G_MB_LIB.T6G(SCH_1):PAGE212',
 MATERIAL='EMPTY',
 PHYS_PAGE='230',
 XY='(-6200,5875)',
 ROT='0',
 VER='1',
 PACK_TYPE='TH',
 LOCATION='H95',
 CDS_LIB='pure_quanta',
 CDS_PART_NAME='HOLE_TH-EMPTY,HOLE596',
 PART_NUMBER='HOLE596',
 PRIM_FILE='./archive_libs/logical/hole/chips/chips.prt';

PART_NAME
 H96 'HOLE_TH-EMPTY,HOLE596':;

SECTION_NUMBER 1
 '@T6G_MB_LIB.T6G(SCH_1):PAGE212_I142@PURE_QUANTA.HOLE(CHIPS)':
 C_PATH='@t6g_mb_lib.t6g(sch_1):page212_i142@pure_quanta.hole(chips)',
 P_PATH='@t6g_mb_lib.t6g(sch_1):page230_i142@pure_quanta.hole(chips)',
 PATH='I142',
 DRAWING='@T6G_MB_LIB.T6G(SCH_1):PAGE212',
 MATERIAL='EMPTY',
 PHYS_PAGE='230',
 XY='(-6150,5350)',
 ROT='0',
 VER='1',
 PACK_TYPE='TH',
 LOCATION='H96',
 CDS_LIB='pure_quanta',
 CDS_PART_NAME='HOLE_TH-EMPTY,HOLE596',
 PART_NUMBER='HOLE596',
 PRIM_FILE='./archive_libs/logical/hole/chips/chips.prt';

PART_NAME
 H97 'HOLE_TH-EMPTY,HOLE596':;

SECTION_NUMBER 1
 '@T6G_MB_LIB.T6G(SCH_1):PAGE212_I145@PURE_QUANTA.HOLE(CHIPS)':
 C_PATH='@t6g_mb_lib.t6g(sch_1):page212_i145@pure_quanta.hole(chips)',
 P_PATH='@t6g_mb_lib.t6g(sch_1):page230_i145@pure_quanta.hole(chips)',
 PATH='I145',
 DRAWING='@T6G_MB_LIB.T6G(SCH_1):PAGE212',
 MATERIAL='EMPTY',
 PHYS_PAGE='230',
 XY='(-5475,5925)',
 ROT='0',
 VER='1',
 PACK_TYPE='TH',
 LOCATION='H97',
 CDS_LIB='pure_quanta',
 CDS_PART_NAME='HOLE_TH-EMPTY,HOLE596',
 PART_NUMBER='HOLE596',
 PRIM_FILE='./archive_libs/logical/hole/chips/chips.prt';

PART_NAME
 H98 'HOLE_TH-EMPTY,HOLE596':;

SECTION_NUMBER 1
 '@T6G_MB_LIB.T6G(SCH_1):PAGE212_I147@PURE_QUANTA.HOLE(CHIPS)':
 C_PATH='@t6g_mb_lib.t6g(sch_1):page212_i147@pure_quanta.hole(chips)',
 P_PATH='@t6g_mb_lib.t6g(sch_1):page230_i147@pure_quanta.hole(chips)',
 PATH='I147',
 DRAWING='@T6G_MB_LIB.T6G(SCH_1):PAGE212',
 MATERIAL='EMPTY',
 PHYS_PAGE='230',
 XY='(-5450,5300)',
 ROT='0',
 VER='1',
 PACK_TYPE='TH',
 LOCATION='H98',
 CDS_LIB='pure_quanta',
 CDS_PART_NAME='HOLE_TH-EMPTY,HOLE596',
 PART_NUMBER='HOLE596',
 PRIM_FILE='./archive_libs/logical/hole/chips/chips.prt';

PART_NAME
 H99 'HOLE_TH-EMPTY,HOLE596':;

SECTION_NUMBER 1
 '@T6G_MB_LIB.T6G(SCH_1):PAGE212_I149@PURE_QUANTA.HOLE(CHIPS)':
 C_PATH='@t6g_mb_lib.t6g(sch_1):page212_i149@pure_quanta.hole(chips)',
 P_PATH='@t6g_mb_lib.t6g(sch_1):page230_i149@pure_quanta.hole(chips)',
 PATH='I149',
 DRAWING='@T6G_MB_LIB.T6G(SCH_1):PAGE212',
 MATERIAL='EMPTY',
 PHYS_PAGE='230',
 XY='(-4750,5925)',
 ROT='0',
 VER='1',
 PACK_TYPE='TH',
 LOCATION='H99',
 CDS_LIB='pure_quanta',
 CDS_PART_NAME='HOLE_TH-EMPTY,HOLE596',
 PART_NUMBER='HOLE596',
 PRIM_FILE='./archive_libs/logical/hole/chips/chips.prt';

PART_NAME
 H100 'HOLE_TH-EMPTY,HOLE596':;

SECTION_NUMBER 1
 '@T6G_MB_LIB.T6G(SCH_1):PAGE212_I152@PURE_QUANTA.HOLE(CHIPS)':
 C_PATH='@t6g_mb_lib.t6g(sch_1):page212_i152@pure_quanta.hole(chips)',
 P_PATH='@t6g_mb_lib.t6g(sch_1):page230_i152@pure_quanta.hole(chips)',
 PATH='I152',
 DRAWING='@T6G_MB_LIB.T6G(SCH_1):PAGE212',
 MATERIAL='EMPTY',
 PHYS_PAGE='230',
 XY='(-4725,5300)',
 ROT='0',
 VER='1',
 PACK_TYPE='TH',
 LOCATION='H100',
 CDS_LIB='pure_quanta',
 CDS_PART_NAME='HOLE_TH-EMPTY,HOLE596',
 PART_NUMBER='HOLE596',
 PRIM_FILE='./archive_libs/logical/hole/chips/chips.prt';

PART_NAME
 H101 'HOLE_TH-EMPTY,HOLE596':;

SECTION_NUMBER 1
 '@T6G_MB_LIB.T6G(SCH_1):PAGE212_I153@PURE_QUANTA.HOLE(CHIPS)':
 C_PATH='@t6g_mb_lib.t6g(sch_1):page212_i153@pure_quanta.hole(chips)',
 P_PATH='@t6g_mb_lib.t6g(sch_1):page230_i153@pure_quanta.hole(chips)',
 PATH='I153',
 DRAWING='@T6G_MB_LIB.T6G(SCH_1):PAGE212',
 MATERIAL='EMPTY',
 PHYS_PAGE='230',
 XY='(-4100,5925)',
 ROT='0',
 VER='1',
 PACK_TYPE='TH',
 LOCATION='H101',
 CDS_LIB='pure_quanta',
 CDS_PART_NAME='HOLE_TH-EMPTY,HOLE596',
 PART_NUMBER='HOLE596',
 PRIM_FILE='./archive_libs/logical/hole/chips/chips.prt';

PART_NAME
 H102 'HOLE_TH-EMPTY,HOLE596':;

SECTION_NUMBER 1
 '@T6G_MB_LIB.T6G(SCH_1):PAGE212_I156@PURE_QUANTA.HOLE(CHIPS)':
 C_PATH='@t6g_mb_lib.t6g(sch_1):page212_i156@pure_quanta.hole(chips)',
 P_PATH='@t6g_mb_lib.t6g(sch_1):page230_i156@pure_quanta.hole(chips)',
 PATH='I156',
 DRAWING='@T6G_MB_LIB.T6G(SCH_1):PAGE212',
 MATERIAL='EMPTY',
 PHYS_PAGE='230',
 XY='(-4075,5300)',
 ROT='0',
 VER='1',
 PACK_TYPE='TH',
 LOCATION='H102',
 CDS_LIB='pure_quanta',
 CDS_PART_NAME='HOLE_TH-EMPTY,HOLE596',
 PART_NUMBER='HOLE596',
 PRIM_FILE='./archive_libs/logical/hole/chips/chips.prt';

PART_NAME
 H103 'HOLE_TH-EMPTY,HOLE596':;

SECTION_NUMBER 1
 '@T6G_MB_LIB.T6G(SCH_1):PAGE212_I157@PURE_QUANTA.HOLE(CHIPS)':
 C_PATH='@t6g_mb_lib.t6g(sch_1):page212_i157@pure_quanta.hole(chips)',
 P_PATH='@t6g_mb_lib.t6g(sch_1):page230_i157@pure_quanta.hole(chips)',
 PATH='I157',
 DRAWING='@T6G_MB_LIB.T6G(SCH_1):PAGE212',
 MATERIAL='EMPTY',
 PHYS_PAGE='230',
 XY='(-3325,5950)',
 ROT='0',
 VER='1',
 PACK_TYPE='TH',
 LOCATION='H103',
 CDS_LIB='pure_quanta',
 CDS_PART_NAME='HOLE_TH-EMPTY,HOLE596',
 PART_NUMBER='HOLE596',
 PRIM_FILE='./archive_libs/logical/hole/chips/chips.prt';

PART_NAME
 H104 'HOLE_TH-EMPTY,HOLE596':;

SECTION_NUMBER 1
 '@T6G_MB_LIB.T6G(SCH_1):PAGE212_I159@PURE_QUANTA.HOLE(CHIPS)':
 C_PATH='@t6g_mb_lib.t6g(sch_1):page212_i159@pure_quanta.hole(chips)',
 P_PATH='@t6g_mb_lib.t6g(sch_1):page230_i159@pure_quanta.hole(chips)',
 PATH='I159',
 DRAWING='@T6G_MB_LIB.T6G(SCH_1):PAGE212',
 MATERIAL='EMPTY',
 PHYS_PAGE='230',
 XY='(-3325,5325)',
 ROT='0',
 VER='1',
 PACK_TYPE='TH',
 LOCATION='H104',
 CDS_LIB='pure_quanta',
 CDS_PART_NAME='HOLE_TH-EMPTY,HOLE596',
 PART_NUMBER='HOLE596',
 PRIM_FILE='./archive_libs/logical/hole/chips/chips.prt';

PART_NAME
 H105 'HOLE_TH-EMPTY,HOLE596':;

SECTION_NUMBER 1
 '@T6G_MB_LIB.T6G(SCH_1):PAGE212_I161@PURE_QUANTA.HOLE(CHIPS)':
 C_PATH='@t6g_mb_lib.t6g(sch_1):page212_i161@pure_quanta.hole(chips)',
 P_PATH='@t6g_mb_lib.t6g(sch_1):page230_i161@pure_quanta.hole(chips)',
 PATH='I161',
 DRAWING='@T6G_MB_LIB.T6G(SCH_1):PAGE212',
 MATERIAL='EMPTY',
 PHYS_PAGE='230',
 XY='(-2675,5950)',
 ROT='0',
 VER='1',
 PACK_TYPE='TH',
 LOCATION='H105',
 CDS_LIB='pure_quanta',
 CDS_PART_NAME='HOLE_TH-EMPTY,HOLE596',
 PART_NUMBER='HOLE596',
 PRIM_FILE='./archive_libs/logical/hole/chips/chips.prt';

PART_NAME
 H106 'HOLE_TH-EMPTY,HOLE596':;

SECTION_NUMBER 1
 '@T6G_MB_LIB.T6G(SCH_1):PAGE212_I163@PURE_QUANTA.HOLE(CHIPS)':
 C_PATH='@t6g_mb_lib.t6g(sch_1):page212_i163@pure_quanta.hole(chips)',
 P_PATH='@t6g_mb_lib.t6g(sch_1):page230_i163@pure_quanta.hole(chips)',
 PATH='I163',
 DRAWING='@T6G_MB_LIB.T6G(SCH_1):PAGE212',
 MATERIAL='EMPTY',
 PHYS_PAGE='230',
 XY='(-2675,5300)',
 ROT='0',
 VER='1',
 PACK_TYPE='TH',
 LOCATION='H106',
 CDS_LIB='pure_quanta',
 CDS_PART_NAME='HOLE_TH-EMPTY,HOLE596',
 PART_NUMBER='HOLE596',
 PRIM_FILE='./archive_libs/logical/hole/chips/chips.prt';

PART_NAME
 H111 'GND_HOLE_TH-EMPTY,TMP-QGND_HOLE12':;

SECTION_NUMBER 1
 '@T6G_MB_LIB.T6G(SCH_1):PAGE212_I120@PURE_QUANTA.GND_HOLE(CHIPS)':
 C_PATH='@t6g_mb_lib.t6g(sch_1):page212_i120@pure_quanta.gnd_hole(chips)',
 P_PATH='@t6g_mb_lib.t6g(sch_1):page230_i120@pure_quanta.gnd_hole(chips)',
 PATH='I120',
 DRAWING='@T6G_MB_LIB.T6G(SCH_1):PAGE212',
 SEC_TYPE='TH',
 MATERIAL='EMPTY',
 PHYS_PAGE='230',
 XY='(-7225,800)',
 ROT='0',
 VER='1',
 PACK_TYPE='TH',
 LOCATION='H111',
 SEC='1',
 CDS_LIB='pure_quanta',
 CDS_PART_NAME='GND_HOLE_TH-EMPTY,TMP-QGND_HOLE12',
 PART_NUMBER='TMP-QGND_HOLE12',
 PRIM_FILE='./archive_libs/logical/gnd_hole/chips/chips.prt';

PART_NAME
 H112 'GND_HOLE_TH-EMPTY,TMP-QGND_HOLE12':;

SECTION_NUMBER 1
 '@T6G_MB_LIB.T6G(SCH_1):PAGE212_I123@PURE_QUANTA.GND_HOLE(CHIPS)':
 C_PATH='@t6g_mb_lib.t6g(sch_1):page212_i123@pure_quanta.gnd_hole(chips)',
 P_PATH='@t6g_mb_lib.t6g(sch_1):page230_i123@pure_quanta.gnd_hole(chips)',
 PATH='I123',
 DRAWING='@T6G_MB_LIB.T6G(SCH_1):PAGE212',
 SEC_TYPE='TH',
 MATERIAL='EMPTY',
 PHYS_PAGE='230',
 XY='(-6475,825)',
 ROT='0',
 VER='1',
 PACK_TYPE='TH',
 LOCATION='H112',
 SEC='1',
 CDS_LIB='pure_quanta',
 CDS_PART_NAME='GND_HOLE_TH-EMPTY,TMP-QGND_HOLE12',
 PART_NUMBER='TMP-QGND_HOLE12',
 PRIM_FILE='./archive_libs/logical/gnd_hole/chips/chips.prt';

PART_NAME
 H113 'GND_HOLE_TH-EMPTY,GND_HOLE140':;

SECTION_NUMBER 1
 '@T6G_MB_LIB.T6G(SCH_1):PAGE212_I25@PURE_QUANTA.GND_HOLE(CHIPS)':
 C_PATH='@t6g_mb_lib.t6g(sch_1):page212_i25@pure_quanta.gnd_hole(chips)',
 P_PATH='@t6g_mb_lib.t6g(sch_1):page230_i25@pure_quanta.gnd_hole(chips)',
 PATH='I25',
 DRAWING='@T6G_MB_LIB.T6G(SCH_1):PAGE212',
 MATERIAL='EMPTY',
 PHYS_PAGE='230',
 XY='(-8850,850)',
 ROT='0',
 VER='1',
 PACK_TYPE='TH',
 LOCATION='H113',
 CDS_LIB='pure_quanta',
 CDS_PART_NAME='GND_HOLE_TH-EMPTY,GND_HOLE140',
 PART_NUMBER='GND_HOLE140',
 PRIM_FILE='./archive_libs/logical/gnd_hole/chips/chips.prt';

PART_NAME
 H114 'GND_HOLE_TH-EMPTY,GND_HOLE140':;

SECTION_NUMBER 1
 '@T6G_MB_LIB.T6G(SCH_1):PAGE212_I30@PURE_QUANTA.GND_HOLE(CHIPS)':
 C_PATH='@t6g_mb_lib.t6g(sch_1):page212_i30@pure_quanta.gnd_hole(chips)',
 P_PATH='@t6g_mb_lib.t6g(sch_1):page230_i30@pure_quanta.gnd_hole(chips)',
 PATH='I30',
 DRAWING='@T6G_MB_LIB.T6G(SCH_1):PAGE212',
 MATERIAL='EMPTY',
 PHYS_PAGE='230',
 XY='(-8075,875)',
 ROT='0',
 VER='1',
 PACK_TYPE='TH',
 LOCATION='H114',
 CDS_LIB='pure_quanta',
 CDS_PART_NAME='GND_HOLE_TH-EMPTY,GND_HOLE140',
 PART_NUMBER='GND_HOLE140',
 PRIM_FILE='./archive_libs/logical/gnd_hole/chips/chips.prt';

PART_NAME
 H115 'GND_HOLE_TH-EMPTY,GND_HOLE514':;

SECTION_NUMBER 1
 '@T6G_MB_LIB.T6G(SCH_1):PAGE212_I43@PURE_QUANTA.GND_HOLE(CHIPS)':
 C_PATH='@t6g_mb_lib.t6g(sch_1):page212_i43@pure_quanta.gnd_hole(chips)',
 P_PATH='@t6g_mb_lib.t6g(sch_1):page230_i43@pure_quanta.gnd_hole(chips)',
 PATH='I43',
 DRAWING='@T6G_MB_LIB.T6G(SCH_1):PAGE212',
 MATERIAL='EMPTY',
 PHYS_PAGE='230',
 XY='(-5425,850)',
 ROT='0',
 VER='1',
 PACK_TYPE='TH',
 LOCATION='H115',
 CDS_LIB='pure_quanta',
 CDS_PART_NAME='GND_HOLE_TH-EMPTY,GND_HOLE514',
 PART_NUMBER='GND_HOLE514',
 PRIM_FILE='./archive_libs/logical/gnd_hole/chips/chips.prt';

PART_NAME
 H124 'HOLE_TH-EMPTY,TMP-C_T2I_ALEX_1121_1':;

SECTION_NUMBER 1
 '@T6G_MB_LIB.T6G(SCH_1):PAGE212_I84@PURE_QUANTA.HOLE(CHIPS)':
 C_PATH='@t6g_mb_lib.t6g(sch_1):page212_i84@pure_quanta.hole(chips)',
 P_PATH='@t6g_mb_lib.t6g(sch_1):page230_i84@pure_quanta.hole(chips)',
 PATH='I84',
 DRAWING='@T6G_MB_LIB.T6G(SCH_1):PAGE212',
 MATERIAL='EMPTY',
 PHYS_PAGE='230',
 XY='(-3675,500)',
 ROT='0',
 VER='1',
 PACK_TYPE='TH',
 LOCATION='H124',
 CDS_LIB='pure_quanta',
 CDS_PART_NAME='HOLE_TH-EMPTY,TMP-C_T2I_ALEX_1121_1',
 PART_NUMBER='TMP-C_T2I_ALEX_1121_1',
 PRIM_FILE='./archive_libs/logical/hole/chips/chips.prt';

PART_NAME
 H125 'HOLE_TH-EMPTY,TMP-C_T2I_ALEX_1121_1':;

SECTION_NUMBER 1
 '@T6G_MB_LIB.T6G(SCH_1):PAGE212_I85@PURE_QUANTA.HOLE(CHIPS)':
 C_PATH='@t6g_mb_lib.t6g(sch_1):page212_i85@pure_quanta.hole(chips)',
 P_PATH='@t6g_mb_lib.t6g(sch_1):page230_i85@pure_quanta.hole(chips)',
 PATH='I85',
 DRAWING='@T6G_MB_LIB.T6G(SCH_1):PAGE212',
 MATERIAL='EMPTY',
 PHYS_PAGE='230',
 XY='(-3625,925)',
 ROT='0',
 VER='1',
 PACK_TYPE='TH',
 LOCATION='H125',
 CDS_LIB='pure_quanta',
 CDS_PART_NAME='HOLE_TH-EMPTY,TMP-C_T2I_ALEX_1121_1',
 PART_NUMBER='TMP-C_T2I_ALEX_1121_1',
 PRIM_FILE='./archive_libs/logical/hole/chips/chips.prt';

PART_NAME
 H126 'HOLE_TH-EMPTY,TMP-C_T2I_ALEX_1121_1':;

SECTION_NUMBER 1
 '@T6G_MB_LIB.T6G(SCH_1):PAGE212_I111@PURE_QUANTA.HOLE(CHIPS)':
 C_PATH='@t6g_mb_lib.t6g(sch_1):page212_i111@pure_quanta.hole(chips)',
 P_PATH='@t6g_mb_lib.t6g(sch_1):page230_i111@pure_quanta.hole(chips)',
 PATH='I111',
 DRAWING='@T6G_MB_LIB.T6G(SCH_1):PAGE212',
 MATERIAL='EMPTY',
 PHYS_PAGE='230',
 XY='(-2875,475)',
 ROT='0',
 VER='1',
 PACK_TYPE='TH',
 LOCATION='H126',
 CDS_LIB='pure_quanta',
 CDS_PART_NAME='HOLE_TH-EMPTY,TMP-C_T2I_ALEX_1121_1',
 PART_NUMBER='TMP-C_T2I_ALEX_1121_1',
 PRIM_FILE='./archive_libs/logical/hole/chips/chips.prt';

PART_NAME
 H127 'HOLE_TH-EMPTY,TMP-C_T2I_ALEX_1121_1':;

SECTION_NUMBER 1
 '@T6G_MB_LIB.T6G(SCH_1):PAGE212_I94@PURE_QUANTA.HOLE(CHIPS)':
 C_PATH='@t6g_mb_lib.t6g(sch_1):page212_i94@pure_quanta.hole(chips)',
 P_PATH='@t6g_mb_lib.t6g(sch_1):page230_i94@pure_quanta.hole(chips)',
 PATH='I94',
 DRAWING='@T6G_MB_LIB.T6G(SCH_1):PAGE212',
 MATERIAL='EMPTY',
 PHYS_PAGE='230',
 XY='(-2850,900)',
 ROT='0',
 VER='1',
 PACK_TYPE='TH',
 LOCATION='H127',
 CDS_LIB='pure_quanta',
 CDS_PART_NAME='HOLE_TH-EMPTY,TMP-C_T2I_ALEX_1121_1',
 PART_NUMBER='TMP-C_T2I_ALEX_1121_1',
 PRIM_FILE='./archive_libs/logical/hole/chips/chips.prt';

PART_NAME
 H128 'HOLE_TH-EMPTY,HOLE596':;

SECTION_NUMBER 1
 '@T6G_MB_LIB.T6G(SCH_1):PAGE212_I166@PURE_QUANTA.HOLE(CHIPS)':
 C_PATH='@t6g_mb_lib.t6g(sch_1):page212_i166@pure_quanta.hole(chips)',
 P_PATH='@t6g_mb_lib.t6g(sch_1):page230_i166@pure_quanta.hole(chips)',
 PATH='I166',
 DRAWING='@T6G_MB_LIB.T6G(SCH_1):PAGE212',
 MATERIAL='EMPTY',
 PHYS_PAGE='230',
 XY='(-2000,6000)',
 ROT='0',
 VER='1',
 PACK_TYPE='TH',
 LOCATION='H128',
 CDS_LIB='pure_quanta',
 CDS_PART_NAME='HOLE_TH-EMPTY,HOLE596',
 PART_NUMBER='HOLE596',
 PRIM_FILE='./archive_libs/logical/hole/chips/chips.prt';

PART_NAME
 H6000 'HOLE_TH-EMPTY,HOLE1226':;

SECTION_NUMBER 1
 '@T6G_MB_LIB.T6G(SCH_1):PAGE212_I113@PURE_QUANTA.HOLE(CHIPS)':
 C_PATH='@t6g_mb_lib.t6g(sch_1):page212_i113@pure_quanta.hole(chips)',
 P_PATH='@t6g_mb_lib.t6g(sch_1):page230_i113@pure_quanta.hole(chips)',
 PATH='I113',
 DRAWING='@T6G_MB_LIB.T6G(SCH_1):PAGE212',
 MATERIAL='EMPTY',
 PHYS_PAGE='230',
 XY='(-825,1400)',
 ROT='0',
 VER='1',
 PACK_TYPE='TH',
 LOCATION='H6000',
 CDS_LIB='pure_quanta',
 CDS_PART_NAME='HOLE_TH-EMPTY,HOLE1226',
 PART_NUMBER='HOLE1226',
 PRIM_FILE='./archive_libs/logical/hole/chips/chips.prt';

PART_NAME
 H6001 'HOLE_TH-EMPTY,HOLE1226':;

SECTION_NUMBER 1
 '@T6G_MB_LIB.T6G(SCH_1):PAGE212_I116@PURE_QUANTA.HOLE(CHIPS)':
 C_PATH='@t6g_mb_lib.t6g(sch_1):page212_i116@pure_quanta.hole(chips)',
 P_PATH='@t6g_mb_lib.t6g(sch_1):page230_i116@pure_quanta.hole(chips)',
 PATH='I116',
 DRAWING='@T6G_MB_LIB.T6G(SCH_1):PAGE212',
 MATERIAL='EMPTY',
 PHYS_PAGE='230',
 XY='(-300,1375)',
 ROT='0',
 VER='1',
 PACK_TYPE='TH',
 LOCATION='H6001',
 CDS_LIB='pure_quanta',
 CDS_PART_NAME='HOLE_TH-EMPTY,HOLE1226',
 PART_NUMBER='HOLE1226',
 PRIM_FILE='./archive_libs/logical/hole/chips/chips.prt';

PART_NAME
 H6002 'HOLE_TH-EMPTY,HOLE1195':;

SECTION_NUMBER 1
 '@T6G_MB_LIB.T6G(SCH_1):PAGE212_I168@PURE_QUANTA.HOLE(CHIPS)':
 C_PATH='@t6g_mb_lib.t6g(sch_1):page212_i168@pure_quanta.hole(chips)',
 P_PATH='@t6g_mb_lib.t6g(sch_1):page230_i168@pure_quanta.hole(chips)',
 PATH='I168',
 DRAWING='@T6G_MB_LIB.T6G(SCH_1):PAGE212',
 MATERIAL='EMPTY',
 PHYS_PAGE='230',
 XY='(-525,3975)',
 ROT='0',
 VER='1',
 PACK_TYPE='TH',
 LOCATION='H6002',
 CDS_LIB='pure_quanta',
 CDS_PART_NAME='HOLE_TH-EMPTY,HOLE1195',
 PART_NUMBER='HOLE1195',
 PRIM_FILE='./archive_libs/logical/hole/chips/chips.prt';

PART_NAME
 H8027 'HOLE_TH-EMPTY,HOLE1226':;

SECTION_NUMBER 1
 '@T6G_MB_LIB.T6G(SCH_1):PAGE212_I7@PURE_QUANTA.HOLE(CHIPS)':
 C_PATH='@t6g_mb_lib.t6g(sch_1):page212_i7@pure_quanta.hole(chips)',
 P_PATH='@t6g_mb_lib.t6g(sch_1):page230_i7@pure_quanta.hole(chips)',
 PATH='I7',
 DRAWING='@T6G_MB_LIB.T6G(SCH_1):PAGE212',
 MATERIAL='EMPTY',
 PHYS_PAGE='230',
 XY='(-8300,3400)',
 ROT='0',
 VER='1',
 PACK_TYPE='TH',
 LOCATION='H8027',
 CDS_LIB='pure_quanta',
 CDS_PART_NAME='HOLE_TH-EMPTY,HOLE1226',
 PART_NUMBER='HOLE1226',
 PRIM_FILE='./archive_libs/logical/hole/chips/chips.prt';

PART_NAME
 H8028 'HOLE_TH-EMPTY,HOLE1226':;

SECTION_NUMBER 1
 '@T6G_MB_LIB.T6G(SCH_1):PAGE212_I27@PURE_QUANTA.HOLE(CHIPS)':
 C_PATH='@t6g_mb_lib.t6g(sch_1):page212_i27@pure_quanta.hole(chips)',
 P_PATH='@t6g_mb_lib.t6g(sch_1):page230_i27@pure_quanta.hole(chips)',
 PATH='I27',
 DRAWING='@T6G_MB_LIB.T6G(SCH_1):PAGE212',
 MATERIAL='EMPTY',
 PHYS_PAGE='230',
 XY='(-7700,2800)',
 ROT='0',
 VER='1',
 PACK_TYPE='TH',
 LOCATION='H8028',
 CDS_LIB='pure_quanta',
 CDS_PART_NAME='HOLE_TH-EMPTY,HOLE1226',
 PART_NUMBER='HOLE1226',
 PRIM_FILE='./archive_libs/logical/hole/chips/chips.prt';

PART_NAME
 J1 'SCONN288_DDR506112002KQ-SCONN288_DDR506112002KQ,SMA':;

SECTION_NUMBER 1
 '@T6G_MB_LIB.T6G(SCH_1):PAGE85_I536@PURE_QUANTA.SCONN288_DDR506112002KQ(CHIPS)':
 C_PATH='@t6g_mb_lib.t6g(sch_1):page85_i536@pure_quanta.sconn288_ddr506112002kq(~
chips)',
 P_PATH='@t6g_mb_lib.t6g(sch_1):page86_i536@pure_quanta.sconn288_ddr506112002kq(~
chips)',
 PATH='I536',
 DRAWING='@T6G_MB_LIB.T6G(SCH_1):PAGE85',
 PART_TYPE='SMLF',
 MATERIAL='IO',
 PHYS_PAGE='86',
 XY='(-6900,3675)',
 ROT='0',
 VER='1',
 LOCATION='J1',
 CDS_LIB='pure_quanta',
 CDS_PART_NAME='SCONN288_DDR506112002KQ-SCONN288_DDR506112002KQ,SMA',
 PART_NUMBER='DFHST8FS479',
 VALUE='SCONN288_DDR506112002KQ',
 PRIM_FILE='./archive_libs/logical/sconn288_ddr506112002kq/chips/chips.prt';

SECTION_NUMBER 2
 '@T6G_MB_LIB.T6G(SCH_1):PAGE85_I537@PURE_QUANTA.SCONN288_DDR506112002KQ(CHIPS)':
 C_PATH='@t6g_mb_lib.t6g(sch_1):page85_i537@pure_quanta.sconn288_ddr506112002kq(~
chips)',
 P_PATH='@t6g_mb_lib.t6g(sch_1):page86_i537@pure_quanta.sconn288_ddr506112002kq(~
chips)',
 PATH='I537',
 DRAWING='@T6G_MB_LIB.T6G(SCH_1):PAGE85',
 PART_TYPE='SMLF',
 MATERIAL='IO',
 PHYS_PAGE='86',
 XY='(-4600,4375)',
 ROT='0',
 VER='2',
 LOCATION='J1',
 CDS_LIB='pure_quanta',
 CDS_PART_NAME='SCONN288_DDR506112002KQ-SCONN288_DDR506112002KQ,SMA',
 PART_NUMBER='DFHST8FS479',
 VALUE='SCONN288_DDR506112002KQ',
 PRIM_FILE='./archive_libs/logical/sconn288_ddr506112002kq/chips/chips.prt';

SECTION_NUMBER 3
 '@T6G_MB_LIB.T6G(SCH_1):PAGE85_I538@PURE_QUANTA.SCONN288_DDR506112002KQ(CHIPS)':
 C_PATH='@t6g_mb_lib.t6g(sch_1):page85_i538@pure_quanta.sconn288_ddr506112002kq(~
chips)',
 P_PATH='@t6g_mb_lib.t6g(sch_1):page86_i538@pure_quanta.sconn288_ddr506112002kq(~
chips)',
 PATH='I538',
 DRAWING='@T6G_MB_LIB.T6G(SCH_1):PAGE85',
 PART_TYPE='SMLF',
 MATERIAL='IO',
 PHYS_PAGE='86',
 XY='(-1450,3700)',
 ROT='0',
 VER='3',
 LOCATION='J1',
 CDS_LIB='pure_quanta',
 CDS_PART_NAME='SCONN288_DDR506112002KQ-SCONN288_DDR506112002KQ,SMA',
 PART_NUMBER='DFHST8FS479',
 VALUE='SCONN288_DDR506112002KQ',
 PRIM_FILE='./archive_libs/logical/sconn288_ddr506112002kq/chips/chips.prt';

PART_NAME
 J5 'SCONN8_G802M0083150RD3HR-SCONN8_G802M0083150RD3HR,A':;

SECTION_NUMBER 1
 '@T6G_MB_LIB.T6G(SCH_1):PAGE27_I425@PURE_QUANTA.SCONN8_G802M0083150RD3HR(CHIPS)':
 C_PATH='@t6g_mb_lib.t6g(sch_1):page27_i425@pure_quanta.sconn8_g802m0083150rd3hr~
(chips)',
 P_PATH='@t6g_mb_lib.t6g(sch_1):page27_i425@pure_quanta.sconn8_g802m0083150rd3hr~
(chips)',
 PATH='I425',
 DRAWING='@T6G_MB_LIB.T6G(SCH_1):PAGE27',
 SEC_TYPE='',
 PART_TYPE='SMLF',
 MATERIAL='IO',
 PHYS_PAGE='27',
 XY='(-500,2875)',
 ROT='0',
 VER='1',
 LOCATION='J5',
 SEC='1',
 CDS_LIB='pure_quanta',
 CDS_PART_NAME='SCONN8_G802M0083150RD3HR-SCONN8_G802M0083150RD3HR,A',
 PART_NUMBER='DFHD08MS385',
 VALUE='SCONN8_G802M0083150RD3HR',
 PRIM_FILE='./archive_libs/logical/sconn8_g802m0083150rd3hr/chips/chips.prt';

PART_NAME
 J6 'CONN6_HBC1031L200D8H-CONN6_HBC1031-L200D-8H,THLF,IA':;

SECTION_NUMBER 1
 '@T6G_MB_LIB.T6G(SCH_1):PAGE28_I28@PURE_QUANTA.CONN6_HBC1031L200D8H(CHIPS)':
 C_PATH='@t6g_mb_lib.t6g(sch_1):page28_i28@pure_quanta.conn6_hbc1031l200d8h(chip~
s)',
 P_PATH='@t6g_mb_lib.t6g(sch_1):page28_i28@pure_quanta.conn6_hbc1031l200d8h(chip~
s)',
 PATH='I28',
 DRAWING='@T6G_MB_LIB.T6G(SCH_1):PAGE28',
 PART_TYPE='THLF',
 MATERIAL='IO',
 PHYS_PAGE='28',
 XY='(-8750,12225)',
 ROT='2',
 VER='1',
 LOCATION='J6',
 CDS_LIB='pure_quanta',
 CDS_PART_NAME='CONN6_HBC1031L200D8H-CONN6_HBC1031-L200D-8H,THLF,IA',
 PART_NUMBER='DFHD06MS263',
 VALUE='CONN6_HBC1031-L200D-8H',
 PRIM_FILE='./archive_libs/logical/conn6_hbc1031l200d8h/chips/chips.prt';

PART_NAME
 J7 'SCONN8_G802M0083150RD3HR-SCONN8_G802M0083150RD3HR,A':;

SECTION_NUMBER 1
 '@T6G_MB_LIB.T6G(SCH_1):PAGE54_I418@PURE_QUANTA.SCONN8_G802M0083150RD3HR(CHIPS)':
 C_PATH='@t6g_mb_lib.t6g(sch_1):page54_i418@pure_quanta.sconn8_g802m0083150rd3hr~
(chips)',
 P_PATH='@t6g_mb_lib.t6g(sch_1):page54_i418@pure_quanta.sconn8_g802m0083150rd3hr~
(chips)',
 PATH='I418',
 DRAWING='@T6G_MB_LIB.T6G(SCH_1):PAGE54',
 SEC_TYPE='',
 PART_TYPE='SMLF',
 MATERIAL='IO',
 PHYS_PAGE='54',
 XY='(-500,3575)',
 ROT='0',
 VER='1',
 LOCATION='J7',
 SEC='1',
 CDS_LIB='pure_quanta',
 CDS_PART_NAME='SCONN8_G802M0083150RD3HR-SCONN8_G802M0083150RD3HR,A',
 PART_NUMBER='DFHD08MS385',
 VALUE='SCONN8_G802M0083150RD3HR',
 PRIM_FILE='./archive_libs/logical/sconn8_g802m0083150rd3hr/chips/chips.prt';

PART_NAME
 J8 'CONN4_HFK1040L0P1L7H-CONN4_HFK1040-L0P1L-7H,THLF,IA':;

SECTION_NUMBER 1
 '@T6G_MB_LIB.T6G(SCH_1):PAGE349_I148@PURE_QUANTA.CONN4_HFK1040L0P1L7H(CHIPS)':
 C_PATH='@t6g_mb_lib.t6g(sch_1):page349_i148@pure_quanta.conn4_hfk1040l0p1l7h(ch~
ips)',
 P_PATH='@t6g_mb_lib.t6g(sch_1):page151_i148@pure_quanta.conn4_hfk1040l0p1l7h(ch~
ips)',
 PATH='I148',
 DRAWING='@T6G_MB_LIB.T6G(SCH_1):PAGE349',
 PART_TYPE='THLF',
 MATERIAL='IO',
 PHYS_PAGE='151',
 XY='(5350,1575)',
 ROT='0',
 VER='1',
 LOCATION='J8',
 CDS_LIB='pure_quanta',
 CDS_PART_NAME='CONN4_HFK1040L0P1L7H-CONN4_HFK1040-L0P1L-7H,THLF,IA',
 PART_NUMBER='DFHD04MS460',
 VALUE='CONN4_HFK1040-L0P1L-7H',
 PRIM_FILE='./archive_libs/logical/conn4_hfk1040l0p1l7h/chips/chips.prt';

PART_NAME
 J13 'CONN4_HFK1040L0P1L7H-CONN4_HFK1040-L0P1L-7H,THLF,IA':;

SECTION_NUMBER 1
 '@T6G_MB_LIB.T6G(SCH_1):PAGE141_I195@PURE_QUANTA.CONN4_HFK1040L0P1L7H(CHIPS)':
 C_PATH='@t6g_mb_lib.t6g(sch_1):page141_i195@pure_quanta.conn4_hfk1040l0p1l7h(ch~
ips)',
 P_PATH='@t6g_mb_lib.t6g(sch_1):page164_i195@pure_quanta.conn4_hfk1040l0p1l7h(ch~
ips)',
 PATH='I195',
 DRAWING='@T6G_MB_LIB.T6G(SCH_1):PAGE141',
 PART_TYPE='THLF',
 MATERIAL='IO',
 PHYS_PAGE='164',
 XY='(-1325,1450)',
 ROT='0',
 VER='1',
 LOCATION='J13',
 CDS_LIB='pure_quanta',
 CDS_PART_NAME='CONN4_HFK1040L0P1L7H-CONN4_HFK1040-L0P1L-7H,THLF,IA',
 PART_NUMBER='DFHD04MS460',
 VALUE='CONN4_HFK1040-L0P1L-7H',
 PRIM_FILE='./archive_libs/logical/conn4_hfk1040l0p1l7h/chips/chips.prt';

PART_NAME
 J15 'SCONN288_DDR506112002KQ-SCONN288_DDR506112002KQ,SMA':;

SECTION_NUMBER 1
 '@T6G_MB_LIB.T6G(SCH_1):PAGE86_I350@PURE_QUANTA.SCONN288_DDR506112002KQ(CHIPS)':
 C_PATH='@t6g_mb_lib.t6g(sch_1):page86_i350@pure_quanta.sconn288_ddr506112002kq(~
chips)',
 P_PATH='@t6g_mb_lib.t6g(sch_1):page87_i350@pure_quanta.sconn288_ddr506112002kq(~
chips)',
 PATH='I350',
 DRAWING='@T6G_MB_LIB.T6G(SCH_1):PAGE86',
 PART_TYPE='SMLF',
 MATERIAL='IO',
 PHYS_PAGE='87',
 XY='(-7100,3775)',
 ROT='0',
 VER='1',
 LOCATION='J15',
 CDS_LIB='pure_quanta',
 CDS_PART_NAME='SCONN288_DDR506112002KQ-SCONN288_DDR506112002KQ,SMA',
 PART_NUMBER='DFHST8FS479',
 VALUE='SCONN288_DDR506112002KQ',
 PRIM_FILE='./archive_libs/logical/sconn288_ddr506112002kq/chips/chips.prt';

SECTION_NUMBER 2
 '@T6G_MB_LIB.T6G(SCH_1):PAGE86_I367@PURE_QUANTA.SCONN288_DDR506112002KQ(CHIPS)':
 C_PATH='@t6g_mb_lib.t6g(sch_1):page86_i367@pure_quanta.sconn288_ddr506112002kq(~
chips)',
 P_PATH='@t6g_mb_lib.t6g(sch_1):page87_i367@pure_quanta.sconn288_ddr506112002kq(~
chips)',
 PATH='I367',
 DRAWING='@T6G_MB_LIB.T6G(SCH_1):PAGE86',
 PART_TYPE='SMLF',
 MATERIAL='IO',
 PHYS_PAGE='87',
 XY='(-4600,3650)',
 ROT='0',
 VER='2',
 LOCATION='J15',
 CDS_LIB='pure_quanta',
 CDS_PART_NAME='SCONN288_DDR506112002KQ-SCONN288_DDR506112002KQ,SMA',
 PART_NUMBER='DFHST8FS479',
 VALUE='SCONN288_DDR506112002KQ',
 PRIM_FILE='./archive_libs/logical/sconn288_ddr506112002kq/chips/chips.prt';

SECTION_NUMBER 3
 '@T6G_MB_LIB.T6G(SCH_1):PAGE86_I352@PURE_QUANTA.SCONN288_DDR506112002KQ(CHIPS)':
 C_PATH='@t6g_mb_lib.t6g(sch_1):page86_i352@pure_quanta.sconn288_ddr506112002kq(~
chips)',
 P_PATH='@t6g_mb_lib.t6g(sch_1):page87_i352@pure_quanta.sconn288_ddr506112002kq(~
chips)',
 PATH='I352',
 DRAWING='@T6G_MB_LIB.T6G(SCH_1):PAGE86',
 PART_TYPE='SMLF',
 MATERIAL='IO',
 PHYS_PAGE='87',
 XY='(-1225,3575)',
 ROT='0',
 VER='3',
 LOCATION='J15',
 CDS_LIB='pure_quanta',
 CDS_PART_NAME='SCONN288_DDR506112002KQ-SCONN288_DDR506112002KQ,SMA',
 PART_NUMBER='DFHST8FS479',
 VALUE='SCONN288_DDR506112002KQ',
 PRIM_FILE='./archive_libs/logical/sconn288_ddr506112002kq/chips/chips.prt';

PART_NAME
 J16 'SCONN288_DDR506112002KQ-SCONN288_DDR506112002KQ,SMA':;

SECTION_NUMBER 1
 '@T6G_MB_LIB.T6G(SCH_1):PAGE91_I22@PURE_QUANTA.SCONN288_DDR506112002KQ(CHIPS)':
 C_PATH='@t6g_mb_lib.t6g(sch_1):page91_i22@pure_quanta.sconn288_ddr506112002kq(c~
hips)',
 P_PATH='@t6g_mb_lib.t6g(sch_1):page92_i22@pure_quanta.sconn288_ddr506112002kq(c~
hips)',
 PATH='I22',
 DRAWING='@T6G_MB_LIB.T6G(SCH_1):PAGE91',
 PART_TYPE='SMLF',
 MATERIAL='IO',
 PHYS_PAGE='92',
 XY='(-6475,3650)',
 ROT='0',
 VER='1',
 LOCATION='J16',
 CDS_LIB='pure_quanta',
 CDS_PART_NAME='SCONN288_DDR506112002KQ-SCONN288_DDR506112002KQ,SMA',
 PART_NUMBER='DFHST8FS479',
 VALUE='SCONN288_DDR506112002KQ',
 PRIM_FILE='./archive_libs/logical/sconn288_ddr506112002kq/chips/chips.prt';

SECTION_NUMBER 2
 '@T6G_MB_LIB.T6G(SCH_1):PAGE91_I236@PURE_QUANTA.SCONN288_DDR506112002KQ(CHIPS)':
 C_PATH='@t6g_mb_lib.t6g(sch_1):page91_i236@pure_quanta.sconn288_ddr506112002kq(~
chips)',
 P_PATH='@t6g_mb_lib.t6g(sch_1):page92_i236@pure_quanta.sconn288_ddr506112002kq(~
chips)',
 PATH='I236',
 DRAWING='@T6G_MB_LIB.T6G(SCH_1):PAGE91',
 PART_TYPE='SMLF',
 MATERIAL='IO',
 PHYS_PAGE='92',
 XY='(-4100,3575)',
 ROT='0',
 VER='2',
 LOCATION='J16',
 CDS_LIB='pure_quanta',
 CDS_PART_NAME='SCONN288_DDR506112002KQ-SCONN288_DDR506112002KQ,SMA',
 PART_NUMBER='DFHST8FS479',
 VALUE='SCONN288_DDR506112002KQ',
 PRIM_FILE='./archive_libs/logical/sconn288_ddr506112002kq/chips/chips.prt';

SECTION_NUMBER 3
 '@T6G_MB_LIB.T6G(SCH_1):PAGE91_I177@PURE_QUANTA.SCONN288_DDR506112002KQ(CHIPS)':
 C_PATH='@t6g_mb_lib.t6g(sch_1):page91_i177@pure_quanta.sconn288_ddr506112002kq(~
chips)',
 P_PATH='@t6g_mb_lib.t6g(sch_1):page92_i177@pure_quanta.sconn288_ddr506112002kq(~
chips)',
 PATH='I177',
 DRAWING='@T6G_MB_LIB.T6G(SCH_1):PAGE91',
 PART_TYPE='SMLF',
 MATERIAL='IO',
 PHYS_PAGE='92',
 XY='(-1175,3650)',
 ROT='0',
 VER='3',
 LOCATION='J16',
 CDS_LIB='pure_quanta',
 CDS_PART_NAME='SCONN288_DDR506112002KQ-SCONN288_DDR506112002KQ,SMA',
 PART_NUMBER='DFHST8FS479',
 VALUE='SCONN288_DDR506112002KQ',
 PRIM_FILE='./archive_libs/logical/sconn288_ddr506112002kq/chips/chips.prt';

PART_NAME
 J17 'SCONN288_DDR506112002KQ-SCONN288_DDR506112002KQ,SMA':;

SECTION_NUMBER 1
 '@T6G_MB_LIB.T6G(SCH_1):PAGE87_I350@PURE_QUANTA.SCONN288_DDR506112002KQ(CHIPS)':
 C_PATH='@t6g_mb_lib.t6g(sch_1):page87_i350@pure_quanta.sconn288_ddr506112002kq(~
chips)',
 P_PATH='@t6g_mb_lib.t6g(sch_1):page88_i350@pure_quanta.sconn288_ddr506112002kq(~
chips)',
 PATH='I350',
 DRAWING='@T6G_MB_LIB.T6G(SCH_1):PAGE87',
 PART_TYPE='SMLF',
 MATERIAL='IO',
 PHYS_PAGE='88',
 XY='(-7075,3975)',
 ROT='0',
 VER='1',
 LOCATION='J17',
 CDS_LIB='pure_quanta',
 CDS_PART_NAME='SCONN288_DDR506112002KQ-SCONN288_DDR506112002KQ,SMA',
 PART_NUMBER='DFHST8FS479',
 VALUE='SCONN288_DDR506112002KQ',
 PRIM_FILE='./archive_libs/logical/sconn288_ddr506112002kq/chips/chips.prt';

SECTION_NUMBER 2
 '@T6G_MB_LIB.T6G(SCH_1):PAGE87_I411@PURE_QUANTA.SCONN288_DDR506112002KQ(CHIPS)':
 C_PATH='@t6g_mb_lib.t6g(sch_1):page87_i411@pure_quanta.sconn288_ddr506112002kq(~
chips)',
 P_PATH='@t6g_mb_lib.t6g(sch_1):page88_i411@pure_quanta.sconn288_ddr506112002kq(~
chips)',
 PATH='I411',
 DRAWING='@T6G_MB_LIB.T6G(SCH_1):PAGE87',
 PART_TYPE='SMLF',
 MATERIAL='IO',
 PHYS_PAGE='88',
 XY='(-4675,3950)',
 ROT='0',
 VER='2',
 LOCATION='J17',
 CDS_LIB='pure_quanta',
 CDS_PART_NAME='SCONN288_DDR506112002KQ-SCONN288_DDR506112002KQ,SMA',
 PART_NUMBER='DFHST8FS479',
 VALUE='SCONN288_DDR506112002KQ',
 PRIM_FILE='./archive_libs/logical/sconn288_ddr506112002kq/chips/chips.prt';

SECTION_NUMBER 3
 '@T6G_MB_LIB.T6G(SCH_1):PAGE87_I352@PURE_QUANTA.SCONN288_DDR506112002KQ(CHIPS)':
 C_PATH='@t6g_mb_lib.t6g(sch_1):page87_i352@pure_quanta.sconn288_ddr506112002kq(~
chips)',
 P_PATH='@t6g_mb_lib.t6g(sch_1):page88_i352@pure_quanta.sconn288_ddr506112002kq(~
chips)',
 PATH='I352',
 DRAWING='@T6G_MB_LIB.T6G(SCH_1):PAGE87',
 PART_TYPE='SMLF',
 MATERIAL='IO',
 PHYS_PAGE='88',
 XY='(-1400,4050)',
 ROT='0',
 VER='3',
 LOCATION='J17',
 CDS_LIB='pure_quanta',
 CDS_PART_NAME='SCONN288_DDR506112002KQ-SCONN288_DDR506112002KQ,SMA',
 PART_NUMBER='DFHST8FS479',
 VALUE='SCONN288_DDR506112002KQ',
 PRIM_FILE='./archive_libs/logical/sconn288_ddr506112002kq/chips/chips.prt';

PART_NAME
 J18 'SCONN288_DDR506112002KQ-SCONN288_DDR506112002KQ,SMA':;

SECTION_NUMBER 1
 '@T6G_MB_LIB.T6G(SCH_1):PAGE93_I22@PURE_QUANTA.SCONN288_DDR506112002KQ(CHIPS)':
 C_PATH='@t6g_mb_lib.t6g(sch_1):page93_i22@pure_quanta.sconn288_ddr506112002kq(c~
hips)',
 P_PATH='@t6g_mb_lib.t6g(sch_1):page94_i22@pure_quanta.sconn288_ddr506112002kq(c~
hips)',
 PATH='I22',
 DRAWING='@T6G_MB_LIB.T6G(SCH_1):PAGE93',
 PART_TYPE='SMLF',
 MATERIAL='IO',
 PHYS_PAGE='94',
 XY='(-6850,3700)',
 ROT='0',
 VER='1',
 LOCATION='J18',
 CDS_LIB='pure_quanta',
 CDS_PART_NAME='SCONN288_DDR506112002KQ-SCONN288_DDR506112002KQ,SMA',
 PART_NUMBER='DFHST8FS479',
 VALUE='SCONN288_DDR506112002KQ',
 PRIM_FILE='./archive_libs/logical/sconn288_ddr506112002kq/chips/chips.prt';

SECTION_NUMBER 2
 '@T6G_MB_LIB.T6G(SCH_1):PAGE93_I236@PURE_QUANTA.SCONN288_DDR506112002KQ(CHIPS)':
 C_PATH='@t6g_mb_lib.t6g(sch_1):page93_i236@pure_quanta.sconn288_ddr506112002kq(~
chips)',
 P_PATH='@t6g_mb_lib.t6g(sch_1):page94_i236@pure_quanta.sconn288_ddr506112002kq(~
chips)',
 PATH='I236',
 DRAWING='@T6G_MB_LIB.T6G(SCH_1):PAGE93',
 PART_TYPE='SMLF',
 MATERIAL='IO',
 PHYS_PAGE='94',
 XY='(-4400,3500)',
 ROT='0',
 VER='2',
 LOCATION='J18',
 CDS_LIB='pure_quanta',
 CDS_PART_NAME='SCONN288_DDR506112002KQ-SCONN288_DDR506112002KQ,SMA',
 PART_NUMBER='DFHST8FS479',
 VALUE='SCONN288_DDR506112002KQ',
 PRIM_FILE='./archive_libs/logical/sconn288_ddr506112002kq/chips/chips.prt';

SECTION_NUMBER 3
 '@T6G_MB_LIB.T6G(SCH_1):PAGE93_I143@PURE_QUANTA.SCONN288_DDR506112002KQ(CHIPS)':
 C_PATH='@t6g_mb_lib.t6g(sch_1):page93_i143@pure_quanta.sconn288_ddr506112002kq(~
chips)',
 P_PATH='@t6g_mb_lib.t6g(sch_1):page94_i143@pure_quanta.sconn288_ddr506112002kq(~
chips)',
 PATH='I143',
 DRAWING='@T6G_MB_LIB.T6G(SCH_1):PAGE93',
 PART_TYPE='SMLF',
 MATERIAL='IO',
 PHYS_PAGE='94',
 XY='(-1225,3800)',
 ROT='0',
 VER='3',
 LOCATION='J18',
 CDS_LIB='pure_quanta',
 CDS_PART_NAME='SCONN288_DDR506112002KQ-SCONN288_DDR506112002KQ,SMA',
 PART_NUMBER='DFHST8FS479',
 VALUE='SCONN288_DDR506112002KQ',
 PRIM_FILE='./archive_libs/logical/sconn288_ddr506112002kq/chips/chips.prt';

PART_NAME
 J19 'SCONN288_DDR506112002KQ-SCONN288_DDR506112002KQ,SMA':;

SECTION_NUMBER 1
 '@T6G_MB_LIB.T6G(SCH_1):PAGE88_I350@PURE_QUANTA.SCONN288_DDR506112002KQ(CHIPS)':
 C_PATH='@t6g_mb_lib.t6g(sch_1):page88_i350@pure_quanta.sconn288_ddr506112002kq(~
chips)',
 P_PATH='@t6g_mb_lib.t6g(sch_1):page89_i350@pure_quanta.sconn288_ddr506112002kq(~
chips)',
 PATH='I350',
 DRAWING='@T6G_MB_LIB.T6G(SCH_1):PAGE88',
 PART_TYPE='SMLF',
 MATERIAL='IO',
 PHYS_PAGE='89',
 XY='(-6925,3800)',
 ROT='0',
 VER='1',
 LOCATION='J19',
 CDS_LIB='pure_quanta',
 CDS_PART_NAME='SCONN288_DDR506112002KQ-SCONN288_DDR506112002KQ,SMA',
 PART_NUMBER='DFHST8FS479',
 VALUE='SCONN288_DDR506112002KQ',
 PRIM_FILE='./archive_libs/logical/sconn288_ddr506112002kq/chips/chips.prt';

SECTION_NUMBER 2
 '@T6G_MB_LIB.T6G(SCH_1):PAGE88_I415@PURE_QUANTA.SCONN288_DDR506112002KQ(CHIPS)':
 C_PATH='@t6g_mb_lib.t6g(sch_1):page88_i415@pure_quanta.sconn288_ddr506112002kq(~
chips)',
 P_PATH='@t6g_mb_lib.t6g(sch_1):page89_i415@pure_quanta.sconn288_ddr506112002kq(~
chips)',
 PATH='I415',
 DRAWING='@T6G_MB_LIB.T6G(SCH_1):PAGE88',
 PART_TYPE='SMLF',
 MATERIAL='IO',
 PHYS_PAGE='89',
 XY='(-4650,3625)',
 ROT='0',
 VER='2',
 LOCATION='J19',
 CDS_LIB='pure_quanta',
 CDS_PART_NAME='SCONN288_DDR506112002KQ-SCONN288_DDR506112002KQ,SMA',
 PART_NUMBER='DFHST8FS479',
 VALUE='SCONN288_DDR506112002KQ',
 PRIM_FILE='./archive_libs/logical/sconn288_ddr506112002kq/chips/chips.prt';

SECTION_NUMBER 3
 '@T6G_MB_LIB.T6G(SCH_1):PAGE88_I352@PURE_QUANTA.SCONN288_DDR506112002KQ(CHIPS)':
 C_PATH='@t6g_mb_lib.t6g(sch_1):page88_i352@pure_quanta.sconn288_ddr506112002kq(~
chips)',
 P_PATH='@t6g_mb_lib.t6g(sch_1):page89_i352@pure_quanta.sconn288_ddr506112002kq(~
chips)',
 PATH='I352',
 DRAWING='@T6G_MB_LIB.T6G(SCH_1):PAGE88',
 PART_TYPE='SMLF',
 MATERIAL='IO',
 PHYS_PAGE='89',
 XY='(-1350,3700)',
 ROT='0',
 VER='3',
 LOCATION='J19',
 CDS_LIB='pure_quanta',
 CDS_PART_NAME='SCONN288_DDR506112002KQ-SCONN288_DDR506112002KQ,SMA',
 PART_NUMBER='DFHST8FS479',
 VALUE='SCONN288_DDR506112002KQ',
 PRIM_FILE='./archive_libs/logical/sconn288_ddr506112002kq/chips/chips.prt';

PART_NAME
 J20 'SCONN288_DDR506112002KQ-SCONN288_DDR506112002KQ,SMA':;

SECTION_NUMBER 1
 '@T6G_MB_LIB.T6G(SCH_1):PAGE95_I22@PURE_QUANTA.SCONN288_DDR506112002KQ(CHIPS)':
 C_PATH='@t6g_mb_lib.t6g(sch_1):page95_i22@pure_quanta.sconn288_ddr506112002kq(c~
hips)',
 P_PATH='@t6g_mb_lib.t6g(sch_1):page96_i22@pure_quanta.sconn288_ddr506112002kq(c~
hips)',
 PATH='I22',
 DRAWING='@T6G_MB_LIB.T6G(SCH_1):PAGE95',
 PART_TYPE='SMLF',
 MATERIAL='IO',
 PHYS_PAGE='96',
 XY='(-6875,3625)',
 ROT='0',
 VER='1',
 LOCATION='J20',
 CDS_LIB='pure_quanta',
 CDS_PART_NAME='SCONN288_DDR506112002KQ-SCONN288_DDR506112002KQ,SMA',
 PART_NUMBER='DFHST8FS479',
 VALUE='SCONN288_DDR506112002KQ',
 PRIM_FILE='./archive_libs/logical/sconn288_ddr506112002kq/chips/chips.prt';

SECTION_NUMBER 2
 '@T6G_MB_LIB.T6G(SCH_1):PAGE95_I236@PURE_QUANTA.SCONN288_DDR506112002KQ(CHIPS)':
 C_PATH='@t6g_mb_lib.t6g(sch_1):page95_i236@pure_quanta.sconn288_ddr506112002kq(~
chips)',
 P_PATH='@t6g_mb_lib.t6g(sch_1):page96_i236@pure_quanta.sconn288_ddr506112002kq(~
chips)',
 PATH='I236',
 DRAWING='@T6G_MB_LIB.T6G(SCH_1):PAGE95',
 PART_TYPE='SMLF',
 MATERIAL='IO',
 PHYS_PAGE='96',
 XY='(-4425,3600)',
 ROT='0',
 VER='2',
 LOCATION='J20',
 CDS_LIB='pure_quanta',
 CDS_PART_NAME='SCONN288_DDR506112002KQ-SCONN288_DDR506112002KQ,SMA',
 PART_NUMBER='DFHST8FS479',
 VALUE='SCONN288_DDR506112002KQ',
 PRIM_FILE='./archive_libs/logical/sconn288_ddr506112002kq/chips/chips.prt';

SECTION_NUMBER 3
 '@T6G_MB_LIB.T6G(SCH_1):PAGE95_I177@PURE_QUANTA.SCONN288_DDR506112002KQ(CHIPS)':
 C_PATH='@t6g_mb_lib.t6g(sch_1):page95_i177@pure_quanta.sconn288_ddr506112002kq(~
chips)',
 P_PATH='@t6g_mb_lib.t6g(sch_1):page96_i177@pure_quanta.sconn288_ddr506112002kq(~
chips)',
 PATH='I177',
 DRAWING='@T6G_MB_LIB.T6G(SCH_1):PAGE95',
 PART_TYPE='SMLF',
 MATERIAL='IO',
 PHYS_PAGE='96',
 XY='(-1225,3675)',
 ROT='0',
 VER='3',
 LOCATION='J20',
 CDS_LIB='pure_quanta',
 CDS_PART_NAME='SCONN288_DDR506112002KQ-SCONN288_DDR506112002KQ,SMA',
 PART_NUMBER='DFHST8FS479',
 VALUE='SCONN288_DDR506112002KQ',
 PRIM_FILE='./archive_libs/logical/sconn288_ddr506112002kq/chips/chips.prt';

PART_NAME
 J21 'SCONN288_DDR506112002KQ-SCONN288_DDR506112002KQ,SMA':;

SECTION_NUMBER 1
 '@T6G_MB_LIB.T6G(SCH_1):PAGE89_I348@PURE_QUANTA.SCONN288_DDR506112002KQ(CHIPS)':
 C_PATH='@t6g_mb_lib.t6g(sch_1):page89_i348@pure_quanta.sconn288_ddr506112002kq(~
chips)',
 P_PATH='@t6g_mb_lib.t6g(sch_1):page90_i348@pure_quanta.sconn288_ddr506112002kq(~
chips)',
 PATH='I348',
 DRAWING='@T6G_MB_LIB.T6G(SCH_1):PAGE89',
 PART_TYPE='SMLF',
 MATERIAL='IO',
 PHYS_PAGE='90',
 XY='(-7125,3825)',
 ROT='0',
 VER='1',
 LOCATION='J21',
 CDS_LIB='pure_quanta',
 CDS_PART_NAME='SCONN288_DDR506112002KQ-SCONN288_DDR506112002KQ,SMA',
 PART_NUMBER='DFHST8FS479',
 VALUE='SCONN288_DDR506112002KQ',
 PRIM_FILE='./archive_libs/logical/sconn288_ddr506112002kq/chips/chips.prt';

SECTION_NUMBER 2
 '@T6G_MB_LIB.T6G(SCH_1):PAGE89_I410@PURE_QUANTA.SCONN288_DDR506112002KQ(CHIPS)':
 C_PATH='@t6g_mb_lib.t6g(sch_1):page89_i410@pure_quanta.sconn288_ddr506112002kq(~
chips)',
 P_PATH='@t6g_mb_lib.t6g(sch_1):page90_i410@pure_quanta.sconn288_ddr506112002kq(~
chips)',
 PATH='I410',
 DRAWING='@T6G_MB_LIB.T6G(SCH_1):PAGE89',
 PART_TYPE='SMLF',
 MATERIAL='IO',
 PHYS_PAGE='90',
 XY='(-4625,3675)',
 ROT='0',
 VER='2',
 LOCATION='J21',
 CDS_LIB='pure_quanta',
 CDS_PART_NAME='SCONN288_DDR506112002KQ-SCONN288_DDR506112002KQ,SMA',
 PART_NUMBER='DFHST8FS479',
 VALUE='SCONN288_DDR506112002KQ',
 PRIM_FILE='./archive_libs/logical/sconn288_ddr506112002kq/chips/chips.prt';

SECTION_NUMBER 3
 '@T6G_MB_LIB.T6G(SCH_1):PAGE89_I350@PURE_QUANTA.SCONN288_DDR506112002KQ(CHIPS)':
 C_PATH='@t6g_mb_lib.t6g(sch_1):page89_i350@pure_quanta.sconn288_ddr506112002kq(~
chips)',
 P_PATH='@t6g_mb_lib.t6g(sch_1):page90_i350@pure_quanta.sconn288_ddr506112002kq(~
chips)',
 PATH='I350',
 DRAWING='@T6G_MB_LIB.T6G(SCH_1):PAGE89',
 PART_TYPE='SMLF',
 MATERIAL='IO',
 PHYS_PAGE='90',
 XY='(-1400,3925)',
 ROT='0',
 VER='3',
 LOCATION='J21',
 CDS_LIB='pure_quanta',
 CDS_PART_NAME='SCONN288_DDR506112002KQ-SCONN288_DDR506112002KQ,SMA',
 PART_NUMBER='DFHST8FS479',
 VALUE='SCONN288_DDR506112002KQ',
 PRIM_FILE='./archive_libs/logical/sconn288_ddr506112002kq/chips/chips.prt';

PART_NAME
 J23 'SCONN288_DDR506112002KQ-SCONN288_DDR506112002KQ,SMA':;

SECTION_NUMBER 1
 '@T6G_MB_LIB.T6G(SCH_1):PAGE90_I350@PURE_QUANTA.SCONN288_DDR506112002KQ(CHIPS)':
 C_PATH='@t6g_mb_lib.t6g(sch_1):page90_i350@pure_quanta.sconn288_ddr506112002kq(~
chips)',
 P_PATH='@t6g_mb_lib.t6g(sch_1):page91_i350@pure_quanta.sconn288_ddr506112002kq(~
chips)',
 PATH='I350',
 DRAWING='@T6G_MB_LIB.T6G(SCH_1):PAGE90',
 PART_TYPE='SMLF',
 MATERIAL='IO',
 PHYS_PAGE='91',
 XY='(-6925,3975)',
 ROT='0',
 VER='1',
 LOCATION='J23',
 CDS_LIB='pure_quanta',
 CDS_PART_NAME='SCONN288_DDR506112002KQ-SCONN288_DDR506112002KQ,SMA',
 PART_NUMBER='DFHST8FS479',
 VALUE='SCONN288_DDR506112002KQ',
 PRIM_FILE='./archive_libs/logical/sconn288_ddr506112002kq/chips/chips.prt';

SECTION_NUMBER 2
 '@T6G_MB_LIB.T6G(SCH_1):PAGE90_I412@PURE_QUANTA.SCONN288_DDR506112002KQ(CHIPS)':
 C_PATH='@t6g_mb_lib.t6g(sch_1):page90_i412@pure_quanta.sconn288_ddr506112002kq(~
chips)',
 P_PATH='@t6g_mb_lib.t6g(sch_1):page91_i412@pure_quanta.sconn288_ddr506112002kq(~
chips)',
 PATH='I412',
 DRAWING='@T6G_MB_LIB.T6G(SCH_1):PAGE90',
 PART_TYPE='SMLF',
 MATERIAL='IO',
 PHYS_PAGE='91',
 XY='(-4525,3825)',
 ROT='0',
 VER='2',
 LOCATION='J23',
 CDS_LIB='pure_quanta',
 CDS_PART_NAME='SCONN288_DDR506112002KQ-SCONN288_DDR506112002KQ,SMA',
 PART_NUMBER='DFHST8FS479',
 VALUE='SCONN288_DDR506112002KQ',
 PRIM_FILE='./archive_libs/logical/sconn288_ddr506112002kq/chips/chips.prt';

SECTION_NUMBER 3
 '@T6G_MB_LIB.T6G(SCH_1):PAGE90_I352@PURE_QUANTA.SCONN288_DDR506112002KQ(CHIPS)':
 C_PATH='@t6g_mb_lib.t6g(sch_1):page90_i352@pure_quanta.sconn288_ddr506112002kq(~
chips)',
 P_PATH='@t6g_mb_lib.t6g(sch_1):page91_i352@pure_quanta.sconn288_ddr506112002kq(~
chips)',
 PATH='I352',
 DRAWING='@T6G_MB_LIB.T6G(SCH_1):PAGE90',
 PART_TYPE='SMLF',
 MATERIAL='IO',
 PHYS_PAGE='91',
 XY='(-1325,3950)',
 ROT='0',
 VER='3',
 LOCATION='J23',
 CDS_LIB='pure_quanta',
 CDS_PART_NAME='SCONN288_DDR506112002KQ-SCONN288_DDR506112002KQ,SMA',
 PART_NUMBER='DFHST8FS479',
 VALUE='SCONN288_DDR506112002KQ',
 PRIM_FILE='./archive_libs/logical/sconn288_ddr506112002kq/chips/chips.prt';

PART_NAME
 J24 'SCONN288_DDR506112002KQ-SCONN288_DDR506112002KQ,SMA':;

SECTION_NUMBER 1
 '@T6G_MB_LIB.T6G(SCH_1):PAGE97_I22@PURE_QUANTA.SCONN288_DDR506112002KQ(CHIPS)':
 C_PATH='@t6g_mb_lib.t6g(sch_1):page97_i22@pure_quanta.sconn288_ddr506112002kq(c~
hips)',
 P_PATH='@t6g_mb_lib.t6g(sch_1):page98_i22@pure_quanta.sconn288_ddr506112002kq(c~
hips)',
 PATH='I22',
 DRAWING='@T6G_MB_LIB.T6G(SCH_1):PAGE97',
 PART_TYPE='SMLF',
 MATERIAL='IO',
 PHYS_PAGE='98',
 XY='(-6600,3725)',
 ROT='0',
 VER='1',
 LOCATION='J24',
 CDS_LIB='pure_quanta',
 CDS_PART_NAME='SCONN288_DDR506112002KQ-SCONN288_DDR506112002KQ,SMA',
 PART_NUMBER='DFHST8FS479',
 VALUE='SCONN288_DDR506112002KQ',
 PRIM_FILE='./archive_libs/logical/sconn288_ddr506112002kq/chips/chips.prt';

SECTION_NUMBER 2
 '@T6G_MB_LIB.T6G(SCH_1):PAGE97_I238@PURE_QUANTA.SCONN288_DDR506112002KQ(CHIPS)':
 C_PATH='@t6g_mb_lib.t6g(sch_1):page97_i238@pure_quanta.sconn288_ddr506112002kq(~
chips)',
 P_PATH='@t6g_mb_lib.t6g(sch_1):page98_i238@pure_quanta.sconn288_ddr506112002kq(~
chips)',
 PATH='I238',
 DRAWING='@T6G_MB_LIB.T6G(SCH_1):PAGE97',
 PART_TYPE='SMLF',
 MATERIAL='IO',
 PHYS_PAGE='98',
 XY='(-4225,3600)',
 ROT='0',
 VER='2',
 LOCATION='J24',
 CDS_LIB='pure_quanta',
 CDS_PART_NAME='SCONN288_DDR506112002KQ-SCONN288_DDR506112002KQ,SMA',
 PART_NUMBER='DFHST8FS479',
 VALUE='SCONN288_DDR506112002KQ',
 PRIM_FILE='./archive_libs/logical/sconn288_ddr506112002kq/chips/chips.prt';

SECTION_NUMBER 3
 '@T6G_MB_LIB.T6G(SCH_1):PAGE97_I177@PURE_QUANTA.SCONN288_DDR506112002KQ(CHIPS)':
 C_PATH='@t6g_mb_lib.t6g(sch_1):page97_i177@pure_quanta.sconn288_ddr506112002kq(~
chips)',
 P_PATH='@t6g_mb_lib.t6g(sch_1):page98_i177@pure_quanta.sconn288_ddr506112002kq(~
chips)',
 PATH='I177',
 DRAWING='@T6G_MB_LIB.T6G(SCH_1):PAGE97',
 PART_TYPE='SMLF',
 MATERIAL='IO',
 PHYS_PAGE='98',
 XY='(-1300,3825)',
 ROT='0',
 VER='3',
 LOCATION='J24',
 CDS_LIB='pure_quanta',
 CDS_PART_NAME='SCONN288_DDR506112002KQ-SCONN288_DDR506112002KQ,SMA',
 PART_NUMBER='DFHST8FS479',
 VALUE='SCONN288_DDR506112002KQ',
 PRIM_FILE='./archive_libs/logical/sconn288_ddr506112002kq/chips/chips.prt';

PART_NAME
 J26 'SCONN288_DDR506112002KQ-SCONN288_DDR506112002KQ,SMA':;

SECTION_NUMBER 1
 '@T6G_MB_LIB.T6G(SCH_1):PAGE98_I22@PURE_QUANTA.SCONN288_DDR506112002KQ(CHIPS)':
 C_PATH='@t6g_mb_lib.t6g(sch_1):page98_i22@pure_quanta.sconn288_ddr506112002kq(c~
hips)',
 P_PATH='@t6g_mb_lib.t6g(sch_1):page99_i22@pure_quanta.sconn288_ddr506112002kq(c~
hips)',
 PATH='I22',
 DRAWING='@T6G_MB_LIB.T6G(SCH_1):PAGE98',
 PART_TYPE='SMLF',
 MATERIAL='IO',
 PHYS_PAGE='99',
 XY='(-6925,3775)',
 ROT='0',
 VER='1',
 LOCATION='J26',
 CDS_LIB='pure_quanta',
 CDS_PART_NAME='SCONN288_DDR506112002KQ-SCONN288_DDR506112002KQ,SMA',
 PART_NUMBER='DFHST8FS479',
 VALUE='SCONN288_DDR506112002KQ',
 PRIM_FILE='./archive_libs/logical/sconn288_ddr506112002kq/chips/chips.prt';

SECTION_NUMBER 2
 '@T6G_MB_LIB.T6G(SCH_1):PAGE98_I236@PURE_QUANTA.SCONN288_DDR506112002KQ(CHIPS)':
 C_PATH='@t6g_mb_lib.t6g(sch_1):page98_i236@pure_quanta.sconn288_ddr506112002kq(~
chips)',
 P_PATH='@t6g_mb_lib.t6g(sch_1):page99_i236@pure_quanta.sconn288_ddr506112002kq(~
chips)',
 PATH='I236',
 DRAWING='@T6G_MB_LIB.T6G(SCH_1):PAGE98',
 PART_TYPE='SMLF',
 MATERIAL='IO',
 PHYS_PAGE='99',
 XY='(-4400,3500)',
 ROT='0',
 VER='2',
 LOCATION='J26',
 CDS_LIB='pure_quanta',
 CDS_PART_NAME='SCONN288_DDR506112002KQ-SCONN288_DDR506112002KQ,SMA',
 PART_NUMBER='DFHST8FS479',
 VALUE='SCONN288_DDR506112002KQ',
 PRIM_FILE='./archive_libs/logical/sconn288_ddr506112002kq/chips/chips.prt';

SECTION_NUMBER 3
 '@T6G_MB_LIB.T6G(SCH_1):PAGE98_I160@PURE_QUANTA.SCONN288_DDR506112002KQ(CHIPS)':
 C_PATH='@t6g_mb_lib.t6g(sch_1):page98_i160@pure_quanta.sconn288_ddr506112002kq(~
chips)',
 P_PATH='@t6g_mb_lib.t6g(sch_1):page99_i160@pure_quanta.sconn288_ddr506112002kq(~
chips)',
 PATH='I160',
 DRAWING='@T6G_MB_LIB.T6G(SCH_1):PAGE98',
 PART_TYPE='SMLF',
 MATERIAL='IO',
 PHYS_PAGE='99',
 XY='(-1275,3475)',
 ROT='0',
 VER='3',
 LOCATION='J26',
 CDS_LIB='pure_quanta',
 CDS_PART_NAME='SCONN288_DDR506112002KQ-SCONN288_DDR506112002KQ,SMA',
 PART_NUMBER='DFHST8FS479',
 VALUE='SCONN288_DDR506112002KQ',
 PRIM_FILE='./archive_libs/logical/sconn288_ddr506112002kq/chips/chips.prt';

PART_NAME
 J27 'SCONN288_DDR506112002KQ-SCONN288_DDR506112002KQ,SMA':;

SECTION_NUMBER 1
 '@T6G_MB_LIB.T6G(SCH_1):PAGE104_I22@PURE_QUANTA.SCONN288_DDR506112002KQ(CHIPS)':
 C_PATH='@t6g_mb_lib.t6g(sch_1):page104_i22@pure_quanta.sconn288_ddr506112002kq(~
chips)',
 P_PATH='@t6g_mb_lib.t6g(sch_1):page105_i22@pure_quanta.sconn288_ddr506112002kq(~
chips)',
 PATH='I22',
 DRAWING='@T6G_MB_LIB.T6G(SCH_1):PAGE104',
 PART_TYPE='SMLF',
 MATERIAL='IO',
 PHYS_PAGE='105',
 XY='(-6800,3650)',
 ROT='0',
 VER='1',
 LOCATION='J27',
 CDS_LIB='pure_quanta',
 CDS_PART_NAME='SCONN288_DDR506112002KQ-SCONN288_DDR506112002KQ,SMA',
 PART_NUMBER='DFHST8FS479',
 VALUE='SCONN288_DDR506112002KQ',
 PRIM_FILE='./archive_libs/logical/sconn288_ddr506112002kq/chips/chips.prt';

SECTION_NUMBER 2
 '@T6G_MB_LIB.T6G(SCH_1):PAGE104_I238@PURE_QUANTA.SCONN288_DDR506112002KQ(CHIPS)':
 C_PATH='@t6g_mb_lib.t6g(sch_1):page104_i238@pure_quanta.sconn288_ddr506112002kq~
(chips)',
 P_PATH='@t6g_mb_lib.t6g(sch_1):page105_i238@pure_quanta.sconn288_ddr506112002kq~
(chips)',
 PATH='I238',
 DRAWING='@T6G_MB_LIB.T6G(SCH_1):PAGE104',
 PART_TYPE='SMLF',
 MATERIAL='IO',
 PHYS_PAGE='105',
 XY='(-4375,3425)',
 ROT='0',
 VER='2',
 LOCATION='J27',
 CDS_LIB='pure_quanta',
 CDS_PART_NAME='SCONN288_DDR506112002KQ-SCONN288_DDR506112002KQ,SMA',
 PART_NUMBER='DFHST8FS479',
 VALUE='SCONN288_DDR506112002KQ',
 PRIM_FILE='./archive_libs/logical/sconn288_ddr506112002kq/chips/chips.prt';

SECTION_NUMBER 3
 '@T6G_MB_LIB.T6G(SCH_1):PAGE104_I174@PURE_QUANTA.SCONN288_DDR506112002KQ(CHIPS)':
 C_PATH='@t6g_mb_lib.t6g(sch_1):page104_i174@pure_quanta.sconn288_ddr506112002kq~
(chips)',
 P_PATH='@t6g_mb_lib.t6g(sch_1):page105_i174@pure_quanta.sconn288_ddr506112002kq~
(chips)',
 PATH='I174',
 DRAWING='@T6G_MB_LIB.T6G(SCH_1):PAGE104',
 PART_TYPE='SMLF',
 MATERIAL='IO',
 PHYS_PAGE='105',
 XY='(-1225,3650)',
 ROT='0',
 VER='3',
 LOCATION='J27',
 CDS_LIB='pure_quanta',
 CDS_PART_NAME='SCONN288_DDR506112002KQ-SCONN288_DDR506112002KQ,SMA',
 PART_NUMBER='DFHST8FS479',
 VALUE='SCONN288_DDR506112002KQ',
 PRIM_FILE='./archive_libs/logical/sconn288_ddr506112002kq/chips/chips.prt';

PART_NAME
 J28 'SCONN288_DDR506112002KQ-SCONN288_DDR506112002KQ,SMA':;

SECTION_NUMBER 1
 '@T6G_MB_LIB.T6G(SCH_1):PAGE99_I22@PURE_QUANTA.SCONN288_DDR506112002KQ(CHIPS)':
 C_PATH='@t6g_mb_lib.t6g(sch_1):page99_i22@pure_quanta.sconn288_ddr506112002kq(c~
hips)',
 P_PATH='@t6g_mb_lib.t6g(sch_1):page100_i22@pure_quanta.sconn288_ddr506112002kq(~
chips)',
 PATH='I22',
 DRAWING='@T6G_MB_LIB.T6G(SCH_1):PAGE99',
 PART_TYPE='SMLF',
 MATERIAL='IO',
 PHYS_PAGE='100',
 XY='(-7050,3650)',
 ROT='0',
 VER='1',
 LOCATION='J28',
 CDS_LIB='pure_quanta',
 CDS_PART_NAME='SCONN288_DDR506112002KQ-SCONN288_DDR506112002KQ,SMA',
 PART_NUMBER='DFHST8FS479',
 VALUE='SCONN288_DDR506112002KQ',
 PRIM_FILE='./archive_libs/logical/sconn288_ddr506112002kq/chips/chips.prt';

SECTION_NUMBER 2
 '@T6G_MB_LIB.T6G(SCH_1):PAGE99_I236@PURE_QUANTA.SCONN288_DDR506112002KQ(CHIPS)':
 C_PATH='@t6g_mb_lib.t6g(sch_1):page99_i236@pure_quanta.sconn288_ddr506112002kq(~
chips)',
 P_PATH='@t6g_mb_lib.t6g(sch_1):page100_i236@pure_quanta.sconn288_ddr506112002kq~
(chips)',
 PATH='I236',
 DRAWING='@T6G_MB_LIB.T6G(SCH_1):PAGE99',
 PART_TYPE='SMLF',
 MATERIAL='IO',
 PHYS_PAGE='100',
 XY='(-4500,3550)',
 ROT='0',
 VER='2',
 LOCATION='J28',
 CDS_LIB='pure_quanta',
 CDS_PART_NAME='SCONN288_DDR506112002KQ-SCONN288_DDR506112002KQ,SMA',
 PART_NUMBER='DFHST8FS479',
 VALUE='SCONN288_DDR506112002KQ',
 PRIM_FILE='./archive_libs/logical/sconn288_ddr506112002kq/chips/chips.prt';

SECTION_NUMBER 3
 '@T6G_MB_LIB.T6G(SCH_1):PAGE99_I155@PURE_QUANTA.SCONN288_DDR506112002KQ(CHIPS)':
 C_PATH='@t6g_mb_lib.t6g(sch_1):page99_i155@pure_quanta.sconn288_ddr506112002kq(~
chips)',
 P_PATH='@t6g_mb_lib.t6g(sch_1):page100_i155@pure_quanta.sconn288_ddr506112002kq~
(chips)',
 PATH='I155',
 DRAWING='@T6G_MB_LIB.T6G(SCH_1):PAGE99',
 PART_TYPE='SMLF',
 MATERIAL='IO',
 PHYS_PAGE='100',
 XY='(-1325,3750)',
 ROT='0',
 VER='3',
 LOCATION='J28',
 CDS_LIB='pure_quanta',
 CDS_PART_NAME='SCONN288_DDR506112002KQ-SCONN288_DDR506112002KQ,SMA',
 PART_NUMBER='DFHST8FS479',
 VALUE='SCONN288_DDR506112002KQ',
 PRIM_FILE='./archive_libs/logical/sconn288_ddr506112002kq/chips/chips.prt';

PART_NAME
 J29 'SCONN288_DDR506112002KQ-SCONN288_DDR506112002KQ,SMA':;

SECTION_NUMBER 1
 '@T6G_MB_LIB.T6G(SCH_1):PAGE106_I22@PURE_QUANTA.SCONN288_DDR506112002KQ(CHIPS)':
 C_PATH='@t6g_mb_lib.t6g(sch_1):page106_i22@pure_quanta.sconn288_ddr506112002kq(~
chips)',
 P_PATH='@t6g_mb_lib.t6g(sch_1):page107_i22@pure_quanta.sconn288_ddr506112002kq(~
chips)',
 PATH='I22',
 DRAWING='@T6G_MB_LIB.T6G(SCH_1):PAGE106',
 PART_TYPE='SMLF',
 MATERIAL='IO',
 PHYS_PAGE='107',
 XY='(-6700,3575)',
 ROT='0',
 VER='1',
 LOCATION='J29',
 CDS_LIB='pure_quanta',
 CDS_PART_NAME='SCONN288_DDR506112002KQ-SCONN288_DDR506112002KQ,SMA',
 PART_NUMBER='DFHST8FS479',
 VALUE='SCONN288_DDR506112002KQ',
 PRIM_FILE='./archive_libs/logical/sconn288_ddr506112002kq/chips/chips.prt';

SECTION_NUMBER 2
 '@T6G_MB_LIB.T6G(SCH_1):PAGE106_I236@PURE_QUANTA.SCONN288_DDR506112002KQ(CHIPS)':
 C_PATH='@t6g_mb_lib.t6g(sch_1):page106_i236@pure_quanta.sconn288_ddr506112002kq~
(chips)',
 P_PATH='@t6g_mb_lib.t6g(sch_1):page107_i236@pure_quanta.sconn288_ddr506112002kq~
(chips)',
 PATH='I236',
 DRAWING='@T6G_MB_LIB.T6G(SCH_1):PAGE106',
 PART_TYPE='SMLF',
 MATERIAL='IO',
 PHYS_PAGE='107',
 XY='(-4300,3650)',
 ROT='0',
 VER='2',
 LOCATION='J29',
 CDS_LIB='pure_quanta',
 CDS_PART_NAME='SCONN288_DDR506112002KQ-SCONN288_DDR506112002KQ,SMA',
 PART_NUMBER='DFHST8FS479',
 VALUE='SCONN288_DDR506112002KQ',
 PRIM_FILE='./archive_libs/logical/sconn288_ddr506112002kq/chips/chips.prt';

SECTION_NUMBER 3
 '@T6G_MB_LIB.T6G(SCH_1):PAGE106_I143@PURE_QUANTA.SCONN288_DDR506112002KQ(CHIPS)':
 C_PATH='@t6g_mb_lib.t6g(sch_1):page106_i143@pure_quanta.sconn288_ddr506112002kq~
(chips)',
 P_PATH='@t6g_mb_lib.t6g(sch_1):page107_i143@pure_quanta.sconn288_ddr506112002kq~
(chips)',
 PATH='I143',
 DRAWING='@T6G_MB_LIB.T6G(SCH_1):PAGE106',
 PART_TYPE='SMLF',
 MATERIAL='IO',
 PHYS_PAGE='107',
 XY='(-1125,3575)',
 ROT='0',
 VER='3',
 LOCATION='J29',
 CDS_LIB='pure_quanta',
 CDS_PART_NAME='SCONN288_DDR506112002KQ-SCONN288_DDR506112002KQ,SMA',
 PART_NUMBER='DFHST8FS479',
 VALUE='SCONN288_DDR506112002KQ',
 PRIM_FILE='./archive_libs/logical/sconn288_ddr506112002kq/chips/chips.prt';

PART_NAME
 J30 'SCONN288_DDR506112002KQ-SCONN288_DDR506112002KQ,SMA':;

SECTION_NUMBER 1
 '@T6G_MB_LIB.T6G(SCH_1):PAGE100_I52@PURE_QUANTA.SCONN288_DDR506112002KQ(CHIPS)':
 C_PATH='@t6g_mb_lib.t6g(sch_1):page100_i52@pure_quanta.sconn288_ddr506112002kq(~
chips)',
 P_PATH='@t6g_mb_lib.t6g(sch_1):page101_i52@pure_quanta.sconn288_ddr506112002kq(~
chips)',
 PATH='I52',
 DRAWING='@T6G_MB_LIB.T6G(SCH_1):PAGE100',
 PART_TYPE='SMLF',
 MATERIAL='IO',
 PHYS_PAGE='101',
 XY='(-6950,3825)',
 ROT='0',
 VER='1',
 LOCATION='J30',
 CDS_LIB='pure_quanta',
 CDS_PART_NAME='SCONN288_DDR506112002KQ-SCONN288_DDR506112002KQ,SMA',
 PART_NUMBER='DFHST8FS479',
 VALUE='SCONN288_DDR506112002KQ',
 PRIM_FILE='./archive_libs/logical/sconn288_ddr506112002kq/chips/chips.prt';

SECTION_NUMBER 2
 '@T6G_MB_LIB.T6G(SCH_1):PAGE100_I236@PURE_QUANTA.SCONN288_DDR506112002KQ(CHIPS)':
 C_PATH='@t6g_mb_lib.t6g(sch_1):page100_i236@pure_quanta.sconn288_ddr506112002kq~
(chips)',
 P_PATH='@t6g_mb_lib.t6g(sch_1):page101_i236@pure_quanta.sconn288_ddr506112002kq~
(chips)',
 PATH='I236',
 DRAWING='@T6G_MB_LIB.T6G(SCH_1):PAGE100',
 PART_TYPE='SMLF',
 MATERIAL='IO',
 PHYS_PAGE='101',
 XY='(-4425,3725)',
 ROT='0',
 VER='2',
 LOCATION='J30',
 CDS_LIB='pure_quanta',
 CDS_PART_NAME='SCONN288_DDR506112002KQ-SCONN288_DDR506112002KQ,SMA',
 PART_NUMBER='DFHST8FS479',
 VALUE='SCONN288_DDR506112002KQ',
 PRIM_FILE='./archive_libs/logical/sconn288_ddr506112002kq/chips/chips.prt';

SECTION_NUMBER 3
 '@T6G_MB_LIB.T6G(SCH_1):PAGE100_I161@PURE_QUANTA.SCONN288_DDR506112002KQ(CHIPS)':
 C_PATH='@t6g_mb_lib.t6g(sch_1):page100_i161@pure_quanta.sconn288_ddr506112002kq~
(chips)',
 P_PATH='@t6g_mb_lib.t6g(sch_1):page101_i161@pure_quanta.sconn288_ddr506112002kq~
(chips)',
 PATH='I161',
 DRAWING='@T6G_MB_LIB.T6G(SCH_1):PAGE100',
 PART_TYPE='SMLF',
 MATERIAL='IO',
 PHYS_PAGE='101',
 XY='(-1300,3750)',
 ROT='0',
 VER='3',
 LOCATION='J30',
 CDS_LIB='pure_quanta',
 CDS_PART_NAME='SCONN288_DDR506112002KQ-SCONN288_DDR506112002KQ,SMA',
 PART_NUMBER='DFHST8FS479',
 VALUE='SCONN288_DDR506112002KQ',
 PRIM_FILE='./archive_libs/logical/sconn288_ddr506112002kq/chips/chips.prt';

PART_NAME
 J32 'SCONN288_DDR506112002KQ-SCONN288_DDR506112002KQ,SMA':;

SECTION_NUMBER 1
 '@T6G_MB_LIB.T6G(SCH_1):PAGE101_I52@PURE_QUANTA.SCONN288_DDR506112002KQ(CHIPS)':
 C_PATH='@t6g_mb_lib.t6g(sch_1):page101_i52@pure_quanta.sconn288_ddr506112002kq(~
chips)',
 P_PATH='@t6g_mb_lib.t6g(sch_1):page102_i52@pure_quanta.sconn288_ddr506112002kq(~
chips)',
 PATH='I52',
 DRAWING='@T6G_MB_LIB.T6G(SCH_1):PAGE101',
 PART_TYPE='SMLF',
 MATERIAL='IO',
 PHYS_PAGE='102',
 XY='(-7025,3900)',
 ROT='0',
 VER='1',
 LOCATION='J32',
 CDS_LIB='pure_quanta',
 CDS_PART_NAME='SCONN288_DDR506112002KQ-SCONN288_DDR506112002KQ,SMA',
 PART_NUMBER='DFHST8FS479',
 VALUE='SCONN288_DDR506112002KQ',
 PRIM_FILE='./archive_libs/logical/sconn288_ddr506112002kq/chips/chips.prt';

SECTION_NUMBER 2
 '@T6G_MB_LIB.T6G(SCH_1):PAGE101_I236@PURE_QUANTA.SCONN288_DDR506112002KQ(CHIPS)':
 C_PATH='@t6g_mb_lib.t6g(sch_1):page101_i236@pure_quanta.sconn288_ddr506112002kq~
(chips)',
 P_PATH='@t6g_mb_lib.t6g(sch_1):page102_i236@pure_quanta.sconn288_ddr506112002kq~
(chips)',
 PATH='I236',
 DRAWING='@T6G_MB_LIB.T6G(SCH_1):PAGE101',
 PART_TYPE='SMLF',
 MATERIAL='IO',
 PHYS_PAGE='102',
 XY='(-4425,3775)',
 ROT='0',
 VER='2',
 LOCATION='J32',
 CDS_LIB='pure_quanta',
 CDS_PART_NAME='SCONN288_DDR506112002KQ-SCONN288_DDR506112002KQ,SMA',
 PART_NUMBER='DFHST8FS479',
 VALUE='SCONN288_DDR506112002KQ',
 PRIM_FILE='./archive_libs/logical/sconn288_ddr506112002kq/chips/chips.prt';

SECTION_NUMBER 3
 '@T6G_MB_LIB.T6G(SCH_1):PAGE101_I175@PURE_QUANTA.SCONN288_DDR506112002KQ(CHIPS)':
 C_PATH='@t6g_mb_lib.t6g(sch_1):page101_i175@pure_quanta.sconn288_ddr506112002kq~
(chips)',
 P_PATH='@t6g_mb_lib.t6g(sch_1):page102_i175@pure_quanta.sconn288_ddr506112002kq~
(chips)',
 PATH='I175',
 DRAWING='@T6G_MB_LIB.T6G(SCH_1):PAGE101',
 PART_TYPE='SMLF',
 MATERIAL='IO',
 PHYS_PAGE='102',
 XY='(-1275,4000)',
 ROT='0',
 VER='3',
 LOCATION='J32',
 CDS_LIB='pure_quanta',
 CDS_PART_NAME='SCONN288_DDR506112002KQ-SCONN288_DDR506112002KQ,SMA',
 PART_NUMBER='DFHST8FS479',
 VALUE='SCONN288_DDR506112002KQ',
 PRIM_FILE='./archive_libs/logical/sconn288_ddr506112002kq/chips/chips.prt';

PART_NAME
 J33 'SCONN288_DDR506112002KQ-SCONN288_DDR506112002KQ,SMA':;

SECTION_NUMBER 1
 '@T6G_MB_LIB.T6G(SCH_1):PAGE102_I22@PURE_QUANTA.SCONN288_DDR506112002KQ(CHIPS)':
 C_PATH='@t6g_mb_lib.t6g(sch_1):page102_i22@pure_quanta.sconn288_ddr506112002kq(~
chips)',
 P_PATH='@t6g_mb_lib.t6g(sch_1):page103_i22@pure_quanta.sconn288_ddr506112002kq(~
chips)',
 PATH='I22',
 DRAWING='@T6G_MB_LIB.T6G(SCH_1):PAGE102',
 PART_TYPE='SMLF',
 MATERIAL='IO',
 PHYS_PAGE='103',
 XY='(-6975,3775)',
 ROT='0',
 VER='1',
 LOCATION='J33',
 CDS_LIB='pure_quanta',
 CDS_PART_NAME='SCONN288_DDR506112002KQ-SCONN288_DDR506112002KQ,SMA',
 PART_NUMBER='DFHST8FS479',
 VALUE='SCONN288_DDR506112002KQ',
 PRIM_FILE='./archive_libs/logical/sconn288_ddr506112002kq/chips/chips.prt';

SECTION_NUMBER 2
 '@T6G_MB_LIB.T6G(SCH_1):PAGE102_I236@PURE_QUANTA.SCONN288_DDR506112002KQ(CHIPS)':
 C_PATH='@t6g_mb_lib.t6g(sch_1):page102_i236@pure_quanta.sconn288_ddr506112002kq~
(chips)',
 P_PATH='@t6g_mb_lib.t6g(sch_1):page103_i236@pure_quanta.sconn288_ddr506112002kq~
(chips)',
 PATH='I236',
 DRAWING='@T6G_MB_LIB.T6G(SCH_1):PAGE102',
 PART_TYPE='SMLF',
 MATERIAL='IO',
 PHYS_PAGE='103',
 XY='(-4450,3700)',
 ROT='0',
 VER='2',
 LOCATION='J33',
 CDS_LIB='pure_quanta',
 CDS_PART_NAME='SCONN288_DDR506112002KQ-SCONN288_DDR506112002KQ,SMA',
 PART_NUMBER='DFHST8FS479',
 VALUE='SCONN288_DDR506112002KQ',
 PRIM_FILE='./archive_libs/logical/sconn288_ddr506112002kq/chips/chips.prt';

SECTION_NUMBER 3
 '@T6G_MB_LIB.T6G(SCH_1):PAGE102_I142@PURE_QUANTA.SCONN288_DDR506112002KQ(CHIPS)':
 C_PATH='@t6g_mb_lib.t6g(sch_1):page102_i142@pure_quanta.sconn288_ddr506112002kq~
(chips)',
 P_PATH='@t6g_mb_lib.t6g(sch_1):page103_i142@pure_quanta.sconn288_ddr506112002kq~
(chips)',
 PATH='I142',
 DRAWING='@T6G_MB_LIB.T6G(SCH_1):PAGE102',
 PART_TYPE='SMLF',
 MATERIAL='IO',
 PHYS_PAGE='103',
 XY='(-1300,3775)',
 ROT='0',
 VER='3',
 LOCATION='J33',
 CDS_LIB='pure_quanta',
 CDS_PART_NAME='SCONN288_DDR506112002KQ-SCONN288_DDR506112002KQ,SMA',
 PART_NUMBER='DFHST8FS479',
 VALUE='SCONN288_DDR506112002KQ',
 PRIM_FILE='./archive_libs/logical/sconn288_ddr506112002kq/chips/chips.prt';

PART_NAME
 J35 'SCONN168_ME1016810202011-SCONN168_ME1016810202011,A':;

SECTION_NUMBER 1
 '@T6G_MB_LIB.T6G(SCH_1):PAGE341_I168@PURE_QUANTA.SCONN168_ME1016810202011(CHIPS)':
 C_PATH='@t6g_mb_lib.t6g(sch_1):page341_i168@pure_quanta.sconn168_me101681020201~
1(chips)',
 P_PATH='@t6g_mb_lib.t6g(sch_1):page137_i168@pure_quanta.sconn168_me101681020201~
1(chips)',
 PATH='I168',
 DRAWING='@T6G_MB_LIB.T6G(SCH_1):PAGE341',
 PART_TYPE='SMLF',
 MATERIAL='IO',
 PHYS_PAGE='137',
 XY='(4475,2750)',
 ROT='0',
 VER='1',
 LOCATION='J35',
 CDS_LIB='pure_quanta',
 CDS_PART_NAME='SCONN168_ME1016810202011-SCONN168_ME1016810202011,A',
 PART_NUMBER='DFHSG8FR011',
 VALUE='SCONN168_ME1016810202011',
 PRIM_FILE='./archive_libs/logical/sconn168_me1016810202011/chips/chips.prt';

PART_NAME
 J37 'SCONN288_DDR506112002KQ-SCONN288_DDR506112002KQ,SMA':;

SECTION_NUMBER 1
 '@T6G_MB_LIB.T6G(SCH_1):PAGE108_I22@PURE_QUANTA.SCONN288_DDR506112002KQ(CHIPS)':
 C_PATH='@t6g_mb_lib.t6g(sch_1):page108_i22@pure_quanta.sconn288_ddr506112002kq(~
chips)',
 P_PATH='@t6g_mb_lib.t6g(sch_1):page109_i22@pure_quanta.sconn288_ddr506112002kq(~
chips)',
 PATH='I22',
 DRAWING='@T6G_MB_LIB.T6G(SCH_1):PAGE108',
 PART_TYPE='SMLF',
 MATERIAL='IO',
 PHYS_PAGE='109',
 XY='(-6800,3650)',
 ROT='0',
 VER='1',
 LOCATION='J37',
 CDS_LIB='pure_quanta',
 CDS_PART_NAME='SCONN288_DDR506112002KQ-SCONN288_DDR506112002KQ,SMA',
 PART_NUMBER='DFHST8FS479',
 VALUE='SCONN288_DDR506112002KQ',
 PRIM_FILE='./archive_libs/logical/sconn288_ddr506112002kq/chips/chips.prt';

SECTION_NUMBER 2
 '@T6G_MB_LIB.T6G(SCH_1):PAGE108_I235@PURE_QUANTA.SCONN288_DDR506112002KQ(CHIPS)':
 C_PATH='@t6g_mb_lib.t6g(sch_1):page108_i235@pure_quanta.sconn288_ddr506112002kq~
(chips)',
 P_PATH='@t6g_mb_lib.t6g(sch_1):page109_i235@pure_quanta.sconn288_ddr506112002kq~
(chips)',
 PATH='I235',
 DRAWING='@T6G_MB_LIB.T6G(SCH_1):PAGE108',
 PART_TYPE='SMLF',
 MATERIAL='IO',
 PHYS_PAGE='109',
 XY='(-4350,3325)',
 ROT='0',
 VER='2',
 LOCATION='J37',
 CDS_LIB='pure_quanta',
 CDS_PART_NAME='SCONN288_DDR506112002KQ-SCONN288_DDR506112002KQ,SMA',
 PART_NUMBER='DFHST8FS479',
 VALUE='SCONN288_DDR506112002KQ',
 PRIM_FILE='./archive_libs/logical/sconn288_ddr506112002kq/chips/chips.prt';

SECTION_NUMBER 3
 '@T6G_MB_LIB.T6G(SCH_1):PAGE108_I138@PURE_QUANTA.SCONN288_DDR506112002KQ(CHIPS)':
 C_PATH='@t6g_mb_lib.t6g(sch_1):page108_i138@pure_quanta.sconn288_ddr506112002kq~
(chips)',
 P_PATH='@t6g_mb_lib.t6g(sch_1):page109_i138@pure_quanta.sconn288_ddr506112002kq~
(chips)',
 PATH='I138',
 DRAWING='@T6G_MB_LIB.T6G(SCH_1):PAGE108',
 PART_TYPE='SMLF',
 MATERIAL='IO',
 PHYS_PAGE='109',
 XY='(-1200,3675)',
 ROT='0',
 VER='3',
 LOCATION='J37',
 CDS_LIB='pure_quanta',
 CDS_PART_NAME='SCONN288_DDR506112002KQ-SCONN288_DDR506112002KQ,SMA',
 PART_NUMBER='DFHST8FS479',
 VALUE='SCONN288_DDR506112002KQ',
 PRIM_FILE='./archive_libs/logical/sconn288_ddr506112002kq/chips/chips.prt';

PART_NAME
 J38 'SCONN168_ME1016810202011-SCONN168_ME1016810202011,A':;

SECTION_NUMBER 1
 '@T6G_MB_LIB.T6G(SCH_1):PAGE335_I168@PURE_QUANTA.SCONN168_ME1016810202011(CHIPS)':
 C_PATH='@t6g_mb_lib.t6g(sch_1):page335_i168@pure_quanta.sconn168_me101681020201~
1(chips)',
 P_PATH='@t6g_mb_lib.t6g(sch_1):page131_i168@pure_quanta.sconn168_me101681020201~
1(chips)',
 PATH='I168',
 DRAWING='@T6G_MB_LIB.T6G(SCH_1):PAGE335',
 SEC_TYPE='',
 PART_TYPE='SMLF',
 MATERIAL='IO',
 PHYS_PAGE='131',
 XY='(-350,4725)',
 ROT='0',
 VER='1',
 LOCATION='J38',
 SEC='1',
 CDS_LIB='pure_quanta',
 CDS_PART_NAME='SCONN168_ME1016810202011-SCONN168_ME1016810202011,A',
 PART_NUMBER='DFHSG8FR011',
 VALUE='SCONN168_ME1016810202011',
 PRIM_FILE='./archive_libs/logical/sconn168_me1016810202011/chips/chips.prt';

PART_NAME
 J41 'SCONN168_ME1016810202011-SCONN168_ME1016810202011,A':;

SECTION_NUMBER 1
 '@T6G_MB_LIB.T6G(SCH_1):PAGE348_I176@PURE_QUANTA.SCONN168_ME1016810202011(CHIPS)':
 C_PATH='@t6g_mb_lib.t6g(sch_1):page348_i176@pure_quanta.sconn168_me101681020201~
1(chips)',
 P_PATH='@t6g_mb_lib.t6g(sch_1):page150_i176@pure_quanta.sconn168_me101681020201~
1(chips)',
 PATH='I176',
 DRAWING='@T6G_MB_LIB.T6G(SCH_1):PAGE348',
 SEC_TYPE='',
 PART_TYPE='SMLF',
 MATERIAL='IO',
 PHYS_PAGE='150',
 XY='(-12050,7100)',
 ROT='2',
 VER='1',
 LOCATION='J41',
 SEC='1',
 CDS_LIB='pure_quanta',
 CDS_PART_NAME='SCONN168_ME1016810202011-SCONN168_ME1016810202011,A',
 PART_NUMBER='DFHSG8FR011',
 VALUE='SCONN168_ME1016810202011',
 PRIM_FILE='./archive_libs/logical/sconn168_me1016810202011/chips/chips.prt';

PART_NAME
 J45 'CONN60_101062636003K02LF-CONN60_10106263-6003K02LFA':;

SECTION_NUMBER 1
 '@T6G_MB_LIB.T6G(SCH_1):PAGE363_I466@PURE_QUANTA.CONN60_101062636003K02LF(CHIPS)':
 C_PATH='@t6g_mb_lib.t6g(sch_1):page363_i466@pure_quanta.conn60_101062636003k02l~
f(chips)',
 P_PATH='@t6g_mb_lib.t6g(sch_1):page240_i466@pure_quanta.conn60_101062636003k02l~
f(chips)',
 PATH='I466',
 DRAWING='@T6G_MB_LIB.T6G(SCH_1):PAGE363',
 SEC_TYPE='',
 PART_TYPE='THLF',
 MATERIAL='IO',
 PHYS_PAGE='240',
 XY='(-3750,-75)',
 ROT='0',
 VER='1',
 LOCATION='J45',
 SEC='1',
 CDS_LIB='pure_quanta',
 CDS_PART_NAME='CONN60_101062636003K02LF-CONN60_10106263-6003K02LFA',
 PART_NUMBER='DFHD60MR024',
 VALUE='CONN60_10106263-6003K02LF',
 PRIM_FILE='./archive_libs/logical/conn60_101062636003k02lf/chips/chips.prt';

PART_NAME
 J48 'SCONN8_G802M0083150RD3HR-SCONN8_G802M0083150RD3HR,A':;

SECTION_NUMBER 1
 '@T6G_MB_LIB.T6G(SCH_1):PAGE27_I424@PURE_QUANTA.SCONN8_G802M0083150RD3HR(CHIPS)':
 C_PATH='@t6g_mb_lib.t6g(sch_1):page27_i424@pure_quanta.sconn8_g802m0083150rd3hr~
(chips)',
 P_PATH='@t6g_mb_lib.t6g(sch_1):page27_i424@pure_quanta.sconn8_g802m0083150rd3hr~
(chips)',
 PATH='I424',
 DRAWING='@T6G_MB_LIB.T6G(SCH_1):PAGE27',
 SEC_TYPE='',
 PART_TYPE='SMLF',
 MATERIAL='IO',
 PHYS_PAGE='27',
 XY='(-500,2250)',
 ROT='0',
 VER='1',
 LOCATION='J48',
 SEC='1',
 CDS_LIB='pure_quanta',
 CDS_PART_NAME='SCONN8_G802M0083150RD3HR-SCONN8_G802M0083150RD3HR,A',
 PART_NUMBER='DFHD08MS385',
 VALUE='SCONN8_G802M0083150RD3HR',
 PRIM_FILE='./archive_libs/logical/sconn8_g802m0083150rd3hr/chips/chips.prt';

PART_NAME
 J49 'SCONN8_G802M0083150RD3HR-SCONN8_G802M0083150RD3HR,A':;

SECTION_NUMBER 1
 '@T6G_MB_LIB.T6G(SCH_1):PAGE54_I419@PURE_QUANTA.SCONN8_G802M0083150RD3HR(CHIPS)':
 C_PATH='@t6g_mb_lib.t6g(sch_1):page54_i419@pure_quanta.sconn8_g802m0083150rd3hr~
(chips)',
 P_PATH='@t6g_mb_lib.t6g(sch_1):page54_i419@pure_quanta.sconn8_g802m0083150rd3hr~
(chips)',
 PATH='I419',
 DRAWING='@T6G_MB_LIB.T6G(SCH_1):PAGE54',
 SEC_TYPE='',
 PART_TYPE='SMLF',
 MATERIAL='IO',
 PHYS_PAGE='54',
 XY='(-1025,2525)',
 ROT='0',
 VER='1',
 LOCATION='J49',
 SEC='1',
 CDS_LIB='pure_quanta',
 CDS_PART_NAME='SCONN8_G802M0083150RD3HR-SCONN8_G802M0083150RD3HR,A',
 PART_NUMBER='DFHD08MS385',
 VALUE='SCONN8_G802M0083150RD3HR',
 PRIM_FILE='./archive_libs/logical/sconn8_g802m0083150rd3hr/chips/chips.prt';

PART_NAME
 J54 'SCONN20_HSU2101L00007H-SCONN20_HSU2101-L0000-7H,SMA':;

SECTION_NUMBER 1
 '@T6G_MB_LIB.T6G(SCH_1):PAGE149_I142@PURE_QUANTA.SCONN20_HSU2101L00007H(CHIPS)':
 C_PATH='@t6g_mb_lib.t6g(sch_1):page149_i142@pure_quanta.sconn20_hsu2101l00007h(~
chips)',
 P_PATH='@t6g_mb_lib.t6g(sch_1):page172_i142@pure_quanta.sconn20_hsu2101l00007h(~
chips)',
 PATH='I142',
 DRAWING='@T6G_MB_LIB.T6G(SCH_1):PAGE149',
 PART_TYPE='SMLF',
 MATERIAL='IO',
 PHYS_PAGE='172',
 XY='(-5125,5725)',
 ROT='0',
 VER='1',
 LOCATION='J54',
 CDS_LIB='pure_quanta',
 CDS_PART_NAME='SCONN20_HSU2101L00007H-SCONN20_HSU2101-L0000-7H,SMA',
 PART_NUMBER='DFHD20MS153',
 VALUE='SCONN20_HSU2101-L0000-7H',
 PRIM_FILE='./archive_libs/logical/sconn20_hsu2101l00007h/chips/chips.prt';

PART_NAME
 J57 'CONN8_HBB1081L200D8H-CONN8_HBB1081-L200D-8H,THLF,IA':;

SECTION_NUMBER 1
 '@T6G_MB_LIB.T6G(SCH_1):PAGE84_I41@PURE_QUANTA.CONN8_HBB1081L200D8H(CHIPS)':
 C_PATH='@t6g_mb_lib.t6g(sch_1):page84_i41@pure_quanta.conn8_hbb1081l200d8h(chip~
s)',
 P_PATH='@t6g_mb_lib.t6g(sch_1):page85_i41@pure_quanta.conn8_hbb1081l200d8h(chip~
s)',
 PATH='I41',
 DRAWING='@T6G_MB_LIB.T6G(SCH_1):PAGE84',
 PART_TYPE='THLF',
 MATERIAL='IO',
 PHYS_PAGE='85',
 XY='(-1475,1700)',
 ROT='0',
 VER='1',
 LOCATION='J57',
 CDS_LIB='pure_quanta',
 CDS_PART_NAME='CONN8_HBB1081L200D8H-CONN8_HBB1081-L200D-8H,THLF,IA',
 PART_NUMBER='DFHD08MS197',
 VALUE='CONN8_HBB1081-L200D-8H',
 PRIM_FILE='./archive_libs/logical/conn8_hbb1081l200d8h/chips/chips.prt';

PART_NAME
 J59 'SCONN75K_APCI0155P004A-SCONN75K_APCI0155-P004A,SMLA':;

SECTION_NUMBER 1
 '@T6G_MB_LIB.T6G(SCH_1):PAGE345_I88@PURE_QUANTA.SCONN75K_APCI0155P004A(CHIPS)':
 C_PATH='@t6g_mb_lib.t6g(sch_1):page345_i88@pure_quanta.sconn75k_apci0155p004a(c~
hips)',
 P_PATH='@t6g_mb_lib.t6g(sch_1):page144_i88@pure_quanta.sconn75k_apci0155p004a(c~
hips)',
 PATH='I88',
 DRAWING='@T6G_MB_LIB.T6G(SCH_1):PAGE345',
 PIN_NAMES_ROTATE='True',
 PART_TYPE='SMLF',
 MATERIAL='EMPTY',
 PHYS_PAGE='144',
 XY='(8675,3250)',
 ROT='2',
 VER='1',
 LOCATION='J59',
 CDS_LIB='pure_quanta',
 CDS_PART_NAME='SCONN75K_APCI0155P004A-SCONN75K_APCI0155-P004A,SMLA',
 PART_NUMBER='DFHS75FR313',
 VALUE='SCONN75K_APCI0155-P004A',
 PRIM_FILE='./archive_libs/logical/sconn75k_apci0155p004a/chips/chips.prt';

PART_NAME
 J63 'PICOPROBE_BXA-DELTA-L 4.0,SMLF,EMPTY,TP33':;

SECTION_NUMBER 1
 '@T6G_MB_LIB.T6G(SCH_1):PAGE211_I65@PURE_QUANTA.PICOPROBE_BXA(CHIPS)':
 C_PATH='@t6g_mb_lib.t6g(sch_1):page211_i65@pure_quanta.picoprobe_bxa(chips)',
 P_PATH='@t6g_mb_lib.t6g(sch_1):page229_i65@pure_quanta.picoprobe_bxa(chips)',
 PATH='I65',
 DRAWING='@T6G_MB_LIB.T6G(SCH_1):PAGE211',
 SEC_TYPE='',
 PART_TYPE='SMLF',
 MATERIAL='EMPTY',
 PHYS_PAGE='229',
 XY='(-7650,5775)',
 ROT='0',
 VER='1',
 LOCATION='J63',
 SEC='1',
 CDS_LIB='pure_quanta',
 CDS_PART_NAME='PICOPROBE_BXA-DELTA-L 4.0,SMLF,EMPTY,TP33',
 PART_NUMBER='TP33',
 VALUE='DELTA-L 4.0',
 PRIM_FILE='./archive_libs/logical/picoprobe_bxa/chips/chips.prt';

PART_NAME
 J64 'PICOPROBE_BXA-DELTA-L 4.0,SMLF,EMPTY,TP33':;

SECTION_NUMBER 1
 '@T6G_MB_LIB.T6G(SCH_1):PAGE211_I67@PURE_QUANTA.PICOPROBE_BXA(CHIPS)':
 C_PATH='@t6g_mb_lib.t6g(sch_1):page211_i67@pure_quanta.picoprobe_bxa(chips)',
 P_PATH='@t6g_mb_lib.t6g(sch_1):page229_i67@pure_quanta.picoprobe_bxa(chips)',
 PATH='I67',
 DRAWING='@T6G_MB_LIB.T6G(SCH_1):PAGE211',
 SEC_TYPE='',
 PART_TYPE='SMLF',
 MATERIAL='EMPTY',
 PHYS_PAGE='229',
 XY='(-7650,5050)',
 ROT='0',
 VER='1',
 LOCATION='J64',
 SEC='1',
 CDS_LIB='pure_quanta',
 CDS_PART_NAME='PICOPROBE_BXA-DELTA-L 4.0,SMLF,EMPTY,TP33',
 PART_NUMBER='TP33',
 VALUE='DELTA-L 4.0',
 PRIM_FILE='./archive_libs/logical/picoprobe_bxa/chips/chips.prt';

PART_NAME
 J65 'PICOPROBE_BXA-DELTA-L 4.0,SMLF,EMPTY,TP33':;

SECTION_NUMBER 1
 '@T6G_MB_LIB.T6G(SCH_1):PAGE211_I69@PURE_QUANTA.PICOPROBE_BXA(CHIPS)':
 C_PATH='@t6g_mb_lib.t6g(sch_1):page211_i69@pure_quanta.picoprobe_bxa(chips)',
 P_PATH='@t6g_mb_lib.t6g(sch_1):page229_i69@pure_quanta.picoprobe_bxa(chips)',
 PATH='I69',
 DRAWING='@T6G_MB_LIB.T6G(SCH_1):PAGE211',
 SEC_TYPE='',
 PART_TYPE='SMLF',
 MATERIAL='EMPTY',
 PHYS_PAGE='229',
 XY='(-7675,4300)',
 ROT='0',
 VER='1',
 LOCATION='J65',
 SEC='1',
 CDS_LIB='pure_quanta',
 CDS_PART_NAME='PICOPROBE_BXA-DELTA-L 4.0,SMLF,EMPTY,TP33',
 PART_NUMBER='TP33',
 VALUE='DELTA-L 4.0',
 PRIM_FILE='./archive_libs/logical/picoprobe_bxa/chips/chips.prt';

PART_NAME
 J66 'PICOPROBE_BXA-DELTA-L 4.0,SMLF,EMPTY,TP33':;

SECTION_NUMBER 1
 '@T6G_MB_LIB.T6G(SCH_1):PAGE211_I71@PURE_QUANTA.PICOPROBE_BXA(CHIPS)':
 C_PATH='@t6g_mb_lib.t6g(sch_1):page211_i71@pure_quanta.picoprobe_bxa(chips)',
 P_PATH='@t6g_mb_lib.t6g(sch_1):page229_i71@pure_quanta.picoprobe_bxa(chips)',
 PATH='I71',
 DRAWING='@T6G_MB_LIB.T6G(SCH_1):PAGE211',
 SEC_TYPE='',
 PART_TYPE='SMLF',
 MATERIAL='EMPTY',
 PHYS_PAGE='229',
 XY='(-7675,3575)',
 ROT='0',
 VER='1',
 LOCATION='J66',
 SEC='1',
 CDS_LIB='pure_quanta',
 CDS_PART_NAME='PICOPROBE_BXA-DELTA-L 4.0,SMLF,EMPTY,TP33',
 PART_NUMBER='TP33',
 VALUE='DELTA-L 4.0',
 PRIM_FILE='./archive_libs/logical/picoprobe_bxa/chips/chips.prt';

PART_NAME
 J67 'SCONN288_DDR506112002KQ-SCONN288_DDR506112002KQ,SMA':;

SECTION_NUMBER 1
 '@T6G_MB_LIB.T6G(SCH_1):PAGE96_I22@PURE_QUANTA.SCONN288_DDR506112002KQ(CHIPS)':
 C_PATH='@t6g_mb_lib.t6g(sch_1):page96_i22@pure_quanta.sconn288_ddr506112002kq(c~
hips)',
 P_PATH='@t6g_mb_lib.t6g(sch_1):page97_i22@pure_quanta.sconn288_ddr506112002kq(c~
hips)',
 PATH='I22',
 DRAWING='@T6G_MB_LIB.T6G(SCH_1):PAGE96',
 PART_TYPE='SMLF',
 MATERIAL='IO',
 PHYS_PAGE='97',
 XY='(-6875,3325)',
 ROT='0',
 VER='1',
 LOCATION='J67',
 CDS_LIB='pure_quanta',
 CDS_PART_NAME='SCONN288_DDR506112002KQ-SCONN288_DDR506112002KQ,SMA',
 PART_NUMBER='DFHST8FS479',
 VALUE='SCONN288_DDR506112002KQ',
 PRIM_FILE='./archive_libs/logical/sconn288_ddr506112002kq/chips/chips.prt';

SECTION_NUMBER 2
 '@T6G_MB_LIB.T6G(SCH_1):PAGE96_I236@PURE_QUANTA.SCONN288_DDR506112002KQ(CHIPS)':
 C_PATH='@t6g_mb_lib.t6g(sch_1):page96_i236@pure_quanta.sconn288_ddr506112002kq(~
chips)',
 P_PATH='@t6g_mb_lib.t6g(sch_1):page97_i236@pure_quanta.sconn288_ddr506112002kq(~
chips)',
 PATH='I236',
 DRAWING='@T6G_MB_LIB.T6G(SCH_1):PAGE96',
 PART_TYPE='SMLF',
 MATERIAL='IO',
 PHYS_PAGE='97',
 XY='(-4450,3300)',
 ROT='0',
 VER='2',
 LOCATION='J67',
 CDS_LIB='pure_quanta',
 CDS_PART_NAME='SCONN288_DDR506112002KQ-SCONN288_DDR506112002KQ,SMA',
 PART_NUMBER='DFHST8FS479',
 VALUE='SCONN288_DDR506112002KQ',
 PRIM_FILE='./archive_libs/logical/sconn288_ddr506112002kq/chips/chips.prt';

SECTION_NUMBER 3
 '@T6G_MB_LIB.T6G(SCH_1):PAGE96_I140@PURE_QUANTA.SCONN288_DDR506112002KQ(CHIPS)':
 C_PATH='@t6g_mb_lib.t6g(sch_1):page96_i140@pure_quanta.sconn288_ddr506112002kq(~
chips)',
 P_PATH='@t6g_mb_lib.t6g(sch_1):page97_i140@pure_quanta.sconn288_ddr506112002kq(~
chips)',
 PATH='I140',
 DRAWING='@T6G_MB_LIB.T6G(SCH_1):PAGE96',
 PART_TYPE='SMLF',
 MATERIAL='IO',
 PHYS_PAGE='97',
 XY='(-1300,3525)',
 ROT='0',
 VER='3',
 LOCATION='J67',
 CDS_LIB='pure_quanta',
 CDS_PART_NAME='SCONN288_DDR506112002KQ-SCONN288_DDR506112002KQ,SMA',
 PART_NUMBER='DFHST8FS479',
 VALUE='SCONN288_DDR506112002KQ',
 PRIM_FILE='./archive_libs/logical/sconn288_ddr506112002kq/chips/chips.prt';

PART_NAME
 J68 'SCONN288_DDR506112002KQ-SCONN288_DDR506112002KQ,SMA':;

SECTION_NUMBER 1
 '@T6G_MB_LIB.T6G(SCH_1):PAGE94_I22@PURE_QUANTA.SCONN288_DDR506112002KQ(CHIPS)':
 C_PATH='@t6g_mb_lib.t6g(sch_1):page94_i22@pure_quanta.sconn288_ddr506112002kq(c~
hips)',
 P_PATH='@t6g_mb_lib.t6g(sch_1):page95_i22@pure_quanta.sconn288_ddr506112002kq(c~
hips)',
 PATH='I22',
 DRAWING='@T6G_MB_LIB.T6G(SCH_1):PAGE94',
 PART_TYPE='SMLF',
 MATERIAL='IO',
 PHYS_PAGE='95',
 XY='(-6800,3575)',
 ROT='0',
 VER='1',
 LOCATION='J68',
 CDS_LIB='pure_quanta',
 CDS_PART_NAME='SCONN288_DDR506112002KQ-SCONN288_DDR506112002KQ,SMA',
 PART_NUMBER='DFHST8FS479',
 VALUE='SCONN288_DDR506112002KQ',
 PRIM_FILE='./archive_libs/logical/sconn288_ddr506112002kq/chips/chips.prt';

SECTION_NUMBER 2
 '@T6G_MB_LIB.T6G(SCH_1):PAGE94_I236@PURE_QUANTA.SCONN288_DDR506112002KQ(CHIPS)':
 C_PATH='@t6g_mb_lib.t6g(sch_1):page94_i236@pure_quanta.sconn288_ddr506112002kq(~
chips)',
 P_PATH='@t6g_mb_lib.t6g(sch_1):page95_i236@pure_quanta.sconn288_ddr506112002kq(~
chips)',
 PATH='I236',
 DRAWING='@T6G_MB_LIB.T6G(SCH_1):PAGE94',
 PART_TYPE='SMLF',
 MATERIAL='IO',
 PHYS_PAGE='95',
 XY='(-4325,3225)',
 ROT='0',
 VER='2',
 LOCATION='J68',
 CDS_LIB='pure_quanta',
 CDS_PART_NAME='SCONN288_DDR506112002KQ-SCONN288_DDR506112002KQ,SMA',
 PART_NUMBER='DFHST8FS479',
 VALUE='SCONN288_DDR506112002KQ',
 PRIM_FILE='./archive_libs/logical/sconn288_ddr506112002kq/chips/chips.prt';

SECTION_NUMBER 3
 '@T6G_MB_LIB.T6G(SCH_1):PAGE94_I177@PURE_QUANTA.SCONN288_DDR506112002KQ(CHIPS)':
 C_PATH='@t6g_mb_lib.t6g(sch_1):page94_i177@pure_quanta.sconn288_ddr506112002kq(~
chips)',
 P_PATH='@t6g_mb_lib.t6g(sch_1):page95_i177@pure_quanta.sconn288_ddr506112002kq(~
chips)',
 PATH='I177',
 DRAWING='@T6G_MB_LIB.T6G(SCH_1):PAGE94',
 PART_TYPE='SMLF',
 MATERIAL='IO',
 PHYS_PAGE='95',
 XY='(-1150,3625)',
 ROT='0',
 VER='3',
 LOCATION='J68',
 CDS_LIB='pure_quanta',
 CDS_PART_NAME='SCONN288_DDR506112002KQ-SCONN288_DDR506112002KQ,SMA',
 PART_NUMBER='DFHST8FS479',
 VALUE='SCONN288_DDR506112002KQ',
 PRIM_FILE='./archive_libs/logical/sconn288_ddr506112002kq/chips/chips.prt';

PART_NAME
 J69 'SCONN288_DDR506112002KQ-SCONN288_DDR506112002KQ,SMA':;

SECTION_NUMBER 1
 '@T6G_MB_LIB.T6G(SCH_1):PAGE92_I22@PURE_QUANTA.SCONN288_DDR506112002KQ(CHIPS)':
 C_PATH='@t6g_mb_lib.t6g(sch_1):page92_i22@pure_quanta.sconn288_ddr506112002kq(c~
hips)',
 P_PATH='@t6g_mb_lib.t6g(sch_1):page93_i22@pure_quanta.sconn288_ddr506112002kq(c~
hips)',
 PATH='I22',
 DRAWING='@T6G_MB_LIB.T6G(SCH_1):PAGE92',
 PART_TYPE='SMLF',
 MATERIAL='IO',
 PHYS_PAGE='93',
 XY='(-6875,3600)',
 ROT='0',
 VER='1',
 LOCATION='J69',
 CDS_LIB='pure_quanta',
 CDS_PART_NAME='SCONN288_DDR506112002KQ-SCONN288_DDR506112002KQ,SMA',
 PART_NUMBER='DFHST8FS479',
 VALUE='SCONN288_DDR506112002KQ',
 PRIM_FILE='./archive_libs/logical/sconn288_ddr506112002kq/chips/chips.prt';

SECTION_NUMBER 2
 '@T6G_MB_LIB.T6G(SCH_1):PAGE92_I237@PURE_QUANTA.SCONN288_DDR506112002KQ(CHIPS)':
 C_PATH='@t6g_mb_lib.t6g(sch_1):page92_i237@pure_quanta.sconn288_ddr506112002kq(~
chips)',
 P_PATH='@t6g_mb_lib.t6g(sch_1):page93_i237@pure_quanta.sconn288_ddr506112002kq(~
chips)',
 PATH='I237',
 DRAWING='@T6G_MB_LIB.T6G(SCH_1):PAGE92',
 PART_TYPE='SMLF',
 MATERIAL='IO',
 PHYS_PAGE='93',
 XY='(-4450,3350)',
 ROT='0',
 VER='2',
 LOCATION='J69',
 CDS_LIB='pure_quanta',
 CDS_PART_NAME='SCONN288_DDR506112002KQ-SCONN288_DDR506112002KQ,SMA',
 PART_NUMBER='DFHST8FS479',
 VALUE='SCONN288_DDR506112002KQ',
 PRIM_FILE='./archive_libs/logical/sconn288_ddr506112002kq/chips/chips.prt';

SECTION_NUMBER 3
 '@T6G_MB_LIB.T6G(SCH_1):PAGE92_I177@PURE_QUANTA.SCONN288_DDR506112002KQ(CHIPS)':
 C_PATH='@t6g_mb_lib.t6g(sch_1):page92_i177@pure_quanta.sconn288_ddr506112002kq(~
chips)',
 P_PATH='@t6g_mb_lib.t6g(sch_1):page93_i177@pure_quanta.sconn288_ddr506112002kq(~
chips)',
 PATH='I177',
 DRAWING='@T6G_MB_LIB.T6G(SCH_1):PAGE92',
 PART_TYPE='SMLF',
 MATERIAL='IO',
 PHYS_PAGE='93',
 XY='(-1300,3650)',
 ROT='0',
 VER='3',
 LOCATION='J69',
 CDS_LIB='pure_quanta',
 CDS_PART_NAME='SCONN288_DDR506112002KQ-SCONN288_DDR506112002KQ,SMA',
 PART_NUMBER='DFHST8FS479',
 VALUE='SCONN288_DDR506112002KQ',
 PRIM_FILE='./archive_libs/logical/sconn288_ddr506112002kq/chips/chips.prt';

PART_NAME
 J70 'PICOPROBE_BXA-DELTA-L 4.0,SMLF,EMPTY,TP33':;

SECTION_NUMBER 1
 '@T6G_MB_LIB.T6G(SCH_1):PAGE211_I68@PURE_QUANTA.PICOPROBE_BXA(CHIPS)':
 C_PATH='@t6g_mb_lib.t6g(sch_1):page211_i68@pure_quanta.picoprobe_bxa(chips)',
 P_PATH='@t6g_mb_lib.t6g(sch_1):page229_i68@pure_quanta.picoprobe_bxa(chips)',
 PATH='I68',
 DRAWING='@T6G_MB_LIB.T6G(SCH_1):PAGE211',
 SEC_TYPE='',
 PART_TYPE='SMLF',
 MATERIAL='EMPTY',
 PHYS_PAGE='229',
 XY='(-5875,5100)',
 ROT='4',
 VER='1',
 LOCATION='J70',
 SEC='1',
 CDS_LIB='pure_quanta',
 CDS_PART_NAME='PICOPROBE_BXA-DELTA-L 4.0,SMLF,EMPTY,TP33',
 PART_NUMBER='TP33',
 VALUE='DELTA-L 4.0',
 PRIM_FILE='./archive_libs/logical/picoprobe_bxa/chips/chips.prt';

PART_NAME
 J71 'PICOPROBE_BXA-DELTA-L 4.0,SMLF,EMPTY,TP33':;

SECTION_NUMBER 1
 '@T6G_MB_LIB.T6G(SCH_1):PAGE211_I70@PURE_QUANTA.PICOPROBE_BXA(CHIPS)':
 C_PATH='@t6g_mb_lib.t6g(sch_1):page211_i70@pure_quanta.picoprobe_bxa(chips)',
 P_PATH='@t6g_mb_lib.t6g(sch_1):page229_i70@pure_quanta.picoprobe_bxa(chips)',
 PATH='I70',
 DRAWING='@T6G_MB_LIB.T6G(SCH_1):PAGE211',
 SEC_TYPE='',
 PART_TYPE='SMLF',
 MATERIAL='EMPTY',
 PHYS_PAGE='229',
 XY='(-5875,4350)',
 ROT='4',
 VER='1',
 LOCATION='J71',
 SEC='1',
 CDS_LIB='pure_quanta',
 CDS_PART_NAME='PICOPROBE_BXA-DELTA-L 4.0,SMLF,EMPTY,TP33',
 PART_NUMBER='TP33',
 VALUE='DELTA-L 4.0',
 PRIM_FILE='./archive_libs/logical/picoprobe_bxa/chips/chips.prt';

PART_NAME
 J72 'PICOPROBE_BXA-DELTA-L 4.0,SMLF,EMPTY,TP33':;

SECTION_NUMBER 1
 '@T6G_MB_LIB.T6G(SCH_1):PAGE211_I72@PURE_QUANTA.PICOPROBE_BXA(CHIPS)':
 C_PATH='@t6g_mb_lib.t6g(sch_1):page211_i72@pure_quanta.picoprobe_bxa(chips)',
 P_PATH='@t6g_mb_lib.t6g(sch_1):page229_i72@pure_quanta.picoprobe_bxa(chips)',
 PATH='I72',
 DRAWING='@T6G_MB_LIB.T6G(SCH_1):PAGE211',
 SEC_TYPE='',
 PART_TYPE='SMLF',
 MATERIAL='EMPTY',
 PHYS_PAGE='229',
 XY='(-5875,3625)',
 ROT='4',
 VER='1',
 LOCATION='J72',
 SEC='1',
 CDS_LIB='pure_quanta',
 CDS_PART_NAME='PICOPROBE_BXA-DELTA-L 4.0,SMLF,EMPTY,TP33',
 PART_NUMBER='TP33',
 VALUE='DELTA-L 4.0',
 PRIM_FILE='./archive_libs/logical/picoprobe_bxa/chips/chips.prt';

PART_NAME
 J73 'PICOPROBE_BXA-DELTA-L 4.0,SMLF,EMPTY,TP33':;

SECTION_NUMBER 1
 '@T6G_MB_LIB.T6G(SCH_1):PAGE211_I74@PURE_QUANTA.PICOPROBE_BXA(CHIPS)':
 C_PATH='@t6g_mb_lib.t6g(sch_1):page211_i74@pure_quanta.picoprobe_bxa(chips)',
 P_PATH='@t6g_mb_lib.t6g(sch_1):page229_i74@pure_quanta.picoprobe_bxa(chips)',
 PATH='I74',
 DRAWING='@T6G_MB_LIB.T6G(SCH_1):PAGE211',
 SEC_TYPE='',
 PART_TYPE='SMLF',
 MATERIAL='EMPTY',
 PHYS_PAGE='229',
 XY='(-5825,2950)',
 ROT='4',
 VER='1',
 LOCATION='J73',
 SEC='1',
 CDS_LIB='pure_quanta',
 CDS_PART_NAME='PICOPROBE_BXA-DELTA-L 4.0,SMLF,EMPTY,TP33',
 PART_NUMBER='TP33',
 VALUE='DELTA-L 4.0',
 PRIM_FILE='./archive_libs/logical/picoprobe_bxa/chips/chips.prt';

PART_NAME
 J74 'PICOPROBE_BXA-DELTA-L 4.0,SMLF,EMPTY,TP33':;

SECTION_NUMBER 1
 '@T6G_MB_LIB.T6G(SCH_1):PAGE211_I76@PURE_QUANTA.PICOPROBE_BXA(CHIPS)':
 C_PATH='@t6g_mb_lib.t6g(sch_1):page211_i76@pure_quanta.picoprobe_bxa(chips)',
 P_PATH='@t6g_mb_lib.t6g(sch_1):page229_i76@pure_quanta.picoprobe_bxa(chips)',
 PATH='I76',
 DRAWING='@T6G_MB_LIB.T6G(SCH_1):PAGE211',
 SEC_TYPE='',
 PART_TYPE='SMLF',
 MATERIAL='EMPTY',
 PHYS_PAGE='229',
 XY='(-5750,2200)',
 ROT='4',
 VER='1',
 LOCATION='J74',
 SEC='1',
 CDS_LIB='pure_quanta',
 CDS_PART_NAME='PICOPROBE_BXA-DELTA-L 4.0,SMLF,EMPTY,TP33',
 PART_NUMBER='TP33',
 VALUE='DELTA-L 4.0',
 PRIM_FILE='./archive_libs/logical/picoprobe_bxa/chips/chips.prt';

PART_NAME
 J75 'PICOPROBE_BXA-DELTA-L 4.0,SMLF,EMPTY,TP33':;

SECTION_NUMBER 1
 '@T6G_MB_LIB.T6G(SCH_1):PAGE211_I81@PURE_QUANTA.PICOPROBE_BXA(CHIPS)':
 C_PATH='@t6g_mb_lib.t6g(sch_1):page211_i81@pure_quanta.picoprobe_bxa(chips)',
 P_PATH='@t6g_mb_lib.t6g(sch_1):page229_i81@pure_quanta.picoprobe_bxa(chips)',
 PATH='I81',
 DRAWING='@T6G_MB_LIB.T6G(SCH_1):PAGE211',
 SEC_TYPE='',
 PART_TYPE='SMLF',
 MATERIAL='EMPTY',
 PHYS_PAGE='229',
 XY='(-3525,5800)',
 ROT='0',
 VER='1',
 LOCATION='J75',
 SEC='1',
 CDS_LIB='pure_quanta',
 CDS_PART_NAME='PICOPROBE_BXA-DELTA-L 4.0,SMLF,EMPTY,TP33',
 PART_NUMBER='TP33',
 VALUE='DELTA-L 4.0',
 PRIM_FILE='./archive_libs/logical/picoprobe_bxa/chips/chips.prt';

PART_NAME
 J76 'PICOPROBE_BXA-DELTA-L 4.0,SMLF,EMPTY,TP33':;

SECTION_NUMBER 1
 '@T6G_MB_LIB.T6G(SCH_1):PAGE211_I83@PURE_QUANTA.PICOPROBE_BXA(CHIPS)':
 C_PATH='@t6g_mb_lib.t6g(sch_1):page211_i83@pure_quanta.picoprobe_bxa(chips)',
 P_PATH='@t6g_mb_lib.t6g(sch_1):page229_i83@pure_quanta.picoprobe_bxa(chips)',
 PATH='I83',
 DRAWING='@T6G_MB_LIB.T6G(SCH_1):PAGE211',
 SEC_TYPE='',
 PART_TYPE='SMLF',
 MATERIAL='EMPTY',
 PHYS_PAGE='229',
 XY='(-3575,5050)',
 ROT='0',
 VER='1',
 LOCATION='J76',
 SEC='1',
 CDS_LIB='pure_quanta',
 CDS_PART_NAME='PICOPROBE_BXA-DELTA-L 4.0,SMLF,EMPTY,TP33',
 PART_NUMBER='TP33',
 VALUE='DELTA-L 4.0',
 PRIM_FILE='./archive_libs/logical/picoprobe_bxa/chips/chips.prt';

PART_NAME
 J77 'PICOPROBE_BXA-DELTA-L 4.0,SMLF,EMPTY,TP33':;

SECTION_NUMBER 1
 '@T6G_MB_LIB.T6G(SCH_1):PAGE211_I85@PURE_QUANTA.PICOPROBE_BXA(CHIPS)':
 C_PATH='@t6g_mb_lib.t6g(sch_1):page211_i85@pure_quanta.picoprobe_bxa(chips)',
 P_PATH='@t6g_mb_lib.t6g(sch_1):page229_i85@pure_quanta.picoprobe_bxa(chips)',
 PATH='I85',
 DRAWING='@T6G_MB_LIB.T6G(SCH_1):PAGE211',
 SEC_TYPE='',
 PART_TYPE='SMLF',
 MATERIAL='EMPTY',
 PHYS_PAGE='229',
 XY='(-3525,4325)',
 ROT='0',
 VER='1',
 LOCATION='J77',
 SEC='1',
 CDS_LIB='pure_quanta',
 CDS_PART_NAME='PICOPROBE_BXA-DELTA-L 4.0,SMLF,EMPTY,TP33',
 PART_NUMBER='TP33',
 VALUE='DELTA-L 4.0',
 PRIM_FILE='./archive_libs/logical/picoprobe_bxa/chips/chips.prt';

PART_NAME
 J78 'PICOPROBE_BXA-DELTA-L 4.0,SMLF,EMPTY,TP33':;

SECTION_NUMBER 1
 '@T6G_MB_LIB.T6G(SCH_1):PAGE211_I87@PURE_QUANTA.PICOPROBE_BXA(CHIPS)':
 C_PATH='@t6g_mb_lib.t6g(sch_1):page211_i87@pure_quanta.picoprobe_bxa(chips)',
 P_PATH='@t6g_mb_lib.t6g(sch_1):page229_i87@pure_quanta.picoprobe_bxa(chips)',
 PATH='I87',
 DRAWING='@T6G_MB_LIB.T6G(SCH_1):PAGE211',
 SEC_TYPE='',
 PART_TYPE='SMLF',
 MATERIAL='EMPTY',
 PHYS_PAGE='229',
 XY='(-3550,3575)',
 ROT='0',
 VER='1',
 LOCATION='J78',
 SEC='1',
 CDS_LIB='pure_quanta',
 CDS_PART_NAME='PICOPROBE_BXA-DELTA-L 4.0,SMLF,EMPTY,TP33',
 PART_NUMBER='TP33',
 VALUE='DELTA-L 4.0',
 PRIM_FILE='./archive_libs/logical/picoprobe_bxa/chips/chips.prt';

PART_NAME
 J79 'PICOPROBE_BXA-DELTA-L 4.0,SMLF,EMPTY,TP33':;

SECTION_NUMBER 1
 '@T6G_MB_LIB.T6G(SCH_1):PAGE211_I89@PURE_QUANTA.PICOPROBE_BXA(CHIPS)':
 C_PATH='@t6g_mb_lib.t6g(sch_1):page211_i89@pure_quanta.picoprobe_bxa(chips)',
 P_PATH='@t6g_mb_lib.t6g(sch_1):page229_i89@pure_quanta.picoprobe_bxa(chips)',
 PATH='I89',
 DRAWING='@T6G_MB_LIB.T6G(SCH_1):PAGE211',
 SEC_TYPE='',
 PART_TYPE='SMLF',
 MATERIAL='EMPTY',
 PHYS_PAGE='229',
 XY='(-3575,2900)',
 ROT='0',
 VER='1',
 LOCATION='J79',
 SEC='1',
 CDS_LIB='pure_quanta',
 CDS_PART_NAME='PICOPROBE_BXA-DELTA-L 4.0,SMLF,EMPTY,TP33',
 PART_NUMBER='TP33',
 VALUE='DELTA-L 4.0',
 PRIM_FILE='./archive_libs/logical/picoprobe_bxa/chips/chips.prt';

PART_NAME
 J80 'PICOPROBE_BXA-DELTA-L 4.0,SMLF,EMPTY,TP33':;

SECTION_NUMBER 1
 '@T6G_MB_LIB.T6G(SCH_1):PAGE211_I91@PURE_QUANTA.PICOPROBE_BXA(CHIPS)':
 C_PATH='@t6g_mb_lib.t6g(sch_1):page211_i91@pure_quanta.picoprobe_bxa(chips)',
 P_PATH='@t6g_mb_lib.t6g(sch_1):page229_i91@pure_quanta.picoprobe_bxa(chips)',
 PATH='I91',
 DRAWING='@T6G_MB_LIB.T6G(SCH_1):PAGE211',
 SEC_TYPE='',
 PART_TYPE='SMLF',
 MATERIAL='EMPTY',
 PHYS_PAGE='229',
 XY='(-3525,2150)',
 ROT='0',
 VER='1',
 LOCATION='J80',
 SEC='1',
 CDS_LIB='pure_quanta',
 CDS_PART_NAME='PICOPROBE_BXA-DELTA-L 4.0,SMLF,EMPTY,TP33',
 PART_NUMBER='TP33',
 VALUE='DELTA-L 4.0',
 PRIM_FILE='./archive_libs/logical/picoprobe_bxa/chips/chips.prt';

PART_NAME
 J81 'PICOPROBE_BXA-DELTA-L 4.0,SMLF,EMPTY,TP33':;

SECTION_NUMBER 1
 '@T6G_MB_LIB.T6G(SCH_1):PAGE211_I82@PURE_QUANTA.PICOPROBE_BXA(CHIPS)':
 C_PATH='@t6g_mb_lib.t6g(sch_1):page211_i82@pure_quanta.picoprobe_bxa(chips)',
 P_PATH='@t6g_mb_lib.t6g(sch_1):page229_i82@pure_quanta.picoprobe_bxa(chips)',
 PATH='I82',
 DRAWING='@T6G_MB_LIB.T6G(SCH_1):PAGE211',
 SEC_TYPE='',
 PART_TYPE='SMLF',
 MATERIAL='EMPTY',
 PHYS_PAGE='229',
 XY='(-1625,5850)',
 ROT='4',
 VER='1',
 LOCATION='J81',
 SEC='1',
 CDS_LIB='pure_quanta',
 CDS_PART_NAME='PICOPROBE_BXA-DELTA-L 4.0,SMLF,EMPTY,TP33',
 PART_NUMBER='TP33',
 VALUE='DELTA-L 4.0',
 PRIM_FILE='./archive_libs/logical/picoprobe_bxa/chips/chips.prt';

PART_NAME
 J82 'PICOPROBE_BXA-DELTA-L 4.0,SMLF,EMPTY,TP33':;

SECTION_NUMBER 1
 '@T6G_MB_LIB.T6G(SCH_1):PAGE211_I84@PURE_QUANTA.PICOPROBE_BXA(CHIPS)':
 C_PATH='@t6g_mb_lib.t6g(sch_1):page211_i84@pure_quanta.picoprobe_bxa(chips)',
 P_PATH='@t6g_mb_lib.t6g(sch_1):page229_i84@pure_quanta.picoprobe_bxa(chips)',
 PATH='I84',
 DRAWING='@T6G_MB_LIB.T6G(SCH_1):PAGE211',
 SEC_TYPE='',
 PART_TYPE='SMLF',
 MATERIAL='EMPTY',
 PHYS_PAGE='229',
 XY='(-1625,5100)',
 ROT='4',
 VER='1',
 LOCATION='J82',
 SEC='1',
 CDS_LIB='pure_quanta',
 CDS_PART_NAME='PICOPROBE_BXA-DELTA-L 4.0,SMLF,EMPTY,TP33',
 PART_NUMBER='TP33',
 VALUE='DELTA-L 4.0',
 PRIM_FILE='./archive_libs/logical/picoprobe_bxa/chips/chips.prt';

PART_NAME
 J83 'PICOPROBE_BXA-DELTA-L 4.0,SMLF,EMPTY,TP33':;

SECTION_NUMBER 1
 '@T6G_MB_LIB.T6G(SCH_1):PAGE211_I86@PURE_QUANTA.PICOPROBE_BXA(CHIPS)':
 C_PATH='@t6g_mb_lib.t6g(sch_1):page211_i86@pure_quanta.picoprobe_bxa(chips)',
 P_PATH='@t6g_mb_lib.t6g(sch_1):page229_i86@pure_quanta.picoprobe_bxa(chips)',
 PATH='I86',
 DRAWING='@T6G_MB_LIB.T6G(SCH_1):PAGE211',
 SEC_TYPE='',
 PART_TYPE='SMLF',
 MATERIAL='EMPTY',
 PHYS_PAGE='229',
 XY='(-1675,4375)',
 ROT='4',
 VER='1',
 LOCATION='J83',
 SEC='1',
 CDS_LIB='pure_quanta',
 CDS_PART_NAME='PICOPROBE_BXA-DELTA-L 4.0,SMLF,EMPTY,TP33',
 PART_NUMBER='TP33',
 VALUE='DELTA-L 4.0',
 PRIM_FILE='./archive_libs/logical/picoprobe_bxa/chips/chips.prt';

PART_NAME
 J84 'PICOPROBE_BXA-DELTA-L 4.0,SMLF,EMPTY,TP33':;

SECTION_NUMBER 1
 '@T6G_MB_LIB.T6G(SCH_1):PAGE211_I88@PURE_QUANTA.PICOPROBE_BXA(CHIPS)':
 C_PATH='@t6g_mb_lib.t6g(sch_1):page211_i88@pure_quanta.picoprobe_bxa(chips)',
 P_PATH='@t6g_mb_lib.t6g(sch_1):page229_i88@pure_quanta.picoprobe_bxa(chips)',
 PATH='I88',
 DRAWING='@T6G_MB_LIB.T6G(SCH_1):PAGE211',
 SEC_TYPE='',
 PART_TYPE='SMLF',
 MATERIAL='EMPTY',
 PHYS_PAGE='229',
 XY='(-1600,3625)',
 ROT='4',
 VER='1',
 LOCATION='J84',
 SEC='1',
 CDS_LIB='pure_quanta',
 CDS_PART_NAME='PICOPROBE_BXA-DELTA-L 4.0,SMLF,EMPTY,TP33',
 PART_NUMBER='TP33',
 VALUE='DELTA-L 4.0',
 PRIM_FILE='./archive_libs/logical/picoprobe_bxa/chips/chips.prt';

PART_NAME
 J85 'PICOPROBE_BXA-DELTA-L 4.0,SMLF,EMPTY,TP33':;

SECTION_NUMBER 1
 '@T6G_MB_LIB.T6G(SCH_1):PAGE211_I90@PURE_QUANTA.PICOPROBE_BXA(CHIPS)':
 C_PATH='@t6g_mb_lib.t6g(sch_1):page211_i90@pure_quanta.picoprobe_bxa(chips)',
 P_PATH='@t6g_mb_lib.t6g(sch_1):page229_i90@pure_quanta.picoprobe_bxa(chips)',
 PATH='I90',
 DRAWING='@T6G_MB_LIB.T6G(SCH_1):PAGE211',
 SEC_TYPE='',
 PART_TYPE='SMLF',
 MATERIAL='EMPTY',
 PHYS_PAGE='229',
 XY='(-1625,2950)',
 ROT='4',
 VER='1',
 LOCATION='J85',
 SEC='1',
 CDS_LIB='pure_quanta',
 CDS_PART_NAME='PICOPROBE_BXA-DELTA-L 4.0,SMLF,EMPTY,TP33',
 PART_NUMBER='TP33',
 VALUE='DELTA-L 4.0',
 PRIM_FILE='./archive_libs/logical/picoprobe_bxa/chips/chips.prt';

PART_NAME
 J86 'PICOPROBE_BXA-DELTA-L 4.0,SMLF,EMPTY,TP33':;

SECTION_NUMBER 1
 '@T6G_MB_LIB.T6G(SCH_1):PAGE211_I92@PURE_QUANTA.PICOPROBE_BXA(CHIPS)':
 C_PATH='@t6g_mb_lib.t6g(sch_1):page211_i92@pure_quanta.picoprobe_bxa(chips)',
 P_PATH='@t6g_mb_lib.t6g(sch_1):page229_i92@pure_quanta.picoprobe_bxa(chips)',
 PATH='I92',
 DRAWING='@T6G_MB_LIB.T6G(SCH_1):PAGE211',
 SEC_TYPE='',
 PART_TYPE='SMLF',
 MATERIAL='EMPTY',
 PHYS_PAGE='229',
 XY='(-1600,2200)',
 ROT='4',
 VER='1',
 LOCATION='J86',
 SEC='1',
 CDS_LIB='pure_quanta',
 CDS_PART_NAME='PICOPROBE_BXA-DELTA-L 4.0,SMLF,EMPTY,TP33',
 PART_NUMBER='TP33',
 VALUE='DELTA-L 4.0',
 PRIM_FILE='./archive_libs/logical/picoprobe_bxa/chips/chips.prt';

PART_NAME
 J90 'SCONN56_123276793-SCONN56_1-2327679-3,SMLF,IO,DFHSA':;

SECTION_NUMBER 1
 '@T6G_MB_LIB.T6G(SCH_1):PAGE297_I90@PURE_QUANTA.SCONN56_123276793(CHIPS)':
 C_PATH='@t6g_mb_lib.t6g(sch_1):page297_i90@pure_quanta.sconn56_123276793(chips)~
',
 P_PATH='@t6g_mb_lib.t6g(sch_1):page145_i90@pure_quanta.sconn56_123276793(chips)~
',
 PATH='I90',
 DRAWING='@T6G_MB_LIB.T6G(SCH_1):PAGE297',
 PART_TYPE='SMLF',
 MATERIAL='IO',
 PHYS_PAGE='145',
 XY='(650,3725)',
 ROT='0',
 VER='1',
 LOCATION='J90',
 CDS_LIB='pure_quanta',
 CDS_PART_NAME='SCONN56_123276793-SCONN56_1-2327679-3,SMLF,IO,DFHSA',
 PART_NUMBER='DFHS56FS022',
 VALUE='SCONN56_1-2327679-3',
 PRIM_FILE='./archive_libs/logical/sconn56_123276793/chips/chips.prt';

PART_NAME
 J99 'SCONN288_DDR506112002KQ-SCONN288_DDR506112002KQ,SMA':;

SECTION_NUMBER 1
 '@T6G_MB_LIB.T6G(SCH_1):PAGE107_I22@PURE_QUANTA.SCONN288_DDR506112002KQ(CHIPS)':
 C_PATH='@t6g_mb_lib.t6g(sch_1):page107_i22@pure_quanta.sconn288_ddr506112002kq(~
chips)',
 P_PATH='@t6g_mb_lib.t6g(sch_1):page108_i22@pure_quanta.sconn288_ddr506112002kq(~
chips)',
 PATH='I22',
 DRAWING='@T6G_MB_LIB.T6G(SCH_1):PAGE107',
 PART_TYPE='SMLF',
 MATERIAL='IO',
 PHYS_PAGE='108',
 XY='(-6850,3575)',
 ROT='0',
 VER='1',
 LOCATION='J99',
 CDS_LIB='pure_quanta',
 CDS_PART_NAME='SCONN288_DDR506112002KQ-SCONN288_DDR506112002KQ,SMA',
 PART_NUMBER='DFHST8FS479',
 VALUE='SCONN288_DDR506112002KQ',
 PRIM_FILE='./archive_libs/logical/sconn288_ddr506112002kq/chips/chips.prt';

SECTION_NUMBER 2
 '@T6G_MB_LIB.T6G(SCH_1):PAGE107_I235@PURE_QUANTA.SCONN288_DDR506112002KQ(CHIPS)':
 C_PATH='@t6g_mb_lib.t6g(sch_1):page107_i235@pure_quanta.sconn288_ddr506112002kq~
(chips)',
 P_PATH='@t6g_mb_lib.t6g(sch_1):page108_i235@pure_quanta.sconn288_ddr506112002kq~
(chips)',
 PATH='I235',
 DRAWING='@T6G_MB_LIB.T6G(SCH_1):PAGE107',
 PART_TYPE='SMLF',
 MATERIAL='IO',
 PHYS_PAGE='108',
 XY='(-4425,3500)',
 ROT='0',
 VER='2',
 LOCATION='J99',
 CDS_LIB='pure_quanta',
 CDS_PART_NAME='SCONN288_DDR506112002KQ-SCONN288_DDR506112002KQ,SMA',
 PART_NUMBER='DFHST8FS479',
 VALUE='SCONN288_DDR506112002KQ',
 PRIM_FILE='./archive_libs/logical/sconn288_ddr506112002kq/chips/chips.prt';

SECTION_NUMBER 3
 '@T6G_MB_LIB.T6G(SCH_1):PAGE107_I139@PURE_QUANTA.SCONN288_DDR506112002KQ(CHIPS)':
 C_PATH='@t6g_mb_lib.t6g(sch_1):page107_i139@pure_quanta.sconn288_ddr506112002kq~
(chips)',
 P_PATH='@t6g_mb_lib.t6g(sch_1):page108_i139@pure_quanta.sconn288_ddr506112002kq~
(chips)',
 PATH='I139',
 DRAWING='@T6G_MB_LIB.T6G(SCH_1):PAGE107',
 PART_TYPE='SMLF',
 MATERIAL='IO',
 PHYS_PAGE='108',
 XY='(-1250,3625)',
 ROT='0',
 VER='3',
 LOCATION='J99',
 CDS_LIB='pure_quanta',
 CDS_PART_NAME='SCONN288_DDR506112002KQ-SCONN288_DDR506112002KQ,SMA',
 PART_NUMBER='DFHST8FS479',
 VALUE='SCONN288_DDR506112002KQ',
 PRIM_FILE='./archive_libs/logical/sconn288_ddr506112002kq/chips/chips.prt';

PART_NAME
 J100 'SCONN288_DDR506112002KQ-SCONN288_DDR506112002KQ,SMA':;

SECTION_NUMBER 1
 '@T6G_MB_LIB.T6G(SCH_1):PAGE105_I22@PURE_QUANTA.SCONN288_DDR506112002KQ(CHIPS)':
 C_PATH='@t6g_mb_lib.t6g(sch_1):page105_i22@pure_quanta.sconn288_ddr506112002kq(~
chips)',
 P_PATH='@t6g_mb_lib.t6g(sch_1):page106_i22@pure_quanta.sconn288_ddr506112002kq(~
chips)',
 PATH='I22',
 DRAWING='@T6G_MB_LIB.T6G(SCH_1):PAGE105',
 PART_TYPE='SMLF',
 MATERIAL='IO',
 PHYS_PAGE='106',
 XY='(-6825,3600)',
 ROT='0',
 VER='1',
 LOCATION='J100',
 CDS_LIB='pure_quanta',
 CDS_PART_NAME='SCONN288_DDR506112002KQ-SCONN288_DDR506112002KQ,SMA',
 PART_NUMBER='DFHST8FS479',
 VALUE='SCONN288_DDR506112002KQ',
 PRIM_FILE='./archive_libs/logical/sconn288_ddr506112002kq/chips/chips.prt';

SECTION_NUMBER 2
 '@T6G_MB_LIB.T6G(SCH_1):PAGE105_I236@PURE_QUANTA.SCONN288_DDR506112002KQ(CHIPS)':
 C_PATH='@t6g_mb_lib.t6g(sch_1):page105_i236@pure_quanta.sconn288_ddr506112002kq~
(chips)',
 P_PATH='@t6g_mb_lib.t6g(sch_1):page106_i236@pure_quanta.sconn288_ddr506112002kq~
(chips)',
 PATH='I236',
 DRAWING='@T6G_MB_LIB.T6G(SCH_1):PAGE105',
 PART_TYPE='SMLF',
 MATERIAL='IO',
 PHYS_PAGE='106',
 XY='(-4400,3400)',
 ROT='0',
 VER='2',
 LOCATION='J100',
 CDS_LIB='pure_quanta',
 CDS_PART_NAME='SCONN288_DDR506112002KQ-SCONN288_DDR506112002KQ,SMA',
 PART_NUMBER='DFHST8FS479',
 VALUE='SCONN288_DDR506112002KQ',
 PRIM_FILE='./archive_libs/logical/sconn288_ddr506112002kq/chips/chips.prt';

SECTION_NUMBER 3
 '@T6G_MB_LIB.T6G(SCH_1):PAGE105_I176@PURE_QUANTA.SCONN288_DDR506112002KQ(CHIPS)':
 C_PATH='@t6g_mb_lib.t6g(sch_1):page105_i176@pure_quanta.sconn288_ddr506112002kq~
(chips)',
 P_PATH='@t6g_mb_lib.t6g(sch_1):page106_i176@pure_quanta.sconn288_ddr506112002kq~
(chips)',
 PATH='I176',
 DRAWING='@T6G_MB_LIB.T6G(SCH_1):PAGE105',
 PART_TYPE='SMLF',
 MATERIAL='IO',
 PHYS_PAGE='106',
 XY='(-1225,3600)',
 ROT='0',
 VER='3',
 LOCATION='J100',
 CDS_LIB='pure_quanta',
 CDS_PART_NAME='SCONN288_DDR506112002KQ-SCONN288_DDR506112002KQ,SMA',
 PART_NUMBER='DFHST8FS479',
 VALUE='SCONN288_DDR506112002KQ',
 PRIM_FILE='./archive_libs/logical/sconn288_ddr506112002kq/chips/chips.prt';

PART_NAME
 J102 'SCONN288_DDR506112002KQ-SCONN288_DDR506112002KQ,SMA':;

SECTION_NUMBER 1
 '@T6G_MB_LIB.T6G(SCH_1):PAGE103_I22@PURE_QUANTA.SCONN288_DDR506112002KQ(CHIPS)':
 C_PATH='@t6g_mb_lib.t6g(sch_1):page103_i22@pure_quanta.sconn288_ddr506112002kq(~
chips)',
 P_PATH='@t6g_mb_lib.t6g(sch_1):page104_i22@pure_quanta.sconn288_ddr506112002kq(~
chips)',
 PATH='I22',
 DRAWING='@T6G_MB_LIB.T6G(SCH_1):PAGE103',
 PART_TYPE='SMLF',
 MATERIAL='IO',
 PHYS_PAGE='104',
 XY='(-6625,3600)',
 ROT='0',
 VER='1',
 LOCATION='J102',
 CDS_LIB='pure_quanta',
 CDS_PART_NAME='SCONN288_DDR506112002KQ-SCONN288_DDR506112002KQ,SMA',
 PART_NUMBER='DFHST8FS479',
 VALUE='SCONN288_DDR506112002KQ',
 PRIM_FILE='./archive_libs/logical/sconn288_ddr506112002kq/chips/chips.prt';

SECTION_NUMBER 2
 '@T6G_MB_LIB.T6G(SCH_1):PAGE103_I238@PURE_QUANTA.SCONN288_DDR506112002KQ(CHIPS)':
 C_PATH='@t6g_mb_lib.t6g(sch_1):page103_i238@pure_quanta.sconn288_ddr506112002kq~
(chips)',
 P_PATH='@t6g_mb_lib.t6g(sch_1):page104_i238@pure_quanta.sconn288_ddr506112002kq~
(chips)',
 PATH='I238',
 DRAWING='@T6G_MB_LIB.T6G(SCH_1):PAGE103',
 PART_TYPE='SMLF',
 MATERIAL='IO',
 PHYS_PAGE='104',
 XY='(-4250,3425)',
 ROT='0',
 VER='2',
 LOCATION='J102',
 CDS_LIB='pure_quanta',
 CDS_PART_NAME='SCONN288_DDR506112002KQ-SCONN288_DDR506112002KQ,SMA',
 PART_NUMBER='DFHST8FS479',
 VALUE='SCONN288_DDR506112002KQ',
 PRIM_FILE='./archive_libs/logical/sconn288_ddr506112002kq/chips/chips.prt';

SECTION_NUMBER 3
 '@T6G_MB_LIB.T6G(SCH_1):PAGE103_I142@PURE_QUANTA.SCONN288_DDR506112002KQ(CHIPS)':
 C_PATH='@t6g_mb_lib.t6g(sch_1):page103_i142@pure_quanta.sconn288_ddr506112002kq~
(chips)',
 P_PATH='@t6g_mb_lib.t6g(sch_1):page104_i142@pure_quanta.sconn288_ddr506112002kq~
(chips)',
 PATH='I142',
 DRAWING='@T6G_MB_LIB.T6G(SCH_1):PAGE103',
 PART_TYPE='SMLF',
 MATERIAL='IO',
 PHYS_PAGE='104',
 XY='(-1325,3625)',
 ROT='0',
 VER='3',
 LOCATION='J102',
 CDS_LIB='pure_quanta',
 CDS_PART_NAME='SCONN288_DDR506112002KQ-SCONN288_DDR506112002KQ,SMA',
 PART_NUMBER='DFHST8FS479',
 VALUE='SCONN288_DDR506112002KQ',
 PRIM_FILE='./archive_libs/logical/sconn288_ddr506112002kq/chips/chips.prt';

PART_NAME
 J105 'CONN112_10137002101LF-CONN112_10137002-101LF,THLF,A':;

SECTION_NUMBER 1
 '@T6G_MB_LIB.T6G(SCH_1):PAGE326_I76@PURE_QUANTA.CONN112_10137002101LF(CHIPS)':
 C_PATH='@t6g_mb_lib.t6g(sch_1):page326_i76@pure_quanta.conn112_10137002101lf(ch~
ips)',
 P_PATH='@t6g_mb_lib.t6g(sch_1):page115_i76@pure_quanta.conn112_10137002101lf(ch~
ips)',
 PATH='I76',
 DRAWING='@T6G_MB_LIB.T6G(SCH_1):PAGE326',
 PART_TYPE='THLF',
 MATERIAL='IO',
 PHYS_PAGE='115',
 XY='(1075,1650)',
 ROT='0',
 VER='1',
 LOCATION='J105',
 CDS_LIB='pure_quanta',
 CDS_PART_NAME='CONN112_10137002101LF-CONN112_10137002-101LF,THLF,A',
 PART_NUMBER='DFHSB2FR012',
 VALUE='CONN112_10137002-101LF',
 PRIM_FILE='./archive_libs/logical/conn112_10137002101lf/chips/chips.prt';

SECTION_NUMBER 2
 '@T6G_MB_LIB.T6G(SCH_1):PAGE326_I75@PURE_QUANTA.CONN112_10137002101LF(CHIPS)':
 C_PATH='@t6g_mb_lib.t6g(sch_1):page326_i75@pure_quanta.conn112_10137002101lf(ch~
ips)',
 P_PATH='@t6g_mb_lib.t6g(sch_1):page115_i75@pure_quanta.conn112_10137002101lf(ch~
ips)',
 PATH='I75',
 DRAWING='@T6G_MB_LIB.T6G(SCH_1):PAGE326',
 PART_TYPE='THLF',
 MATERIAL='IO',
 PHYS_PAGE='115',
 XY='(6000,1650)',
 ROT='0',
 VER='2',
 LOCATION='J105',
 CDS_LIB='pure_quanta',
 CDS_PART_NAME='CONN112_10137002101LF-CONN112_10137002-101LF,THLF,A',
 PART_NUMBER='DFHSB2FR012',
 VALUE='CONN112_10137002-101LF',
 PRIM_FILE='./archive_libs/logical/conn112_10137002101lf/chips/chips.prt';

PART_NAME
 J106 'CONN112_10137002101LF-CONN112_10137002-101LF,THLF,A':;

SECTION_NUMBER 1
 '@T6G_MB_LIB.T6G(SCH_1):PAGE327_I19@PURE_QUANTA.CONN112_10137002101LF(CHIPS)':
 C_PATH='@t6g_mb_lib.t6g(sch_1):page327_i19@pure_quanta.conn112_10137002101lf(ch~
ips)',
 P_PATH='@t6g_mb_lib.t6g(sch_1):page116_i19@pure_quanta.conn112_10137002101lf(ch~
ips)',
 PATH='I19',
 DRAWING='@T6G_MB_LIB.T6G(SCH_1):PAGE327',
 PART_TYPE='THLF',
 MATERIAL='IO',
 PHYS_PAGE='116',
 XY='(0,4050)',
 ROT='0',
 VER='1',
 LOCATION='J106',
 CDS_LIB='pure_quanta',
 CDS_PART_NAME='CONN112_10137002101LF-CONN112_10137002-101LF,THLF,A',
 PART_NUMBER='DFHSB2FR012',
 VALUE='CONN112_10137002-101LF',
 PRIM_FILE='./archive_libs/logical/conn112_10137002101lf/chips/chips.prt';

SECTION_NUMBER 2
 '@T6G_MB_LIB.T6G(SCH_1):PAGE327_I74@PURE_QUANTA.CONN112_10137002101LF(CHIPS)':
 C_PATH='@t6g_mb_lib.t6g(sch_1):page327_i74@pure_quanta.conn112_10137002101lf(ch~
ips)',
 P_PATH='@t6g_mb_lib.t6g(sch_1):page116_i74@pure_quanta.conn112_10137002101lf(ch~
ips)',
 PATH='I74',
 DRAWING='@T6G_MB_LIB.T6G(SCH_1):PAGE327',
 PART_TYPE='THLF',
 MATERIAL='IO',
 PHYS_PAGE='116',
 XY='(4625,3975)',
 ROT='0',
 VER='2',
 LOCATION='J106',
 CDS_LIB='pure_quanta',
 CDS_PART_NAME='CONN112_10137002101LF-CONN112_10137002-101LF,THLF,A',
 PART_NUMBER='DFHSB2FR012',
 VALUE='CONN112_10137002-101LF',
 PRIM_FILE='./archive_libs/logical/conn112_10137002101lf/chips/chips.prt';

PART_NAME
 J107 'CONN112_10137002101LF-CONN112_10137002-101LF,THLF,A':;

SECTION_NUMBER 1
 '@T6G_MB_LIB.T6G(SCH_1):PAGE317_I70@PURE_QUANTA.CONN112_10137002101LF(CHIPS)':
 C_PATH='@t6g_mb_lib.t6g(sch_1):page317_i70@pure_quanta.conn112_10137002101lf(ch~
ips)',
 P_PATH='@t6g_mb_lib.t6g(sch_1):page117_i70@pure_quanta.conn112_10137002101lf(ch~
ips)',
 PATH='I70',
 DRAWING='@T6G_MB_LIB.T6G(SCH_1):PAGE317',
 PART_TYPE='THLF',
 MATERIAL='IO',
 PHYS_PAGE='117',
 XY='(-1000,250)',
 ROT='0',
 VER='1',
 LOCATION='J107',
 CDS_LIB='pure_quanta',
 CDS_PART_NAME='CONN112_10137002101LF-CONN112_10137002-101LF,THLF,A',
 PART_NUMBER='DFHSB2FR012',
 VALUE='CONN112_10137002-101LF',
 PRIM_FILE='./archive_libs/logical/conn112_10137002101lf/chips/chips.prt';

SECTION_NUMBER 2
 '@T6G_MB_LIB.T6G(SCH_1):PAGE317_I49@PURE_QUANTA.CONN112_10137002101LF(CHIPS)':
 C_PATH='@t6g_mb_lib.t6g(sch_1):page317_i49@pure_quanta.conn112_10137002101lf(ch~
ips)',
 P_PATH='@t6g_mb_lib.t6g(sch_1):page117_i49@pure_quanta.conn112_10137002101lf(ch~
ips)',
 PATH='I49',
 DRAWING='@T6G_MB_LIB.T6G(SCH_1):PAGE317',
 PART_TYPE='THLF',
 MATERIAL='IO',
 PHYS_PAGE='117',
 XY='(3500,250)',
 ROT='0',
 VER='2',
 LOCATION='J107',
 CDS_LIB='pure_quanta',
 CDS_PART_NAME='CONN112_10137002101LF-CONN112_10137002-101LF,THLF,A',
 PART_NUMBER='DFHSB2FR012',
 VALUE='CONN112_10137002-101LF',
 PRIM_FILE='./archive_libs/logical/conn112_10137002101lf/chips/chips.prt';

PART_NAME
 J108 'CONN112_10137002101LF-CONN112_10137002-101LF,THLF,A':;

SECTION_NUMBER 1
 '@T6G_MB_LIB.T6G(SCH_1):PAGE320_I15@PURE_QUANTA.CONN112_10137002101LF(CHIPS)':
 C_PATH='@t6g_mb_lib.t6g(sch_1):page320_i15@pure_quanta.conn112_10137002101lf(ch~
ips)',
 P_PATH='@t6g_mb_lib.t6g(sch_1):page118_i15@pure_quanta.conn112_10137002101lf(ch~
ips)',
 PATH='I15',
 DRAWING='@T6G_MB_LIB.T6G(SCH_1):PAGE320',
 PART_TYPE='THLF',
 MATERIAL='IO',
 PHYS_PAGE='118',
 XY='(-950,600)',
 ROT='0',
 VER='1',
 LOCATION='J108',
 CDS_LIB='pure_quanta',
 CDS_PART_NAME='CONN112_10137002101LF-CONN112_10137002-101LF,THLF,A',
 PART_NUMBER='DFHSB2FR012',
 VALUE='CONN112_10137002-101LF',
 PRIM_FILE='./archive_libs/logical/conn112_10137002101lf/chips/chips.prt';

SECTION_NUMBER 2
 '@T6G_MB_LIB.T6G(SCH_1):PAGE320_I72@PURE_QUANTA.CONN112_10137002101LF(CHIPS)':
 C_PATH='@t6g_mb_lib.t6g(sch_1):page320_i72@pure_quanta.conn112_10137002101lf(ch~
ips)',
 P_PATH='@t6g_mb_lib.t6g(sch_1):page118_i72@pure_quanta.conn112_10137002101lf(ch~
ips)',
 PATH='I72',
 DRAWING='@T6G_MB_LIB.T6G(SCH_1):PAGE320',
 PART_TYPE='THLF',
 MATERIAL='IO',
 PHYS_PAGE='118',
 XY='(3600,550)',
 ROT='0',
 VER='2',
 LOCATION='J108',
 CDS_LIB='pure_quanta',
 CDS_PART_NAME='CONN112_10137002101LF-CONN112_10137002-101LF,THLF,A',
 PART_NUMBER='DFHSB2FR012',
 VALUE='CONN112_10137002-101LF',
 PRIM_FILE='./archive_libs/logical/conn112_10137002101lf/chips/chips.prt';

PART_NAME
 J109 'CONN112_10137002101LF-CONN112_10137002-101LF,THLF,A':;

SECTION_NUMBER 1
 '@T6G_MB_LIB.T6G(SCH_1):PAGE319_I16@PURE_QUANTA.CONN112_10137002101LF(CHIPS)':
 C_PATH='@t6g_mb_lib.t6g(sch_1):page319_i16@pure_quanta.conn112_10137002101lf(ch~
ips)',
 P_PATH='@t6g_mb_lib.t6g(sch_1):page119_i16@pure_quanta.conn112_10137002101lf(ch~
ips)',
 PATH='I16',
 DRAWING='@T6G_MB_LIB.T6G(SCH_1):PAGE319',
 PART_TYPE='THLF',
 MATERIAL='IO',
 PHYS_PAGE='119',
 XY='(-1125,775)',
 ROT='0',
 VER='1',
 LOCATION='J109',
 CDS_LIB='pure_quanta',
 CDS_PART_NAME='CONN112_10137002101LF-CONN112_10137002-101LF,THLF,A',
 PART_NUMBER='DFHSB2FR012',
 VALUE='CONN112_10137002-101LF',
 PRIM_FILE='./archive_libs/logical/conn112_10137002101lf/chips/chips.prt';

SECTION_NUMBER 2
 '@T6G_MB_LIB.T6G(SCH_1):PAGE319_I76@PURE_QUANTA.CONN112_10137002101LF(CHIPS)':
 C_PATH='@t6g_mb_lib.t6g(sch_1):page319_i76@pure_quanta.conn112_10137002101lf(ch~
ips)',
 P_PATH='@t6g_mb_lib.t6g(sch_1):page119_i76@pure_quanta.conn112_10137002101lf(ch~
ips)',
 PATH='I76',
 DRAWING='@T6G_MB_LIB.T6G(SCH_1):PAGE319',
 PART_TYPE='THLF',
 MATERIAL='IO',
 PHYS_PAGE='119',
 XY='(3650,700)',
 ROT='0',
 VER='2',
 LOCATION='J109',
 CDS_LIB='pure_quanta',
 CDS_PART_NAME='CONN112_10137002101LF-CONN112_10137002-101LF,THLF,A',
 PART_NUMBER='DFHSB2FR012',
 VALUE='CONN112_10137002-101LF',
 PRIM_FILE='./archive_libs/logical/conn112_10137002101lf/chips/chips.prt';

PART_NAME
 J110 'CONN112_10137002101LF-CONN112_10137002-101LF,THLF,A':;

SECTION_NUMBER 1
 '@T6G_MB_LIB.T6G(SCH_1):PAGE318_I16@PURE_QUANTA.CONN112_10137002101LF(CHIPS)':
 C_PATH='@t6g_mb_lib.t6g(sch_1):page318_i16@pure_quanta.conn112_10137002101lf(ch~
ips)',
 P_PATH='@t6g_mb_lib.t6g(sch_1):page120_i16@pure_quanta.conn112_10137002101lf(ch~
ips)',
 PATH='I16',
 DRAWING='@T6G_MB_LIB.T6G(SCH_1):PAGE318',
 PART_TYPE='THLF',
 MATERIAL='IO',
 PHYS_PAGE='120',
 XY='(-1050,200)',
 ROT='0',
 VER='1',
 LOCATION='J110',
 CDS_LIB='pure_quanta',
 CDS_PART_NAME='CONN112_10137002101LF-CONN112_10137002-101LF,THLF,A',
 PART_NUMBER='DFHSB2FR012',
 VALUE='CONN112_10137002-101LF',
 PRIM_FILE='./archive_libs/logical/conn112_10137002101lf/chips/chips.prt';

SECTION_NUMBER 2
 '@T6G_MB_LIB.T6G(SCH_1):PAGE318_I76@PURE_QUANTA.CONN112_10137002101LF(CHIPS)':
 C_PATH='@t6g_mb_lib.t6g(sch_1):page318_i76@pure_quanta.conn112_10137002101lf(ch~
ips)',
 P_PATH='@t6g_mb_lib.t6g(sch_1):page120_i76@pure_quanta.conn112_10137002101lf(ch~
ips)',
 PATH='I76',
 DRAWING='@T6G_MB_LIB.T6G(SCH_1):PAGE318',
 PART_TYPE='THLF',
 MATERIAL='IO',
 PHYS_PAGE='120',
 XY='(3725,250)',
 ROT='0',
 VER='2',
 LOCATION='J110',
 CDS_LIB='pure_quanta',
 CDS_PART_NAME='CONN112_10137002101LF-CONN112_10137002-101LF,THLF,A',
 PART_NUMBER='DFHSB2FR012',
 VALUE='CONN112_10137002-101LF',
 PRIM_FILE='./archive_libs/logical/conn112_10137002101lf/chips/chips.prt';

PART_NAME
 J111 'CONN112_10137002101LF-CONN112_10137002-101LF,THLF,A':;

SECTION_NUMBER 1
 '@T6G_MB_LIB.T6G(SCH_1):PAGE328_I38@PURE_QUANTA.CONN112_10137002101LF(CHIPS)':
 C_PATH='@t6g_mb_lib.t6g(sch_1):page328_i38@pure_quanta.conn112_10137002101lf(ch~
ips)',
 P_PATH='@t6g_mb_lib.t6g(sch_1):page121_i38@pure_quanta.conn112_10137002101lf(ch~
ips)',
 PATH='I38',
 DRAWING='@T6G_MB_LIB.T6G(SCH_1):PAGE328',
 PART_TYPE='THLF',
 MATERIAL='IO',
 PHYS_PAGE='121',
 XY='(-75,2050)',
 ROT='0',
 VER='1',
 LOCATION='J111',
 CDS_LIB='pure_quanta',
 CDS_PART_NAME='CONN112_10137002101LF-CONN112_10137002-101LF,THLF,A',
 PART_NUMBER='DFHSB2FR012',
 VALUE='CONN112_10137002-101LF',
 PRIM_FILE='./archive_libs/logical/conn112_10137002101lf/chips/chips.prt';

SECTION_NUMBER 2
 '@T6G_MB_LIB.T6G(SCH_1):PAGE328_I76@PURE_QUANTA.CONN112_10137002101LF(CHIPS)':
 C_PATH='@t6g_mb_lib.t6g(sch_1):page328_i76@pure_quanta.conn112_10137002101lf(ch~
ips)',
 P_PATH='@t6g_mb_lib.t6g(sch_1):page121_i76@pure_quanta.conn112_10137002101lf(ch~
ips)',
 PATH='I76',
 DRAWING='@T6G_MB_LIB.T6G(SCH_1):PAGE328',
 PART_TYPE='THLF',
 MATERIAL='IO',
 PHYS_PAGE='121',
 XY='(4675,2050)',
 ROT='0',
 VER='2',
 LOCATION='J111',
 CDS_LIB='pure_quanta',
 CDS_PART_NAME='CONN112_10137002101LF-CONN112_10137002-101LF,THLF,A',
 PART_NUMBER='DFHSB2FR012',
 VALUE='CONN112_10137002-101LF',
 PRIM_FILE='./archive_libs/logical/conn112_10137002101lf/chips/chips.prt';

PART_NAME
 J112 'CONN160_10131762101LF-CONN160_10131762-101LF,THLF,A':;

SECTION_NUMBER 1
 '@T6G_MB_LIB.T6G(SCH_1):PAGE329_I7@PURE_QUANTA.CONN160_10131762101LF(CHIPS)':
 C_PATH='@t6g_mb_lib.t6g(sch_1):page329_i7@pure_quanta.conn160_10131762101lf(chi~
ps)',
 P_PATH='@t6g_mb_lib.t6g(sch_1):page122_i7@pure_quanta.conn160_10131762101lf(chi~
ps)',
 PATH='I7',
 DRAWING='@T6G_MB_LIB.T6G(SCH_1):PAGE329',
 PART_TYPE='THLF',
 MATERIAL='IO',
 PHYS_PAGE='122',
 XY='(525,1625)',
 ROT='0',
 VER='1',
 LOCATION='J112',
 CDS_LIB='pure_quanta',
 CDS_PART_NAME='CONN160_10131762101LF-CONN160_10131762-101LF,THLF,A',
 PART_NUMBER='DFHSG0FR007',
 VALUE='CONN160_10131762-101LF',
 PRIM_FILE='./archive_libs/logical/conn160_10131762101lf/chips/chips.prt';

SECTION_NUMBER 2
 '@T6G_MB_LIB.T6G(SCH_1):PAGE329_I102@PURE_QUANTA.CONN160_10131762101LF(CHIPS)':
 C_PATH='@t6g_mb_lib.t6g(sch_1):page329_i102@pure_quanta.conn160_10131762101lf(c~
hips)',
 P_PATH='@t6g_mb_lib.t6g(sch_1):page122_i102@pure_quanta.conn160_10131762101lf(c~
hips)',
 PATH='I102',
 DRAWING='@T6G_MB_LIB.T6G(SCH_1):PAGE329',
 PART_TYPE='THLF',
 MATERIAL='IO',
 PHYS_PAGE='122',
 XY='(5075,1700)',
 ROT='0',
 VER='2',
 LOCATION='J112',
 CDS_LIB='pure_quanta',
 CDS_PART_NAME='CONN160_10131762101LF-CONN160_10131762-101LF,THLF,A',
 PART_NUMBER='DFHSG0FR007',
 VALUE='CONN160_10131762-101LF',
 PRIM_FILE='./archive_libs/logical/conn160_10131762101lf/chips/chips.prt';

PART_NAME
 J114 'PICOPROBE_BXA-DELTA-L 4.0,SMLF,EMPTY,TP33':;

SECTION_NUMBER 1
 '@T6G_MB_LIB.T6G(SCH_1):PAGE211_I77@PURE_QUANTA.PICOPROBE_BXA(CHIPS)':
 C_PATH='@t6g_mb_lib.t6g(sch_1):page211_i77@pure_quanta.picoprobe_bxa(chips)',
 P_PATH='@t6g_mb_lib.t6g(sch_1):page229_i77@pure_quanta.picoprobe_bxa(chips)',
 PATH='I77',
 DRAWING='@T6G_MB_LIB.T6G(SCH_1):PAGE211',
 SEC_TYPE='',
 PART_TYPE='SMLF',
 MATERIAL='EMPTY',
 PHYS_PAGE='229',
 XY='(-7675,1450)',
 ROT='0',
 VER='1',
 LOCATION='J114',
 SEC='1',
 CDS_LIB='pure_quanta',
 CDS_PART_NAME='PICOPROBE_BXA-DELTA-L 4.0,SMLF,EMPTY,TP33',
 PART_NUMBER='TP33',
 VALUE='DELTA-L 4.0',
 PRIM_FILE='./archive_libs/logical/picoprobe_bxa/chips/chips.prt';

PART_NAME
 J115 'PICOPROBE_BXA-DELTA-L 4.0,SMLF,EMPTY,TP33':;

SECTION_NUMBER 1
 '@T6G_MB_LIB.T6G(SCH_1):PAGE211_I79@PURE_QUANTA.PICOPROBE_BXA(CHIPS)':
 C_PATH='@t6g_mb_lib.t6g(sch_1):page211_i79@pure_quanta.picoprobe_bxa(chips)',
 P_PATH='@t6g_mb_lib.t6g(sch_1):page229_i79@pure_quanta.picoprobe_bxa(chips)',
 PATH='I79',
 DRAWING='@T6G_MB_LIB.T6G(SCH_1):PAGE211',
 SEC_TYPE='',
 PART_TYPE='SMLF',
 MATERIAL='EMPTY',
 PHYS_PAGE='229',
 XY='(-7725,750)',
 ROT='0',
 VER='1',
 LOCATION='J115',
 SEC='1',
 CDS_LIB='pure_quanta',
 CDS_PART_NAME='PICOPROBE_BXA-DELTA-L 4.0,SMLF,EMPTY,TP33',
 PART_NUMBER='TP33',
 VALUE='DELTA-L 4.0',
 PRIM_FILE='./archive_libs/logical/picoprobe_bxa/chips/chips.prt';

PART_NAME
 J116 'PICOPROBE_BXA-DELTA-L 4.0,SMLF,EMPTY,TP33':;

SECTION_NUMBER 1
 '@T6G_MB_LIB.T6G(SCH_1):PAGE211_I78@PURE_QUANTA.PICOPROBE_BXA(CHIPS)':
 C_PATH='@t6g_mb_lib.t6g(sch_1):page211_i78@pure_quanta.picoprobe_bxa(chips)',
 P_PATH='@t6g_mb_lib.t6g(sch_1):page229_i78@pure_quanta.picoprobe_bxa(chips)',
 PATH='I78',
 DRAWING='@T6G_MB_LIB.T6G(SCH_1):PAGE211',
 SEC_TYPE='',
 PART_TYPE='SMLF',
 MATERIAL='EMPTY',
 PHYS_PAGE='229',
 XY='(-5750,1500)',
 ROT='4',
 VER='1',
 LOCATION='J116',
 SEC='1',
 CDS_LIB='pure_quanta',
 CDS_PART_NAME='PICOPROBE_BXA-DELTA-L 4.0,SMLF,EMPTY,TP33',
 PART_NUMBER='TP33',
 VALUE='DELTA-L 4.0',
 PRIM_FILE='./archive_libs/logical/picoprobe_bxa/chips/chips.prt';

PART_NAME
 J117 'PICOPROBE_BXA-DELTA-L 4.0,SMLF,EMPTY,TP33':;

SECTION_NUMBER 1
 '@T6G_MB_LIB.T6G(SCH_1):PAGE211_I80@PURE_QUANTA.PICOPROBE_BXA(CHIPS)':
 C_PATH='@t6g_mb_lib.t6g(sch_1):page211_i80@pure_quanta.picoprobe_bxa(chips)',
 P_PATH='@t6g_mb_lib.t6g(sch_1):page229_i80@pure_quanta.picoprobe_bxa(chips)',
 PATH='I80',
 DRAWING='@T6G_MB_LIB.T6G(SCH_1):PAGE211',
 SEC_TYPE='',
 PART_TYPE='SMLF',
 MATERIAL='EMPTY',
 PHYS_PAGE='229',
 XY='(-5725,800)',
 ROT='4',
 VER='1',
 LOCATION='J117',
 SEC='1',
 CDS_LIB='pure_quanta',
 CDS_PART_NAME='PICOPROBE_BXA-DELTA-L 4.0,SMLF,EMPTY,TP33',
 PART_NUMBER='TP33',
 VALUE='DELTA-L 4.0',
 PRIM_FILE='./archive_libs/logical/picoprobe_bxa/chips/chips.prt';

PART_NAME
 J118 'PICOPROBE_BXA-DELTA-L 4.0,SMLF,EMPTY,TP33':;

SECTION_NUMBER 1
 '@T6G_MB_LIB.T6G(SCH_1):PAGE211_I93@PURE_QUANTA.PICOPROBE_BXA(CHIPS)':
 C_PATH='@t6g_mb_lib.t6g(sch_1):page211_i93@pure_quanta.picoprobe_bxa(chips)',
 P_PATH='@t6g_mb_lib.t6g(sch_1):page229_i93@pure_quanta.picoprobe_bxa(chips)',
 PATH='I93',
 DRAWING='@T6G_MB_LIB.T6G(SCH_1):PAGE211',
 SEC_TYPE='',
 PART_TYPE='SMLF',
 MATERIAL='EMPTY',
 PHYS_PAGE='229',
 XY='(-3475,1500)',
 ROT='0',
 VER='1',
 LOCATION='J118',
 SEC='1',
 CDS_LIB='pure_quanta',
 CDS_PART_NAME='PICOPROBE_BXA-DELTA-L 4.0,SMLF,EMPTY,TP33',
 PART_NUMBER='TP33',
 VALUE='DELTA-L 4.0',
 PRIM_FILE='./archive_libs/logical/picoprobe_bxa/chips/chips.prt';

PART_NAME
 J119 'PICOPROBE_BXA-DELTA-L 4.0,SMLF,EMPTY,TP33':;

SECTION_NUMBER 1
 '@T6G_MB_LIB.T6G(SCH_1):PAGE211_I95@PURE_QUANTA.PICOPROBE_BXA(CHIPS)':
 C_PATH='@t6g_mb_lib.t6g(sch_1):page211_i95@pure_quanta.picoprobe_bxa(chips)',
 P_PATH='@t6g_mb_lib.t6g(sch_1):page229_i95@pure_quanta.picoprobe_bxa(chips)',
 PATH='I95',
 DRAWING='@T6G_MB_LIB.T6G(SCH_1):PAGE211',
 SEC_TYPE='',
 PART_TYPE='SMLF',
 MATERIAL='EMPTY',
 PHYS_PAGE='229',
 XY='(-3475,775)',
 ROT='0',
 VER='1',
 LOCATION='J119',
 SEC='1',
 CDS_LIB='pure_quanta',
 CDS_PART_NAME='PICOPROBE_BXA-DELTA-L 4.0,SMLF,EMPTY,TP33',
 PART_NUMBER='TP33',
 VALUE='DELTA-L 4.0',
 PRIM_FILE='./archive_libs/logical/picoprobe_bxa/chips/chips.prt';

PART_NAME
 J120 'PICOPROBE_BXA-DELTA-L 4.0,SMLF,EMPTY,TP33':;

SECTION_NUMBER 1
 '@T6G_MB_LIB.T6G(SCH_1):PAGE211_I94@PURE_QUANTA.PICOPROBE_BXA(CHIPS)':
 C_PATH='@t6g_mb_lib.t6g(sch_1):page211_i94@pure_quanta.picoprobe_bxa(chips)',
 P_PATH='@t6g_mb_lib.t6g(sch_1):page229_i94@pure_quanta.picoprobe_bxa(chips)',
 PATH='I94',
 DRAWING='@T6G_MB_LIB.T6G(SCH_1):PAGE211',
 SEC_TYPE='',
 PART_TYPE='SMLF',
 MATERIAL='EMPTY',
 PHYS_PAGE='229',
 XY='(-1575,1550)',
 ROT='4',
 VER='1',
 LOCATION='J120',
 SEC='1',
 CDS_LIB='pure_quanta',
 CDS_PART_NAME='PICOPROBE_BXA-DELTA-L 4.0,SMLF,EMPTY,TP33',
 PART_NUMBER='TP33',
 VALUE='DELTA-L 4.0',
 PRIM_FILE='./archive_libs/logical/picoprobe_bxa/chips/chips.prt';

PART_NAME
 J121 'PICOPROBE_BXA-DELTA-L 4.0,SMLF,EMPTY,TP33':;

SECTION_NUMBER 1
 '@T6G_MB_LIB.T6G(SCH_1):PAGE211_I96@PURE_QUANTA.PICOPROBE_BXA(CHIPS)':
 C_PATH='@t6g_mb_lib.t6g(sch_1):page211_i96@pure_quanta.picoprobe_bxa(chips)',
 P_PATH='@t6g_mb_lib.t6g(sch_1):page229_i96@pure_quanta.picoprobe_bxa(chips)',
 PATH='I96',
 DRAWING='@T6G_MB_LIB.T6G(SCH_1):PAGE211',
 SEC_TYPE='',
 PART_TYPE='SMLF',
 MATERIAL='EMPTY',
 PHYS_PAGE='229',
 XY='(-1550,825)',
 ROT='4',
 VER='1',
 LOCATION='J121',
 SEC='1',
 CDS_LIB='pure_quanta',
 CDS_PART_NAME='PICOPROBE_BXA-DELTA-L 4.0,SMLF,EMPTY,TP33',
 PART_NUMBER='TP33',
 VALUE='DELTA-L 4.0',
 PRIM_FILE='./archive_libs/logical/picoprobe_bxa/chips/chips.prt';

PART_NAME
 J122 'CONN1_10165288101LF-CONN1_10165288-101LF,THLF,IO,DA':;

SECTION_NUMBER 1
 '@T6G_MB_LIB.T6G(SCH_1):PAGE212_I101@PURE_QUANTA.CONN1_10165288101LF(CHIPS)':
 C_PATH='@t6g_mb_lib.t6g(sch_1):page212_i101@pure_quanta.conn1_10165288101lf(chi~
ps)',
 P_PATH='@t6g_mb_lib.t6g(sch_1):page230_i101@pure_quanta.conn1_10165288101lf(chi~
ps)',
 PATH='I101',
 DRAWING='@T6G_MB_LIB.T6G(SCH_1):PAGE212',
 PART_TYPE='THLF',
 MATERIAL='IO',
 PHYS_PAGE='230',
 XY='(-1650,5400)',
 ROT='0',
 VER='1',
 LOCATION='J122',
 CDS_LIB='pure_quanta',
 CDS_PART_NAME='CONN1_10165288101LF-CONN1_10165288-101LF,THLF,IO,DA',
 PART_NUMBER='DFHS03FR030',
 VALUE='CONN1_10165288-101LF',
 PRIM_FILE='./archive_libs/logical/conn1_10165288101lf/chips/chips.prt';

PART_NAME
 J123 'CONN1_10165288101LF-CONN1_10165288-101LF,THLF,IO,DA':;

SECTION_NUMBER 1
 '@T6G_MB_LIB.T6G(SCH_1):PAGE212_I106@PURE_QUANTA.CONN1_10165288101LF(CHIPS)':
 C_PATH='@t6g_mb_lib.t6g(sch_1):page212_i106@pure_quanta.conn1_10165288101lf(chi~
ps)',
 P_PATH='@t6g_mb_lib.t6g(sch_1):page230_i106@pure_quanta.conn1_10165288101lf(chi~
ps)',
 PATH='I106',
 DRAWING='@T6G_MB_LIB.T6G(SCH_1):PAGE212',
 PART_TYPE='THLF',
 MATERIAL='IO',
 PHYS_PAGE='230',
 XY='(-825,5400)',
 ROT='0',
 VER='1',
 LOCATION='J123',
 CDS_LIB='pure_quanta',
 CDS_PART_NAME='CONN1_10165288101LF-CONN1_10165288-101LF,THLF,IO,DA',
 PART_NUMBER='DFHS03FR030',
 VALUE='CONN1_10165288-101LF',
 PRIM_FILE='./archive_libs/logical/conn1_10165288101lf/chips/chips.prt';

PART_NAME
 J212 'CONN10_HBC1051L300D8H-CONN10_HBC1051-L300D-8H,THLFA':;

SECTION_NUMBER 1
 '@T6G_MB_LIB.T6G(SCH_1):PAGE27_I423@PURE_QUANTA.CONN10_HBC1051L300D8H(CHIPS)':
 C_PATH='@t6g_mb_lib.t6g(sch_1):page27_i423@pure_quanta.conn10_hbc1051l300d8h(ch~
ips)',
 P_PATH='@t6g_mb_lib.t6g(sch_1):page27_i423@pure_quanta.conn10_hbc1051l300d8h(ch~
ips)',
 PATH='I423',
 DRAWING='@T6G_MB_LIB.T6G(SCH_1):PAGE27',
 SEC_TYPE='',
 PART_TYPE='THLF',
 MATERIAL='IO',
 PHYS_PAGE='27',
 XY='(-1475,750)',
 ROT='0',
 VER='1',
 LOCATION='J212',
 SEC='1',
 CDS_LIB='pure_quanta',
 CDS_PART_NAME='CONN10_HBC1051L300D8H-CONN10_HBC1051-L300D-8H,THLFA',
 PART_NUMBER='DFHD10MS117',
 VALUE='CONN10_HBC1051-L300D-8H',
 PRIM_FILE='./archive_libs/logical/conn10_hbc1051l300d8h/chips/chips.prt';

PART_NAME
 J8067 'PICOPROBE_BXA-DELTA-L 4.0,SMLF,EMPTY,TP33':;

SECTION_NUMBER 1
 '@T6G_MB_LIB.T6G(SCH_1):PAGE211_I73@PURE_QUANTA.PICOPROBE_BXA(CHIPS)':
 C_PATH='@t6g_mb_lib.t6g(sch_1):page211_i73@pure_quanta.picoprobe_bxa(chips)',
 P_PATH='@t6g_mb_lib.t6g(sch_1):page229_i73@pure_quanta.picoprobe_bxa(chips)',
 PATH='I73',
 DRAWING='@T6G_MB_LIB.T6G(SCH_1):PAGE211',
 SEC_TYPE='',
 PART_TYPE='SMLF',
 MATERIAL='EMPTY',
 PHYS_PAGE='229',
 XY='(-7700,2900)',
 ROT='0',
 VER='1',
 LOCATION='J8067',
 SEC='1',
 CDS_LIB='pure_quanta',
 CDS_PART_NAME='PICOPROBE_BXA-DELTA-L 4.0,SMLF,EMPTY,TP33',
 PART_NUMBER='TP33',
 VALUE='DELTA-L 4.0',
 PRIM_FILE='./archive_libs/logical/picoprobe_bxa/chips/chips.prt';

PART_NAME
 J8068 'PICOPROBE_BXA-DELTA-L 4.0,SMLF,EMPTY,TP33':;

SECTION_NUMBER 1
 '@T6G_MB_LIB.T6G(SCH_1):PAGE211_I75@PURE_QUANTA.PICOPROBE_BXA(CHIPS)':
 C_PATH='@t6g_mb_lib.t6g(sch_1):page211_i75@pure_quanta.picoprobe_bxa(chips)',
 P_PATH='@t6g_mb_lib.t6g(sch_1):page229_i75@pure_quanta.picoprobe_bxa(chips)',
 PATH='I75',
 DRAWING='@T6G_MB_LIB.T6G(SCH_1):PAGE211',
 SEC_TYPE='',
 PART_TYPE='SMLF',
 MATERIAL='EMPTY',
 PHYS_PAGE='229',
 XY='(-7650,2150)',
 ROT='0',
 VER='1',
 LOCATION='J8068',
 SEC='1',
 CDS_LIB='pure_quanta',
 CDS_PART_NAME='PICOPROBE_BXA-DELTA-L 4.0,SMLF,EMPTY,TP33',
 PART_NUMBER='TP33',
 VALUE='DELTA-L 4.0',
 PRIM_FILE='./archive_libs/logical/picoprobe_bxa/chips/chips.prt';

PART_NAME
 J8069 'PICOPROBE_BXA-DELTA-L 4.0,SMLF,EMPTY,TP33':;

SECTION_NUMBER 1
 '@T6G_MB_LIB.T6G(SCH_1):PAGE211_I66@PURE_QUANTA.PICOPROBE_BXA(CHIPS)':
 C_PATH='@t6g_mb_lib.t6g(sch_1):page211_i66@pure_quanta.picoprobe_bxa(chips)',
 P_PATH='@t6g_mb_lib.t6g(sch_1):page229_i66@pure_quanta.picoprobe_bxa(chips)',
 PATH='I66',
 DRAWING='@T6G_MB_LIB.T6G(SCH_1):PAGE211',
 SEC_TYPE='',
 PART_TYPE='SMLF',
 MATERIAL='EMPTY',
 PHYS_PAGE='229',
 XY='(-5875,5825)',
 ROT='4',
 VER='1',
 LOCATION='J8069',
 SEC='1',
 CDS_LIB='pure_quanta',
 CDS_PART_NAME='PICOPROBE_BXA-DELTA-L 4.0,SMLF,EMPTY,TP33',
 PART_NUMBER='TP33',
 VALUE='DELTA-L 4.0',
 PRIM_FILE='./archive_libs/logical/picoprobe_bxa/chips/chips.prt';

PART_NAME
 JP10 'CONN3_210HP1030BR1-CONN3_210-HP1-030BR1,THLF,IO,DFA':;

SECTION_NUMBER 1
 '@T6G_MB_LIB.T6G(SCH_1):PAGE372_I103@PURE_QUANTA.CONN3_210HP1030BR1(CHIPS)':
 C_PATH='@t6g_mb_lib.t6g(sch_1):page372_i103@pure_quanta.conn3_210hp1030br1(chip~
s)',
 P_PATH='@t6g_mb_lib.t6g(sch_1):page268_i103@pure_quanta.conn3_210hp1030br1(chip~
s)',
 PATH='I103',
 DRAWING='@T6G_MB_LIB.T6G(SCH_1):PAGE372',
 PART_TYPE='THLF',
 MATERIAL='IO',
 PHYS_PAGE='268',
 XY='(-7850,3550)',
 ROT='2',
 VER='1',
 LOCATION='JP10',
 CDS_LIB='pure_quanta',
 CDS_PART_NAME='CONN3_210HP1030BR1-CONN3_210-HP1-030BR1,THLF,IO,DFA',
 PART_NUMBER='DFHD03MS213',
 VALUE='CONN3_210-HP1-030BR1',
 PRIM_FILE='./archive_libs/logical/conn3_210hp1030br1/chips/chips.prt';

PART_NAME
 JP12 'CONN3_210HP1030BR1-CONN3_210-HP1-030BR1,THLF,IO,DFA':;

SECTION_NUMBER 1
 '@T6G_MB_LIB.T6G(SCH_1):PAGE156_I128@PURE_QUANTA.CONN3_210HP1030BR1(CHIPS)':
 C_PATH='@t6g_mb_lib.t6g(sch_1):page156_i128@pure_quanta.conn3_210hp1030br1(chip~
s)',
 P_PATH='@t6g_mb_lib.t6g(sch_1):page187_i128@pure_quanta.conn3_210hp1030br1(chip~
s)',
 PATH='I128',
 DRAWING='@T6G_MB_LIB.T6G(SCH_1):PAGE156',
 PART_TYPE='THLF',
 MATERIAL='IO',
 PHYS_PAGE='187',
 XY='(-1600,7600)',
 ROT='0',
 VER='1',
 LOCATION='JP12',
 CDS_LIB='pure_quanta',
 CDS_PART_NAME='CONN3_210HP1030BR1-CONN3_210-HP1-030BR1,THLF,IO,DFA',
 PART_NUMBER='DFHD03MS213',
 VALUE='CONN3_210-HP1-030BR1',
 PRIM_FILE='./archive_libs/logical/conn3_210hp1030br1/chips/chips.prt';

PART_NAME
 JP4003 'CONN3_210HP1030BR1-CONN3_210-HP1-030BR1,THLF,IO,DFA':;

SECTION_NUMBER 1
 '@T6G_MB_LIB.T6G(SCH_1):PAGE372_I18@PURE_QUANTA.CONN3_210HP1030BR1(CHIPS)':
 C_PATH='@t6g_mb_lib.t6g(sch_1):page372_i18@pure_quanta.conn3_210hp1030br1(chips~
)',
 P_PATH='@t6g_mb_lib.t6g(sch_1):page268_i18@pure_quanta.conn3_210hp1030br1(chips~
)',
 PATH='I18',
 DRAWING='@T6G_MB_LIB.T6G(SCH_1):PAGE372',
 PART_TYPE='THLF',
 MATERIAL='IO',
 PHYS_PAGE='268',
 XY='(-7975,1950)',
 ROT='0',
 VER='1',
 LOCATION='JP4003',
 CDS_LIB='pure_quanta',
 CDS_PART_NAME='CONN3_210HP1030BR1-CONN3_210-HP1-030BR1,THLF,IO,DFA',
 PART_NUMBER='DFHD03MS213',
 VALUE='CONN3_210-HP1-030BR1',
 PRIM_FILE='./archive_libs/logical/conn3_210hp1030br1/chips/chips.prt';

PART_NAME
 JP6000 'CONN3_210HP1030BR1-CONN3_210-HP1-030BR1,THLF,IO,DFA':;

SECTION_NUMBER 1
 '@T6G_MB_LIB.T6G(SCH_1):PAGE148_I386@PURE_QUANTA.CONN3_210HP1030BR1(CHIPS)':
 C_PATH='@t6g_mb_lib.t6g(sch_1):page148_i386@pure_quanta.conn3_210hp1030br1(chip~
s)',
 P_PATH='@t6g_mb_lib.t6g(sch_1):page171_i386@pure_quanta.conn3_210hp1030br1(chip~
s)',
 PATH='I386',
 DRAWING='@T6G_MB_LIB.T6G(SCH_1):PAGE148',
 SEC_TYPE='',
 PART_TYPE='THLF',
 MATERIAL='IO',
 PHYS_PAGE='171',
 XY='(-4700,1200)',
 ROT='0',
 VER='1',
 LOCATION='JP6000',
 SEC='1',
 CDS_LIB='pure_quanta',
 CDS_PART_NAME='CONN3_210HP1030BR1-CONN3_210-HP1-030BR1,THLF,IO,DFA',
 PART_NUMBER='DFHD03MS213',
 VALUE='CONN3_210-HP1-030BR1',
 PRIM_FILE='./archive_libs/logical/conn3_210hp1030br1/chips/chips.prt';

PART_NAME
 JP6001 'CONN3_210HP1030BR1-CONN3_210-HP1-030BR1,THLF,IO,DFA':;

SECTION_NUMBER 1
 '@T6G_MB_LIB.T6G(SCH_1):PAGE148_I387@PURE_QUANTA.CONN3_210HP1030BR1(CHIPS)':
 C_PATH='@t6g_mb_lib.t6g(sch_1):page148_i387@pure_quanta.conn3_210hp1030br1(chip~
s)',
 P_PATH='@t6g_mb_lib.t6g(sch_1):page171_i387@pure_quanta.conn3_210hp1030br1(chip~
s)',
 PATH='I387',
 DRAWING='@T6G_MB_LIB.T6G(SCH_1):PAGE148',
 PART_TYPE='THLF',
 MATERIAL='IO',
 PHYS_PAGE='171',
 XY='(-3650,3150)',
 ROT='0',
 VER='1',
 LOCATION='JP6001',
 CDS_LIB='pure_quanta',
 CDS_PART_NAME='CONN3_210HP1030BR1-CONN3_210-HP1-030BR1,THLF,IO,DFA',
 PART_NUMBER='DFHD03MS213',
 VALUE='CONN3_210-HP1-030BR1',
 PRIM_FILE='./archive_libs/logical/conn3_210hp1030br1/chips/chips.prt';

PART_NAME
 JP6500 'CONN3_210HP1030BR1-CONN3_210-HP1-030BR1,THLF,IO,DFA':;

SECTION_NUMBER 1
 '@T6G_MB_LIB.T6G(SCH_1):PAGE378_I116@PURE_QUANTA.CONN3_210HP1030BR1(CHIPS)':
 C_PATH='@t6g_mb_lib.t6g(sch_1):page378_i116@pure_quanta.conn3_210hp1030br1(chip~
s)',
 P_PATH='@t6g_mb_lib.t6g(sch_1):page184_i116@pure_quanta.conn3_210hp1030br1(chip~
s)',
 PATH='I116',
 DRAWING='@T6G_MB_LIB.T6G(SCH_1):PAGE378',
 PART_TYPE='THLF',
 MATERIAL='IO',
 PHYS_PAGE='184',
 XY='(-800,5450)',
 ROT='0',
 VER='1',
 LOCATION='JP6500',
 CDS_LIB='pure_quanta',
 CDS_PART_NAME='CONN3_210HP1030BR1-CONN3_210-HP1-030BR1,THLF,IO,DFA',
 PART_NUMBER='DFHD03MS213',
 VALUE='CONN3_210-HP1-030BR1',
 PRIM_FILE='./archive_libs/logical/conn3_210hp1030br1/chips/chips.prt';

PART_NAME
 L1 'Q_INDUCTOR_SMLF-FCM2012KF-601T/0.5A,IND,CX601T05003':;

SECTION_NUMBER 1
 '@T6G_MB_LIB.T6G(SCH_1):PAGE379_I2@PURE_QUANTA.Q_INDUCTOR(CHIPS)':
 C_PATH='@t6g_mb_lib.t6g(sch_1):page379_i2@pure_quanta.q_inductor(chips)',
 P_PATH='@t6g_mb_lib.t6g(sch_1):page183_i2@pure_quanta.q_inductor(chips)',
 PATH='I2',
 DRAWING='@T6G_MB_LIB.T6G(SCH_1):PAGE379',
 MATERIAL='IND',
 PHYS_PAGE='183',
 XY='(-8450,5850)',
 ROT='0',
 VER='1',
 PACK_TYPE='SMLF',
 LOCATION='L1',
 CDS_LIB='pure_quanta',
 CDS_PART_NAME='Q_INDUCTOR_SMLF-FCM2012KF-601T/0.5A,IND,CX601T05003',
 PART_NUMBER='CX601T05003',
 VALUE='FCM2012KF-601T/0.5A',
 PRIM_FILE='./archive_libs/logical/q_inductor/chips/chips.prt';

PART_NAME
 L2 'Q_INDUCTOR_SMLF-FCM2012KF-601T/0.5A,IND,CX601T05003':;

SECTION_NUMBER 1
 '@T6G_MB_LIB.T6G(SCH_1):PAGE379_I32@PURE_QUANTA.Q_INDUCTOR(CHIPS)':
 C_PATH='@t6g_mb_lib.t6g(sch_1):page379_i32@pure_quanta.q_inductor(chips)',
 P_PATH='@t6g_mb_lib.t6g(sch_1):page183_i32@pure_quanta.q_inductor(chips)',
 PATH='I32',
 DRAWING='@T6G_MB_LIB.T6G(SCH_1):PAGE379',
 MATERIAL='IND',
 PHYS_PAGE='183',
 XY='(-5125,5525)',
 ROT='0',
 VER='1',
 PACK_TYPE='SMLF',
 LOCATION='L2',
 CDS_LIB='pure_quanta',
 CDS_PART_NAME='Q_INDUCTOR_SMLF-FCM2012KF-601T/0.5A,IND,CX601T05003',
 PART_NUMBER='CX601T05003',
 VALUE='FCM2012KF-601T/0.5A',
 PRIM_FILE='./archive_libs/logical/q_inductor/chips/chips.prt';

PART_NAME
 L3 'Q_INDUCTOR_SMLF-BLM21SN300SN1D/5A,IND,CX300SN1000':;

SECTION_NUMBER 1
 '@T6G_MB_LIB.T6G(SCH_1):PAGE398_I22@PURE_QUANTA.Q_INDUCTOR(CHIPS)':
 C_PATH='@t6g_mb_lib.t6g(sch_1):page398_i22@pure_quanta.q_inductor(chips)',
 P_PATH='@t6g_mb_lib.t6g(sch_1):page323_i22@pure_quanta.q_inductor(chips)',
 PATH='I22',
 DRAWING='@T6G_MB_LIB.T6G(SCH_1):PAGE398',
 MATERIAL='IND',
 PHYS_PAGE='323',
 XY='(-8050,4750)',
 ROT='0',
 VER='1',
 PACK_TYPE='SMLF',
 LOCATION='L3',
 CDS_LIB='pure_quanta',
 CDS_PART_NAME='Q_INDUCTOR_SMLF-BLM21SN300SN1D/5A,IND,CX300SN1000',
 PART_NUMBER='CX300SN1000',
 VALUE='BLM21SN300SN1D/5A',
 PRIM_FILE='./archive_libs/logical/q_inductor/chips/chips.prt';

PART_NAME
 L4 'Q_INDUCTOR_SMLF-100NH/16A,IND,CV+10G0MZ04':;

SECTION_NUMBER 1
 '@T6G_MB_LIB.T6G(SCH_1):PAGE398_I74@PURE_QUANTA.Q_INDUCTOR(CHIPS)':
 C_PATH='@t6g_mb_lib.t6g(sch_1):page398_i74@pure_quanta.q_inductor(chips)',
 P_PATH='@t6g_mb_lib.t6g(sch_1):page323_i74@pure_quanta.q_inductor(chips)',
 PATH='I74',
 DRAWING='@T6G_MB_LIB.T6G(SCH_1):PAGE398',
 MATERIAL='IND',
 PHYS_PAGE='323',
 XY='(-4100,4750)',
 ROT='0',
 VER='1',
 PACK_TYPE='SMLF',
 LOCATION='L4',
 CDS_LIB='pure_quanta',
 CDS_PART_NAME='Q_INDUCTOR_SMLF-100NH/16A,IND,CV+10G0MZ04',
 PART_NUMBER='CV+10G0MZ04',
 VALUE='100NH/16A',
 PRIM_FILE='./archive_libs/logical/q_inductor/chips/chips.prt';

PART_NAME
 L5 'Q_INDUCTOR_SMLF-BLM21SN300SN1D/5A,IND,CX300SN1000':;

SECTION_NUMBER 1
 '@T6G_MB_LIB.T6G(SCH_1):PAGE443_I12@PURE_QUANTA.Q_INDUCTOR(CHIPS)':
 C_PATH='@t6g_mb_lib.t6g(sch_1):page443_i12@pure_quanta.q_inductor(chips)',
 P_PATH='@t6g_mb_lib.t6g(sch_1):page334_i12@pure_quanta.q_inductor(chips)',
 PATH='I12',
 DRAWING='@T6G_MB_LIB.T6G(SCH_1):PAGE443',
 MATERIAL='IND',
 PHYS_PAGE='334',
 XY='(-7800,4275)',
 ROT='0',
 VER='1',
 PACK_TYPE='SMLF',
 LOCATION='L5',
 CDS_LIB='pure_quanta',
 CDS_PART_NAME='Q_INDUCTOR_SMLF-BLM21SN300SN1D/5A,IND,CX300SN1000',
 PART_NUMBER='CX300SN1000',
 VALUE='BLM21SN300SN1D/5A',
 PRIM_FILE='./archive_libs/logical/q_inductor/chips/chips.prt';

PART_NAME
 L6 'Q_INDUCTOR_SMLF-100NH/16A,IND,CV+10G0MZ04':;

SECTION_NUMBER 1
 '@T6G_MB_LIB.T6G(SCH_1):PAGE443_I30@PURE_QUANTA.Q_INDUCTOR(CHIPS)':
 C_PATH='@t6g_mb_lib.t6g(sch_1):page443_i30@pure_quanta.q_inductor(chips)',
 P_PATH='@t6g_mb_lib.t6g(sch_1):page334_i30@pure_quanta.q_inductor(chips)',
 PATH='I30',
 DRAWING='@T6G_MB_LIB.T6G(SCH_1):PAGE443',
 MATERIAL='IND',
 PHYS_PAGE='334',
 XY='(-3850,4275)',
 ROT='0',
 VER='1',
 PACK_TYPE='SMLF',
 LOCATION='L6',
 CDS_LIB='pure_quanta',
 CDS_PART_NAME='Q_INDUCTOR_SMLF-100NH/16A,IND,CV+10G0MZ04',
 PART_NUMBER='CV+10G0MZ04',
 VALUE='100NH/16A',
 PRIM_FILE='./archive_libs/logical/q_inductor/chips/chips.prt';

PART_NAME
 L7 'Q_INDUCTOR_SMLF-BLM21SN300SN1D/5A,IND,CX300SN1000':;

SECTION_NUMBER 1
 '@T6G_MB_LIB.T6G(SCH_1):PAGE454_I21@PURE_QUANTA.Q_INDUCTOR(CHIPS)':
 C_PATH='@t6g_mb_lib.t6g(sch_1):page454_i21@pure_quanta.q_inductor(chips)',
 P_PATH='@t6g_mb_lib.t6g(sch_1):page345_i21@pure_quanta.q_inductor(chips)',
 PATH='I21',
 DRAWING='@T6G_MB_LIB.T6G(SCH_1):PAGE454',
 MATERIAL='IND',
 PHYS_PAGE='345',
 XY='(-7725,4600)',
 ROT='0',
 VER='1',
 PACK_TYPE='SMLF',
 LOCATION='L7',
 CDS_LIB='pure_quanta',
 CDS_PART_NAME='Q_INDUCTOR_SMLF-BLM21SN300SN1D/5A,IND,CX300SN1000',
 PART_NUMBER='CX300SN1000',
 VALUE='BLM21SN300SN1D/5A',
 PRIM_FILE='./archive_libs/logical/q_inductor/chips/chips.prt';

PART_NAME
 L8 'Q_INDUCTOR_SMLF-100NH/16A,IND,CV+10G0MZ04':;

SECTION_NUMBER 1
 '@T6G_MB_LIB.T6G(SCH_1):PAGE454_I74@PURE_QUANTA.Q_INDUCTOR(CHIPS)':
 C_PATH='@t6g_mb_lib.t6g(sch_1):page454_i74@pure_quanta.q_inductor(chips)',
 P_PATH='@t6g_mb_lib.t6g(sch_1):page345_i74@pure_quanta.q_inductor(chips)',
 PATH='I74',
 DRAWING='@T6G_MB_LIB.T6G(SCH_1):PAGE454',
 MATERIAL='IND',
 PHYS_PAGE='345',
 XY='(-3775,4600)',
 ROT='0',
 VER='1',
 PACK_TYPE='SMLF',
 LOCATION='L8',
 CDS_LIB='pure_quanta',
 CDS_PART_NAME='Q_INDUCTOR_SMLF-100NH/16A,IND,CV+10G0MZ04',
 PART_NUMBER='CV+10G0MZ04',
 VALUE='100NH/16A',
 PRIM_FILE='./archive_libs/logical/q_inductor/chips/chips.prt';

PART_NAME
 L9 'Q_INDUCTOR_SMLF-BLM21SN300SN1D/5A,IND,CX300SN1000':;

SECTION_NUMBER 1
 '@T6G_MB_LIB.T6G(SCH_1):PAGE465_I11@PURE_QUANTA.Q_INDUCTOR(CHIPS)':
 C_PATH='@t6g_mb_lib.t6g(sch_1):page465_i11@pure_quanta.q_inductor(chips)',
 P_PATH='@t6g_mb_lib.t6g(sch_1):page356_i11@pure_quanta.q_inductor(chips)',
 PATH='I11',
 DRAWING='@T6G_MB_LIB.T6G(SCH_1):PAGE465',
 MATERIAL='IND',
 PHYS_PAGE='356',
 XY='(-7775,4425)',
 ROT='0',
 VER='1',
 PACK_TYPE='SMLF',
 LOCATION='L9',
 CDS_LIB='pure_quanta',
 CDS_PART_NAME='Q_INDUCTOR_SMLF-BLM21SN300SN1D/5A,IND,CX300SN1000',
 PART_NUMBER='CX300SN1000',
 VALUE='BLM21SN300SN1D/5A',
 PRIM_FILE='./archive_libs/logical/q_inductor/chips/chips.prt';

PART_NAME
 L10 'Q_INDUCTOR_SMLF-100NH/16A,IND,CV+10G0MZ04':;

SECTION_NUMBER 1
 '@T6G_MB_LIB.T6G(SCH_1):PAGE465_I63@PURE_QUANTA.Q_INDUCTOR(CHIPS)':
 C_PATH='@t6g_mb_lib.t6g(sch_1):page465_i63@pure_quanta.q_inductor(chips)',
 P_PATH='@t6g_mb_lib.t6g(sch_1):page356_i63@pure_quanta.q_inductor(chips)',
 PATH='I63',
 DRAWING='@T6G_MB_LIB.T6G(SCH_1):PAGE465',
 MATERIAL='IND',
 PHYS_PAGE='356',
 XY='(-3825,4425)',
 ROT='0',
 VER='1',
 PACK_TYPE='SMLF',
 LOCATION='L10',
 CDS_LIB='pure_quanta',
 CDS_PART_NAME='Q_INDUCTOR_SMLF-100NH/16A,IND,CV+10G0MZ04',
 PART_NUMBER='CV+10G0MZ04',
 VALUE='100NH/16A',
 PRIM_FILE='./archive_libs/logical/q_inductor/chips/chips.prt';

PART_NAME
 L11 'Q_INDUCTOR_SMLF-BLM21SN300SN1D/5A,IND,CX300SN1000':;

SECTION_NUMBER 1
 '@T6G_MB_LIB.T6G(SCH_1):PAGE388_I12@PURE_QUANTA.Q_INDUCTOR(CHIPS)':
 C_PATH='@t6g_mb_lib.t6g(sch_1):page388_i12@pure_quanta.q_inductor(chips)',
 P_PATH='@t6g_mb_lib.t6g(sch_1):page279_i12@pure_quanta.q_inductor(chips)',
 PATH='I12',
 DRAWING='@T6G_MB_LIB.T6G(SCH_1):PAGE388',
 MATERIAL='IND',
 PHYS_PAGE='279',
 XY='(-7775,4475)',
 ROT='0',
 VER='1',
 PACK_TYPE='SMLF',
 LOCATION='L11',
 CDS_LIB='pure_quanta',
 CDS_PART_NAME='Q_INDUCTOR_SMLF-BLM21SN300SN1D/5A,IND,CX300SN1000',
 PART_NUMBER='CX300SN1000',
 VALUE='BLM21SN300SN1D/5A',
 PRIM_FILE='./archive_libs/logical/q_inductor/chips/chips.prt';

PART_NAME
 L12 'Q_INDUCTOR_SMLF-100NH/16A,IND,CV+10G0MZ04':;

SECTION_NUMBER 1
 '@T6G_MB_LIB.T6G(SCH_1):PAGE388_I30@PURE_QUANTA.Q_INDUCTOR(CHIPS)':
 C_PATH='@t6g_mb_lib.t6g(sch_1):page388_i30@pure_quanta.q_inductor(chips)',
 P_PATH='@t6g_mb_lib.t6g(sch_1):page279_i30@pure_quanta.q_inductor(chips)',
 PATH='I30',
 DRAWING='@T6G_MB_LIB.T6G(SCH_1):PAGE388',
 MATERIAL='IND',
 PHYS_PAGE='279',
 XY='(-3825,4475)',
 ROT='0',
 VER='1',
 PACK_TYPE='SMLF',
 LOCATION='L12',
 CDS_LIB='pure_quanta',
 CDS_PART_NAME='Q_INDUCTOR_SMLF-100NH/16A,IND,CV+10G0MZ04',
 PART_NUMBER='CV+10G0MZ04',
 VALUE='100NH/16A',
 PRIM_FILE='./archive_libs/logical/q_inductor/chips/chips.prt';

PART_NAME
 L13 'Q_INDUCTOR_SMLF-BLM21SN300SN1D/5A,IND,CX300SN1000':;

SECTION_NUMBER 1
 '@T6G_MB_LIB.T6G(SCH_1):PAGE411_I11@PURE_QUANTA.Q_INDUCTOR(CHIPS)':
 C_PATH='@t6g_mb_lib.t6g(sch_1):page411_i11@pure_quanta.q_inductor(chips)',
 P_PATH='@t6g_mb_lib.t6g(sch_1):page290_i11@pure_quanta.q_inductor(chips)',
 PATH='I11',
 DRAWING='@T6G_MB_LIB.T6G(SCH_1):PAGE411',
 MATERIAL='IND',
 PHYS_PAGE='290',
 XY='(-7950,4175)',
 ROT='0',
 VER='1',
 PACK_TYPE='SMLF',
 LOCATION='L13',
 CDS_LIB='pure_quanta',
 CDS_PART_NAME='Q_INDUCTOR_SMLF-BLM21SN300SN1D/5A,IND,CX300SN1000',
 PART_NUMBER='CX300SN1000',
 VALUE='BLM21SN300SN1D/5A',
 PRIM_FILE='./archive_libs/logical/q_inductor/chips/chips.prt';

PART_NAME
 L14 'Q_INDUCTOR_SMLF-100NH/16A,IND,CV+10G0MZ04':;

SECTION_NUMBER 1
 '@T6G_MB_LIB.T6G(SCH_1):PAGE411_I63@PURE_QUANTA.Q_INDUCTOR(CHIPS)':
 C_PATH='@t6g_mb_lib.t6g(sch_1):page411_i63@pure_quanta.q_inductor(chips)',
 P_PATH='@t6g_mb_lib.t6g(sch_1):page290_i63@pure_quanta.q_inductor(chips)',
 PATH='I63',
 DRAWING='@T6G_MB_LIB.T6G(SCH_1):PAGE411',
 MATERIAL='IND',
 PHYS_PAGE='290',
 XY='(-4000,4175)',
 ROT='0',
 VER='1',
 PACK_TYPE='SMLF',
 LOCATION='L14',
 CDS_LIB='pure_quanta',
 CDS_PART_NAME='Q_INDUCTOR_SMLF-100NH/16A,IND,CV+10G0MZ04',
 PART_NUMBER='CV+10G0MZ04',
 VALUE='100NH/16A',
 PRIM_FILE='./archive_libs/logical/q_inductor/chips/chips.prt';

PART_NAME
 L15 'Q_INDUCTOR_SMLF-BLM18PG300SN1D ,IND,TMP_QCX8PG3000A':;

SECTION_NUMBER 1
 '@T6G_MB_LIB.T6G(SCH_1):PAGE369_I167@PURE_QUANTA.Q_INDUCTOR(CHIPS)':
 C_PATH='@t6g_mb_lib.t6g(sch_1):page369_i167@pure_quanta.q_inductor(chips)',
 P_PATH='@t6g_mb_lib.t6g(sch_1):page257_i167@pure_quanta.q_inductor(chips)',
 PATH='I167',
 DRAWING='@T6G_MB_LIB.T6G(SCH_1):PAGE369',
 MATERIAL='IND',
 PHYS_PAGE='257',
 XY='(-800,5550)',
 ROT='0',
 VER='1',
 PACK_TYPE='SMLF',
 LOCATION='L15',
 CDS_LIB='pure_quanta',
 CDS_PART_NAME='Q_INDUCTOR_SMLF-BLM18PG300SN1D ,IND,TMP_QCX8PG3000A',
 PART_NUMBER='TMP_QCX8PG300001',
 VALUE='BLM18PG300SN1D ',
 PRIM_FILE='./archive_libs/logical/q_inductor/chips/chips.prt';

PART_NAME
 L16 'Q_INDUCTOR_SMLF-BLM18PG300SN1D ,IND,TMP_QCX8PG3000A':
 ROOM='ADC_TI_BOM1';

SECTION_NUMBER 1
 '@T6G_MB_LIB.T6G(SCH_1):PAGE369_I69@PURE_QUANTA.Q_INDUCTOR(CHIPS)':
 C_PATH='@t6g_mb_lib.t6g(sch_1):page369_i69@pure_quanta.q_inductor(chips)',
 P_PATH='@t6g_mb_lib.t6g(sch_1):page257_i69@pure_quanta.q_inductor(chips)',
 PATH='I69',
 DRAWING='@T6G_MB_LIB.T6G(SCH_1):PAGE369',
 MATERIAL='IND',
 PHYS_PAGE='257',
 XY='(-4350,2725)',
 ROT='0',
 VER='1',
 PACK_TYPE='SMLF',
 LOCATION='L16',
 CDS_LIB='pure_quanta',
 CDS_PART_NAME='Q_INDUCTOR_SMLF-BLM18PG300SN1D ,IND,TMP_QCX8PG3000A',
 ROOM='ADC_TI_BOM1',
 PART_NUMBER='TMP_QCX8PG300001',
 VALUE='BLM18PG300SN1D ',
 PRIM_FILE='./archive_libs/logical/q_inductor/chips/chips.prt';

PART_NAME
 L17 'Q_INDUCTOR_SMLF-FCM2012KF-601T/0.5A,IND,CX601T05003':;

SECTION_NUMBER 1
 '@T6G_MB_LIB.T6G(SCH_1):PAGE232_I33@PURE_QUANTA.Q_INDUCTOR(CHIPS)':
 C_PATH='@t6g_mb_lib.t6g(sch_1):page232_i33@pure_quanta.q_inductor(chips)',
 P_PATH='@t6g_mb_lib.t6g(sch_1):page233_i33@pure_quanta.q_inductor(chips)',
 PATH='I33',
 DRAWING='@T6G_MB_LIB.T6G(SCH_1):PAGE232',
 MATERIAL='IND',
 PHYS_PAGE='233',
 XY='(-6050,5425)',
 ROT='0',
 VER='1',
 PACK_TYPE='SMLF',
 LOCATION='L17',
 CDS_LIB='pure_quanta',
 CDS_PART_NAME='Q_INDUCTOR_SMLF-FCM2012KF-601T/0.5A,IND,CX601T05003',
 PART_NUMBER='CX601T05003',
 VALUE='FCM2012KF-601T/0.5A',
 PRIM_FILE='./archive_libs/logical/q_inductor/chips/chips.prt';

PART_NAME
 L18 'Q_INDUCTOR_SMLF-BLM21SN300SN1D/5A,IND,CX300SN1000':;

SECTION_NUMBER 1
 '@T6G_MB_LIB.T6G(SCH_1):PAGE422_I23@PURE_QUANTA.Q_INDUCTOR(CHIPS)':
 C_PATH='@t6g_mb_lib.t6g(sch_1):page422_i23@pure_quanta.q_inductor(chips)',
 P_PATH='@t6g_mb_lib.t6g(sch_1):page301_i23@pure_quanta.q_inductor(chips)',
 PATH='I23',
 DRAWING='@T6G_MB_LIB.T6G(SCH_1):PAGE422',
 MATERIAL='IND',
 PHYS_PAGE='301',
 XY='(-7625,4750)',
 ROT='0',
 VER='1',
 PACK_TYPE='SMLF',
 LOCATION='L18',
 CDS_LIB='pure_quanta',
 CDS_PART_NAME='Q_INDUCTOR_SMLF-BLM21SN300SN1D/5A,IND,CX300SN1000',
 PART_NUMBER='CX300SN1000',
 VALUE='BLM21SN300SN1D/5A',
 PRIM_FILE='./archive_libs/logical/q_inductor/chips/chips.prt';

PART_NAME
 L19 'Q_INDUCTOR_SMLF-FCM2012KF-601T/0.5A,IND,CX601T05003':;

SECTION_NUMBER 1
 '@T6G_MB_LIB.T6G(SCH_1):PAGE160_I26@PURE_QUANTA.Q_INDUCTOR(CHIPS)':
 C_PATH='@t6g_mb_lib.t6g(sch_1):page160_i26@pure_quanta.q_inductor(chips)',
 P_PATH='@t6g_mb_lib.t6g(sch_1):page182_i26@pure_quanta.q_inductor(chips)',
 PATH='I26',
 DRAWING='@T6G_MB_LIB.T6G(SCH_1):PAGE160',
 MATERIAL='IND',
 PHYS_PAGE='182',
 XY='(-8775,6075)',
 ROT='0',
 VER='1',
 PACK_TYPE='SMLF',
 LOCATION='L19',
 CDS_LIB='pure_quanta',
 CDS_PART_NAME='Q_INDUCTOR_SMLF-FCM2012KF-601T/0.5A,IND,CX601T05003',
 PART_NUMBER='CX601T05003',
 VALUE='FCM2012KF-601T/0.5A',
 PRIM_FILE='./archive_libs/logical/q_inductor/chips/chips.prt';

PART_NAME
 L20 'Q_INDUCTOR_SMLF-FCM2012KF-601T/0.5A,IND,CX601T05003':;

SECTION_NUMBER 1
 '@T6G_MB_LIB.T6G(SCH_1):PAGE160_I24@PURE_QUANTA.Q_INDUCTOR(CHIPS)':
 C_PATH='@t6g_mb_lib.t6g(sch_1):page160_i24@pure_quanta.q_inductor(chips)',
 P_PATH='@t6g_mb_lib.t6g(sch_1):page182_i24@pure_quanta.q_inductor(chips)',
 PATH='I24',
 DRAWING='@T6G_MB_LIB.T6G(SCH_1):PAGE160',
 MATERIAL='IND',
 PHYS_PAGE='182',
 XY='(-5450,5750)',
 ROT='0',
 VER='1',
 PACK_TYPE='SMLF',
 LOCATION='L20',
 CDS_LIB='pure_quanta',
 CDS_PART_NAME='Q_INDUCTOR_SMLF-FCM2012KF-601T/0.5A,IND,CX601T05003',
 PART_NUMBER='CX601T05003',
 VALUE='FCM2012KF-601T/0.5A',
 PRIM_FILE='./archive_libs/logical/q_inductor/chips/chips.prt';

PART_NAME
 L21 'Q_INDUCTOR_SMLF-100NH/16A,IND,CV+10G0MZ04':;

SECTION_NUMBER 1
 '@T6G_MB_LIB.T6G(SCH_1):PAGE422_I30@PURE_QUANTA.Q_INDUCTOR(CHIPS)':
 C_PATH='@t6g_mb_lib.t6g(sch_1):page422_i30@pure_quanta.q_inductor(chips)',
 P_PATH='@t6g_mb_lib.t6g(sch_1):page301_i30@pure_quanta.q_inductor(chips)',
 PATH='I30',
 DRAWING='@T6G_MB_LIB.T6G(SCH_1):PAGE422',
 MATERIAL='IND',
 PHYS_PAGE='301',
 XY='(-3675,4750)',
 ROT='0',
 VER='1',
 PACK_TYPE='SMLF',
 LOCATION='L21',
 CDS_LIB='pure_quanta',
 CDS_PART_NAME='Q_INDUCTOR_SMLF-100NH/16A,IND,CV+10G0MZ04',
 PART_NUMBER='CV+10G0MZ04',
 VALUE='100NH/16A',
 PRIM_FILE='./archive_libs/logical/q_inductor/chips/chips.prt';

PART_NAME
 L22 'Q_INDUCTOR_SMLF-BLM21SN300SN1D/5A,IND,CX300SN1000':;

SECTION_NUMBER 1
 '@T6G_MB_LIB.T6G(SCH_1):PAGE433_I10@PURE_QUANTA.Q_INDUCTOR(CHIPS)':
 C_PATH='@t6g_mb_lib.t6g(sch_1):page433_i10@pure_quanta.q_inductor(chips)',
 P_PATH='@t6g_mb_lib.t6g(sch_1):page312_i10@pure_quanta.q_inductor(chips)',
 PATH='I10',
 DRAWING='@T6G_MB_LIB.T6G(SCH_1):PAGE433',
 MATERIAL='IND',
 PHYS_PAGE='312',
 XY='(-7925,4650)',
 ROT='0',
 VER='1',
 PACK_TYPE='SMLF',
 LOCATION='L22',
 CDS_LIB='pure_quanta',
 CDS_PART_NAME='Q_INDUCTOR_SMLF-BLM21SN300SN1D/5A,IND,CX300SN1000',
 PART_NUMBER='CX300SN1000',
 VALUE='BLM21SN300SN1D/5A',
 PRIM_FILE='./archive_libs/logical/q_inductor/chips/chips.prt';

PART_NAME
 L23 'Q_INDUCTOR_SMLF-100NH/16A,IND,CV+10G0MZ04':;

SECTION_NUMBER 1
 '@T6G_MB_LIB.T6G(SCH_1):PAGE433_I65@PURE_QUANTA.Q_INDUCTOR(CHIPS)':
 C_PATH='@t6g_mb_lib.t6g(sch_1):page433_i65@pure_quanta.q_inductor(chips)',
 P_PATH='@t6g_mb_lib.t6g(sch_1):page312_i65@pure_quanta.q_inductor(chips)',
 PATH='I65',
 DRAWING='@T6G_MB_LIB.T6G(SCH_1):PAGE433',
 MATERIAL='IND',
 PHYS_PAGE='312',
 XY='(-3975,4650)',
 ROT='0',
 VER='1',
 PACK_TYPE='SMLF',
 LOCATION='L23',
 CDS_LIB='pure_quanta',
 CDS_PART_NAME='Q_INDUCTOR_SMLF-100NH/16A,IND,CV+10G0MZ04',
 PART_NUMBER='CV+10G0MZ04',
 VALUE='100NH/16A',
 PRIM_FILE='./archive_libs/logical/q_inductor/chips/chips.prt';

PART_NAME
 L24 'Q_INDUCTOR_SMLF-BLM18PG300SN1D ,IND,TMP_QCX8PG3000A':;

SECTION_NUMBER 1
 '@T6G_MB_LIB.T6G(SCH_1):PAGE263_I168@PURE_QUANTA.Q_INDUCTOR(CHIPS)':
 C_PATH='@t6g_mb_lib.t6g(sch_1):page263_i168@pure_quanta.q_inductor(chips)',
 P_PATH='@t6g_mb_lib.t6g(sch_1):page258_i168@pure_quanta.q_inductor(chips)',
 PATH='I168',
 DRAWING='@T6G_MB_LIB.T6G(SCH_1):PAGE263',
 MATERIAL='IND',
 PHYS_PAGE='258',
 XY='(-750,5400)',
 ROT='0',
 VER='1',
 PACK_TYPE='SMLF',
 LOCATION='L24',
 CDS_LIB='pure_quanta',
 CDS_PART_NAME='Q_INDUCTOR_SMLF-BLM18PG300SN1D ,IND,TMP_QCX8PG3000A',
 PART_NUMBER='TMP_QCX8PG300001',
 VALUE='BLM18PG300SN1D ',
 PRIM_FILE='./archive_libs/logical/q_inductor/chips/chips.prt';

PART_NAME
 L25 'Q_INDUCTOR_SMLF-BLM18PG300SN1D ,IND,TMP_QCX8PG3000A':
 ROOM='ADC_TI_BOM1';

SECTION_NUMBER 1
 '@T6G_MB_LIB.T6G(SCH_1):PAGE263_I69@PURE_QUANTA.Q_INDUCTOR(CHIPS)':
 C_PATH='@t6g_mb_lib.t6g(sch_1):page263_i69@pure_quanta.q_inductor(chips)',
 P_PATH='@t6g_mb_lib.t6g(sch_1):page258_i69@pure_quanta.q_inductor(chips)',
 PATH='I69',
 DRAWING='@T6G_MB_LIB.T6G(SCH_1):PAGE263',
 MATERIAL='IND',
 PHYS_PAGE='258',
 XY='(-4300,2575)',
 ROT='0',
 VER='1',
 PACK_TYPE='SMLF',
 LOCATION='L25',
 CDS_LIB='pure_quanta',
 CDS_PART_NAME='Q_INDUCTOR_SMLF-BLM18PG300SN1D ,IND,TMP_QCX8PG3000A',
 ROOM='ADC_TI_BOM1',
 PART_NUMBER='TMP_QCX8PG300001',
 VALUE='BLM18PG300SN1D ',
 PRIM_FILE='./archive_libs/logical/q_inductor/chips/chips.prt';

PART_NAME
 L26 'Q_INDUCTOR_SMLF-BLM15PD121SN1D/1300MA,IND,CX5PD121A':;

SECTION_NUMBER 1
 '@T6G_MB_LIB.T6G(SCH_1):PAGE388_I88@PURE_QUANTA.Q_INDUCTOR(CHIPS)':
 C_PATH='@t6g_mb_lib.t6g(sch_1):page388_i88@pure_quanta.q_inductor(chips)',
 P_PATH='@t6g_mb_lib.t6g(sch_1):page279_i88@pure_quanta.q_inductor(chips)',
 PATH='I88',
 DRAWING='@T6G_MB_LIB.T6G(SCH_1):PAGE388',
 MATERIAL='IND',
 PHYS_PAGE='279',
 XY='(-8225,4125)',
 ROT='3',
 VER='1',
 PACK_TYPE='SMLF',
 LOCATION='L26',
 CDS_LIB='pure_quanta',
 CDS_PART_NAME='Q_INDUCTOR_SMLF-BLM15PD121SN1D/1300MA,IND,CX5PD121A',
 PART_NUMBER='CX5PD121000',
 VALUE='BLM15PD121SN1D/1300MA',
 PRIM_FILE='./archive_libs/logical/q_inductor/chips/chips.prt';

PART_NAME
 L27 'Q_INDUCTOR_SMLF-BLM15PD121SN1D/1300MA,IND,CX5PD121A':;

SECTION_NUMBER 1
 '@T6G_MB_LIB.T6G(SCH_1):PAGE398_I97@PURE_QUANTA.Q_INDUCTOR(CHIPS)':
 C_PATH='@t6g_mb_lib.t6g(sch_1):page398_i97@pure_quanta.q_inductor(chips)',
 P_PATH='@t6g_mb_lib.t6g(sch_1):page323_i97@pure_quanta.q_inductor(chips)',
 PATH='I97',
 DRAWING='@T6G_MB_LIB.T6G(SCH_1):PAGE398',
 MATERIAL='IND',
 PHYS_PAGE='323',
 XY='(-8500,4400)',
 ROT='3',
 VER='1',
 PACK_TYPE='SMLF',
 LOCATION='L27',
 CDS_LIB='pure_quanta',
 CDS_PART_NAME='Q_INDUCTOR_SMLF-BLM15PD121SN1D/1300MA,IND,CX5PD121A',
 PART_NUMBER='CX5PD121000',
 VALUE='BLM15PD121SN1D/1300MA',
 PRIM_FILE='./archive_libs/logical/q_inductor/chips/chips.prt';

PART_NAME
 L28 'Q_INDUCTOR_SMLF-BLM15PD121SN1D/1300MA,IND,CX5PD121A':;

SECTION_NUMBER 1
 '@T6G_MB_LIB.T6G(SCH_1):PAGE411_I88@PURE_QUANTA.Q_INDUCTOR(CHIPS)':
 C_PATH='@t6g_mb_lib.t6g(sch_1):page411_i88@pure_quanta.q_inductor(chips)',
 P_PATH='@t6g_mb_lib.t6g(sch_1):page290_i88@pure_quanta.q_inductor(chips)',
 PATH='I88',
 DRAWING='@T6G_MB_LIB.T6G(SCH_1):PAGE411',
 MATERIAL='IND',
 PHYS_PAGE='290',
 XY='(-8400,3825)',
 ROT='3',
 VER='1',
 PACK_TYPE='SMLF',
 LOCATION='L28',
 CDS_LIB='pure_quanta',
 CDS_PART_NAME='Q_INDUCTOR_SMLF-BLM15PD121SN1D/1300MA,IND,CX5PD121A',
 PART_NUMBER='CX5PD121000',
 VALUE='BLM15PD121SN1D/1300MA',
 PRIM_FILE='./archive_libs/logical/q_inductor/chips/chips.prt';

PART_NAME
 L29 'Q_INDUCTOR_SMLF-BLM15PD121SN1D/1300MA,IND,CX5PD121A':;

SECTION_NUMBER 1
 '@T6G_MB_LIB.T6G(SCH_1):PAGE422_I88@PURE_QUANTA.Q_INDUCTOR(CHIPS)':
 C_PATH='@t6g_mb_lib.t6g(sch_1):page422_i88@pure_quanta.q_inductor(chips)',
 P_PATH='@t6g_mb_lib.t6g(sch_1):page301_i88@pure_quanta.q_inductor(chips)',
 PATH='I88',
 DRAWING='@T6G_MB_LIB.T6G(SCH_1):PAGE422',
 MATERIAL='IND',
 PHYS_PAGE='301',
 XY='(-8075,4400)',
 ROT='3',
 VER='1',
 PACK_TYPE='SMLF',
 LOCATION='L29',
 CDS_LIB='pure_quanta',
 CDS_PART_NAME='Q_INDUCTOR_SMLF-BLM15PD121SN1D/1300MA,IND,CX5PD121A',
 PART_NUMBER='CX5PD121000',
 VALUE='BLM15PD121SN1D/1300MA',
 PRIM_FILE='./archive_libs/logical/q_inductor/chips/chips.prt';

PART_NAME
 L30 'Q_INDUCTOR_SMLF-BLM15PD121SN1D/1300MA,IND,CX5PD121A':;

SECTION_NUMBER 1
 '@T6G_MB_LIB.T6G(SCH_1):PAGE433_I88@PURE_QUANTA.Q_INDUCTOR(CHIPS)':
 C_PATH='@t6g_mb_lib.t6g(sch_1):page433_i88@pure_quanta.q_inductor(chips)',
 P_PATH='@t6g_mb_lib.t6g(sch_1):page312_i88@pure_quanta.q_inductor(chips)',
 PATH='I88',
 DRAWING='@T6G_MB_LIB.T6G(SCH_1):PAGE433',
 MATERIAL='IND',
 PHYS_PAGE='312',
 XY='(-8375,4300)',
 ROT='3',
 VER='1',
 PACK_TYPE='SMLF',
 LOCATION='L30',
 CDS_LIB='pure_quanta',
 CDS_PART_NAME='Q_INDUCTOR_SMLF-BLM15PD121SN1D/1300MA,IND,CX5PD121A',
 PART_NUMBER='CX5PD121000',
 VALUE='BLM15PD121SN1D/1300MA',
 PRIM_FILE='./archive_libs/logical/q_inductor/chips/chips.prt';

PART_NAME
 L31 'Q_INDUCTOR_SMLF-BLM15PD121SN1D/1300MA,IND,CX5PD121A':;

SECTION_NUMBER 1
 '@T6G_MB_LIB.T6G(SCH_1):PAGE443_I88@PURE_QUANTA.Q_INDUCTOR(CHIPS)':
 C_PATH='@t6g_mb_lib.t6g(sch_1):page443_i88@pure_quanta.q_inductor(chips)',
 P_PATH='@t6g_mb_lib.t6g(sch_1):page334_i88@pure_quanta.q_inductor(chips)',
 PATH='I88',
 DRAWING='@T6G_MB_LIB.T6G(SCH_1):PAGE443',
 MATERIAL='IND',
 PHYS_PAGE='334',
 XY='(-8250,3925)',
 ROT='3',
 VER='1',
 PACK_TYPE='SMLF',
 LOCATION='L31',
 CDS_LIB='pure_quanta',
 CDS_PART_NAME='Q_INDUCTOR_SMLF-BLM15PD121SN1D/1300MA,IND,CX5PD121A',
 PART_NUMBER='CX5PD121000',
 VALUE='BLM15PD121SN1D/1300MA',
 PRIM_FILE='./archive_libs/logical/q_inductor/chips/chips.prt';

PART_NAME
 L32 'Q_INDUCTOR_SMLF-BLM15PD121SN1D/1300MA,IND,CX5PD121A':;

SECTION_NUMBER 1
 '@T6G_MB_LIB.T6G(SCH_1):PAGE454_I88@PURE_QUANTA.Q_INDUCTOR(CHIPS)':
 C_PATH='@t6g_mb_lib.t6g(sch_1):page454_i88@pure_quanta.q_inductor(chips)',
 P_PATH='@t6g_mb_lib.t6g(sch_1):page345_i88@pure_quanta.q_inductor(chips)',
 PATH='I88',
 DRAWING='@T6G_MB_LIB.T6G(SCH_1):PAGE454',
 MATERIAL='IND',
 PHYS_PAGE='345',
 XY='(-8175,4250)',
 ROT='3',
 VER='1',
 PACK_TYPE='SMLF',
 LOCATION='L32',
 CDS_LIB='pure_quanta',
 CDS_PART_NAME='Q_INDUCTOR_SMLF-BLM15PD121SN1D/1300MA,IND,CX5PD121A',
 PART_NUMBER='CX5PD121000',
 VALUE='BLM15PD121SN1D/1300MA',
 PRIM_FILE='./archive_libs/logical/q_inductor/chips/chips.prt';

PART_NAME
 L33 'Q_INDUCTOR_SMLF-BLM15PD121SN1D/1300MA,IND,CX5PD121A':;

SECTION_NUMBER 1
 '@T6G_MB_LIB.T6G(SCH_1):PAGE465_I88@PURE_QUANTA.Q_INDUCTOR(CHIPS)':
 C_PATH='@t6g_mb_lib.t6g(sch_1):page465_i88@pure_quanta.q_inductor(chips)',
 P_PATH='@t6g_mb_lib.t6g(sch_1):page356_i88@pure_quanta.q_inductor(chips)',
 PATH='I88',
 DRAWING='@T6G_MB_LIB.T6G(SCH_1):PAGE465',
 MATERIAL='IND',
 PHYS_PAGE='356',
 XY='(-8225,4075)',
 ROT='3',
 VER='1',
 PACK_TYPE='SMLF',
 LOCATION='L33',
 CDS_LIB='pure_quanta',
 CDS_PART_NAME='Q_INDUCTOR_SMLF-BLM15PD121SN1D/1300MA,IND,CX5PD121A',
 PART_NUMBER='CX5PD121000',
 VALUE='BLM15PD121SN1D/1300MA',
 PRIM_FILE='./archive_libs/logical/q_inductor/chips/chips.prt';

PART_NAME
 L6000 'Q_INDUCTOR_SMLF-BLM21PG221SN1D,IND,CX1PG221001':
 ROOM='USB3_HUB1_CYP';

SECTION_NUMBER 1
 '@T6G_MB_LIB.T6G(SCH_1):PAGE154_I3@PURE_QUANTA.Q_INDUCTOR(CHIPS)':
 C_PATH='@t6g_mb_lib.t6g(sch_1):page154_i3@pure_quanta.q_inductor(chips)',
 P_PATH='@t6g_mb_lib.t6g(sch_1):page177_i3@pure_quanta.q_inductor(chips)',
 PATH='I3',
 DRAWING='@T6G_MB_LIB.T6G(SCH_1):PAGE154',
 MATERIAL='IND',
 PHYS_PAGE='177',
 XY='(-8100,3425)',
 ROT='0',
 VER='1',
 PACK_TYPE='SMLF',
 LOCATION='L6000',
 CDS_LIB='pure_quanta',
 CDS_PART_NAME='Q_INDUCTOR_SMLF-BLM21PG221SN1D,IND,CX1PG221001',
 ROOM='USB3_HUB1_CYP',
 PART_NUMBER='CX1PG221001',
 VALUE='BLM21PG221SN1D',
 PRIM_FILE='./archive_libs/logical/q_inductor/chips/chips.prt';

PART_NAME
 L6001 'Q_INDUCTOR_SMLF-BLM21PG221SN1D,IND,CX1PG221001':
 ROOM='USB3_HUB1_CYP';

SECTION_NUMBER 1
 '@T6G_MB_LIB.T6G(SCH_1):PAGE154_I26@PURE_QUANTA.Q_INDUCTOR(CHIPS)':
 C_PATH='@t6g_mb_lib.t6g(sch_1):page154_i26@pure_quanta.q_inductor(chips)',
 P_PATH='@t6g_mb_lib.t6g(sch_1):page177_i26@pure_quanta.q_inductor(chips)',
 PATH='I26',
 DRAWING='@T6G_MB_LIB.T6G(SCH_1):PAGE154',
 MATERIAL='IND',
 PHYS_PAGE='177',
 XY='(-8400,5475)',
 ROT='0',
 VER='1',
 PACK_TYPE='SMLF',
 LOCATION='L6001',
 CDS_LIB='pure_quanta',
 CDS_PART_NAME='Q_INDUCTOR_SMLF-BLM21PG221SN1D,IND,CX1PG221001',
 ROOM='USB3_HUB1_CYP',
 PART_NUMBER='CX1PG221001',
 VALUE='BLM21PG221SN1D',
 PRIM_FILE='./archive_libs/logical/q_inductor/chips/chips.prt';

PART_NAME
 L6003 'Q_INDUCTOR_SMLF-BLM21PG221SN1D,IND,CX1PG221001':
 ROOM='USB3_HUB2';

SECTION_NUMBER 1
 '@T6G_MB_LIB.T6G(SCH_1):PAGE157_I17@PURE_QUANTA.Q_INDUCTOR(CHIPS)':
 C_PATH='@t6g_mb_lib.t6g(sch_1):page157_i17@pure_quanta.q_inductor(chips)',
 P_PATH='@t6g_mb_lib.t6g(sch_1):page179_i17@pure_quanta.q_inductor(chips)',
 PATH='I17',
 DRAWING='@T6G_MB_LIB.T6G(SCH_1):PAGE157',
 MATERIAL='IND',
 PHYS_PAGE='179',
 XY='(-6200,2000)',
 ROT='0',
 VER='1',
 PACK_TYPE='SMLF',
 LOCATION='L6003',
 CDS_LIB='pure_quanta',
 CDS_PART_NAME='Q_INDUCTOR_SMLF-BLM21PG221SN1D,IND,CX1PG221001',
 ROOM='USB3_HUB2',
 PART_NUMBER='CX1PG221001',
 VALUE='BLM21PG221SN1D',
 PRIM_FILE='./archive_libs/logical/q_inductor/chips/chips.prt';

PART_NAME
 L6004 'Q_INDUCTOR_SMLF-BLM21PG221SN1D,IND,CX1PG221001':
 ROOM='USB3_HUB2';

SECTION_NUMBER 1
 '@T6G_MB_LIB.T6G(SCH_1):PAGE157_I20@PURE_QUANTA.Q_INDUCTOR(CHIPS)':
 C_PATH='@t6g_mb_lib.t6g(sch_1):page157_i20@pure_quanta.q_inductor(chips)',
 P_PATH='@t6g_mb_lib.t6g(sch_1):page179_i20@pure_quanta.q_inductor(chips)',
 PATH='I20',
 DRAWING='@T6G_MB_LIB.T6G(SCH_1):PAGE157',
 MATERIAL='IND',
 PHYS_PAGE='179',
 XY='(-7900,1075)',
 ROT='0',
 VER='1',
 PACK_TYPE='SMLF',
 LOCATION='L6004',
 CDS_LIB='pure_quanta',
 CDS_PART_NAME='Q_INDUCTOR_SMLF-BLM21PG221SN1D,IND,CX1PG221001',
 ROOM='USB3_HUB2',
 PART_NUMBER='CX1PG221001',
 VALUE='BLM21PG221SN1D',
 PRIM_FILE='./archive_libs/logical/q_inductor/chips/chips.prt';

PART_NAME
 OSC1 'Q_OSC4P_SMLF-50MHZ,OSC,BF650000032':;

SECTION_NUMBER 1
 '@T6G_MB_LIB.T6G(SCH_1):PAGE337_I4@PURE_QUANTA.Q_OSC4P(CHIPS)':
 C_PATH='@t6g_mb_lib.t6g(sch_1):page337_i4@pure_quanta.q_osc4p(chips)',
 P_PATH='@t6g_mb_lib.t6g(sch_1):page133_i4@pure_quanta.q_osc4p(chips)',
 PATH='I4',
 DRAWING='@T6G_MB_LIB.T6G(SCH_1):PAGE337',
 MATERIAL='OSC',
 PHYS_PAGE='133',
 XY='(-9275,2450)',
 ROT='0',
 VER='1',
 PACK_TYPE='SMLF',
 LOCATION='OSC1',
 CDS_LIB='pure_quanta',
 CDS_PART_NAME='Q_OSC4P_SMLF-50MHZ,OSC,BF650000032',
 PART_NUMBER='BF650000032',
 VALUE='50MHZ',
 PRIM_FILE='./archive_libs/logical/q_osc4p/chips/chips.prt';

PART_NAME
 PC3 'Q_CAPP_THLF-270UF,16V,20%,OSCON,CC72703MD38':;

SECTION_NUMBER 1
 '@T6G_MB_LIB.T6G(SCH_1):PAGE245_I29@PURE_QUANTA.Q_CAPP(CHIPS)':
 C_PATH='@t6g_mb_lib.t6g(sch_1):page245_i29@pure_quanta.q_capp(chips)',
 P_PATH='@t6g_mb_lib.t6g(sch_1):page190_i29@pure_quanta.q_capp(chips)',
 PATH='I29',
 DRAWING='@T6G_MB_LIB.T6G(SCH_1):PAGE245',
 TOLERANCE='20%',
 MATERIAL='OSCON',
 PHYS_PAGE='190',
 XY='(-3975,1100)',
 ROT='0',
 VER='1',
 PACK_TYPE='THLF',
 LOCATION='PC3',
 CDS_LIB='pure_quanta',
 CDS_PART_NAME='Q_CAPP_THLF-270UF,16V,20%,OSCON,CC72703MD38',
 VOLTAGE='16V',
 PART_NUMBER='CC72703MD38',
 VALUE='270UF',
 PRIM_FILE='./archive_libs/logical/q_capp/chips/chips.prt';

PART_NAME
 PC4 'Q_CAP_0402-0.1UF,25V,10%,X7R,CH4104K1B00':;

SECTION_NUMBER 1
 '@T6G_MB_LIB.T6G(SCH_1):PAGE182_I79@PURE_QUANTA.Q_CAP(CHIPS)':
 C_PATH='@t6g_mb_lib.t6g(sch_1):page182_i79@pure_quanta.q_cap(chips)',
 P_PATH='@t6g_mb_lib.t6g(sch_1):page207_i79@pure_quanta.q_cap(chips)',
 PATH='I79',
 DRAWING='@T6G_MB_LIB.T6G(SCH_1):PAGE182',
 TOLERANCE='10%',
 MATERIAL='X7R',
 PHYS_PAGE='207',
 XY='(-3425,6150)',
 ROT='0',
 VER='1',
 PACK_TYPE='0402',
 LOCATION='PC4',
 CDS_LIB='pure_quanta',
 CDS_PART_NAME='Q_CAP_0402-0.1UF,25V,10%,X7R,CH4104K1B00',
 VOLTAGE='25V',
 PART_NUMBER='CH4104K1B00',
 VALUE='0.1UF',
 PRIM_FILE='./archive_libs/logical/q_cap/chips/chips.prt';

PART_NAME
 PC5 'Q_CAP_0402-0.1UF,25V,10%,X7R,CH4104K1B00':;

SECTION_NUMBER 1
 '@T6G_MB_LIB.T6G(SCH_1):PAGE182_I20@PURE_QUANTA.Q_CAP(CHIPS)':
 C_PATH='@t6g_mb_lib.t6g(sch_1):page182_i20@pure_quanta.q_cap(chips)',
 P_PATH='@t6g_mb_lib.t6g(sch_1):page207_i20@pure_quanta.q_cap(chips)',
 PATH='I20',
 DRAWING='@T6G_MB_LIB.T6G(SCH_1):PAGE182',
 SEC_TYPE='0402',
 TOLERANCE='10%',
 MATERIAL='X7R',
 PHYS_PAGE='207',
 XY='(-5400,500)',
 ROT='0',
 VER='1',
 PACK_TYPE='0402',
 LOCATION='PC5',
 SEC='1',
 CDS_LIB='pure_quanta',
 CDS_PART_NAME='Q_CAP_0402-0.1UF,25V,10%,X7R,CH4104K1B00',
 VOLTAGE='25V',
 PART_NUMBER='CH4104K1B00',
 VALUE='0.1UF',
 PRIM_FILE='./archive_libs/logical/q_cap/chips/chips.prt';

PART_NAME
 PC6 'Q_CAP_0402-0.1UF,25V,10%,X7R,CH4104K1B00':;

SECTION_NUMBER 1
 '@T6G_MB_LIB.T6G(SCH_1):PAGE185_I51@PURE_QUANTA.Q_CAP(CHIPS)':
 C_PATH='@t6g_mb_lib.t6g(sch_1):page185_i51@pure_quanta.q_cap(chips)',
 P_PATH='@t6g_mb_lib.t6g(sch_1):page210_i51@pure_quanta.q_cap(chips)',
 PATH='I51',
 DRAWING='@T6G_MB_LIB.T6G(SCH_1):PAGE185',
 SEC_TYPE='0402',
 TOLERANCE='10%',
 MATERIAL='X7R',
 PHYS_PAGE='210',
 XY='(-2075,2250)',
 ROT='0',
 VER='1',
 PACK_TYPE='0402',
 LOCATION='PC6',
 SEC='1',
 CDS_LIB='pure_quanta',
 CDS_PART_NAME='Q_CAP_0402-0.1UF,25V,10%,X7R,CH4104K1B00',
 VOLTAGE='25V',
 PART_NUMBER='CH4104K1B00',
 VALUE='0.1UF',
 PRIM_FILE='./archive_libs/logical/q_cap/chips/chips.prt';

PART_NAME
 PC7 'Q_CAP_0402-0.1UF,25V,10%,X7R,CH4104K1B00':;

SECTION_NUMBER 1
 '@T6G_MB_LIB.T6G(SCH_1):PAGE168_I50@PURE_QUANTA.Q_CAP(CHIPS)':
 C_PATH='@t6g_mb_lib.t6g(sch_1):page168_i50@pure_quanta.q_cap(chips)',
 P_PATH='@t6g_mb_lib.t6g(sch_1):page193_i50@pure_quanta.q_cap(chips)',
 PATH='I50',
 DRAWING='@T6G_MB_LIB.T6G(SCH_1):PAGE168',
 SEC_TYPE='0402',
 TOLERANCE='10%',
 MATERIAL='X7R',
 PHYS_PAGE='193',
 XY='(-4875,875)',
 ROT='0',
 VER='1',
 PACK_TYPE='0402',
 LOCATION='PC7',
 SEC='1',
 CDS_LIB='pure_quanta',
 CDS_PART_NAME='Q_CAP_0402-0.1UF,25V,10%,X7R,CH4104K1B00',
 VOLTAGE='25V',
 PART_NUMBER='CH4104K1B00',
 VALUE='0.1UF',
 PRIM_FILE='./archive_libs/logical/q_cap/chips/chips.prt';

PART_NAME
 PC8 'Q_CAP_0402-0.1UF,25V,10%,X7R,CH4104K1B00':;

SECTION_NUMBER 1
 '@T6G_MB_LIB.T6G(SCH_1):PAGE199_I20@PURE_QUANTA.Q_CAP(CHIPS)':
 C_PATH='@t6g_mb_lib.t6g(sch_1):page199_i20@pure_quanta.q_cap(chips)',
 P_PATH='@t6g_mb_lib.t6g(sch_1):page224_i20@pure_quanta.q_cap(chips)',
 PATH='I20',
 DRAWING='@T6G_MB_LIB.T6G(SCH_1):PAGE199',
 SEC_TYPE='0402',
 TOLERANCE='10%',
 MATERIAL='X7R',
 PHYS_PAGE='224',
 XY='(-5400,500)',
 ROT='0',
 VER='1',
 PACK_TYPE='0402',
 LOCATION='PC8',
 SEC='1',
 CDS_LIB='pure_quanta',
 CDS_PART_NAME='Q_CAP_0402-0.1UF,25V,10%,X7R,CH4104K1B00',
 VOLTAGE='25V',
 PART_NUMBER='CH4104K1B00',
 VALUE='0.1UF',
 PRIM_FILE='./archive_libs/logical/q_cap/chips/chips.prt';

PART_NAME
 PC9 'Q_CAP_0402-0.1UF,25V,10%,X7R,CH4104K1B00':;

SECTION_NUMBER 1
 '@T6G_MB_LIB.T6G(SCH_1):PAGE182_I77@PURE_QUANTA.Q_CAP(CHIPS)':
 C_PATH='@t6g_mb_lib.t6g(sch_1):page182_i77@pure_quanta.q_cap(chips)',
 P_PATH='@t6g_mb_lib.t6g(sch_1):page207_i77@pure_quanta.q_cap(chips)',
 PATH='I77',
 DRAWING='@T6G_MB_LIB.T6G(SCH_1):PAGE182',
 TOLERANCE='10%',
 MATERIAL='X7R',
 PHYS_PAGE='207',
 XY='(-3425,5650)',
 ROT='0',
 VER='1',
 PACK_TYPE='0402',
 LOCATION='PC9',
 CDS_LIB='pure_quanta',
 CDS_PART_NAME='Q_CAP_0402-0.1UF,25V,10%,X7R,CH4104K1B00',
 VOLTAGE='25V',
 PART_NUMBER='CH4104K1B00',
 VALUE='0.1UF',
 PRIM_FILE='./archive_libs/logical/q_cap/chips/chips.prt';

PART_NAME
 PC10 'Q_CAP_0402-0.1UF,25V,10%,X7R,CH4104K1B00':;

SECTION_NUMBER 1
 '@T6G_MB_LIB.T6G(SCH_1):PAGE185_I116@PURE_QUANTA.Q_CAP(CHIPS)':
 C_PATH='@t6g_mb_lib.t6g(sch_1):page185_i116@pure_quanta.q_cap(chips)',
 P_PATH='@t6g_mb_lib.t6g(sch_1):page210_i116@pure_quanta.q_cap(chips)',
 PATH='I116',
 DRAWING='@T6G_MB_LIB.T6G(SCH_1):PAGE185',
 TOLERANCE='10%',
 MATERIAL='X7R',
 PHYS_PAGE='210',
 XY='(-25,7900)',
 ROT='0',
 VER='1',
 PACK_TYPE='0402',
 LOCATION='PC10',
 CDS_LIB='pure_quanta',
 CDS_PART_NAME='Q_CAP_0402-0.1UF,25V,10%,X7R,CH4104K1B00',
 VOLTAGE='25V',
 PART_NUMBER='CH4104K1B00',
 VALUE='0.1UF',
 PRIM_FILE='./archive_libs/logical/q_cap/chips/chips.prt';

PART_NAME
 PC11 'Q_CAP_0402-0.1UF,25V,10%,X7R,CH4104K1B00':;

SECTION_NUMBER 1
 '@T6G_MB_LIB.T6G(SCH_1):PAGE185_I114@PURE_QUANTA.Q_CAP(CHIPS)':
 C_PATH='@t6g_mb_lib.t6g(sch_1):page185_i114@pure_quanta.q_cap(chips)',
 P_PATH='@t6g_mb_lib.t6g(sch_1):page210_i114@pure_quanta.q_cap(chips)',
 PATH='I114',
 DRAWING='@T6G_MB_LIB.T6G(SCH_1):PAGE185',
 TOLERANCE='10%',
 MATERIAL='X7R',
 PHYS_PAGE='210',
 XY='(-25,7425)',
 ROT='0',
 VER='1',
 PACK_TYPE='0402',
 LOCATION='PC11',
 CDS_LIB='pure_quanta',
 CDS_PART_NAME='Q_CAP_0402-0.1UF,25V,10%,X7R,CH4104K1B00',
 VOLTAGE='25V',
 PART_NUMBER='CH4104K1B00',
 VALUE='0.1UF',
 PRIM_FILE='./archive_libs/logical/q_cap/chips/chips.prt';

PART_NAME
 PC12 'Q_CAP_0402-0.1UF,25V,10%,X7R,CH4104K1B00':;

SECTION_NUMBER 1
 '@T6G_MB_LIB.T6G(SCH_1):PAGE168_I120@PURE_QUANTA.Q_CAP(CHIPS)':
 C_PATH='@t6g_mb_lib.t6g(sch_1):page168_i120@pure_quanta.q_cap(chips)',
 P_PATH='@t6g_mb_lib.t6g(sch_1):page193_i120@pure_quanta.q_cap(chips)',
 PATH='I120',
 DRAWING='@T6G_MB_LIB.T6G(SCH_1):PAGE168',
 TOLERANCE='10%',
 MATERIAL='X7R',
 PHYS_PAGE='193',
 XY='(-2775,6525)',
 ROT='0',
 VER='1',
 PACK_TYPE='0402',
 LOCATION='PC12',
 CDS_LIB='pure_quanta',
 CDS_PART_NAME='Q_CAP_0402-0.1UF,25V,10%,X7R,CH4104K1B00',
 VOLTAGE='25V',
 PART_NUMBER='CH4104K1B00',
 VALUE='0.1UF',
 PRIM_FILE='./archive_libs/logical/q_cap/chips/chips.prt';

PART_NAME
 PC13 'Q_CAP_0402-0.1UF,25V,10%,X7R,CH4104K1B00':;

SECTION_NUMBER 1
 '@T6G_MB_LIB.T6G(SCH_1):PAGE168_I118@PURE_QUANTA.Q_CAP(CHIPS)':
 C_PATH='@t6g_mb_lib.t6g(sch_1):page168_i118@pure_quanta.q_cap(chips)',
 P_PATH='@t6g_mb_lib.t6g(sch_1):page193_i118@pure_quanta.q_cap(chips)',
 PATH='I118',
 DRAWING='@T6G_MB_LIB.T6G(SCH_1):PAGE168',
 TOLERANCE='10%',
 MATERIAL='X7R',
 PHYS_PAGE='193',
 XY='(-2775,6050)',
 ROT='0',
 VER='1',
 PACK_TYPE='0402',
 LOCATION='PC13',
 CDS_LIB='pure_quanta',
 CDS_PART_NAME='Q_CAP_0402-0.1UF,25V,10%,X7R,CH4104K1B00',
 VOLTAGE='25V',
 PART_NUMBER='CH4104K1B00',
 VALUE='0.1UF',
 PRIM_FILE='./archive_libs/logical/q_cap/chips/chips.prt';

PART_NAME
 PC14 'Q_CAP_0402-0.1UF,25V,10%,X7R,CH4104K1B00':;

SECTION_NUMBER 1
 '@T6G_MB_LIB.T6G(SCH_1):PAGE175_I96@PURE_QUANTA.Q_CAP(CHIPS)':
 C_PATH='@t6g_mb_lib.t6g(sch_1):page175_i96@pure_quanta.q_cap(chips)',
 P_PATH='@t6g_mb_lib.t6g(sch_1):page200_i96@pure_quanta.q_cap(chips)',
 PATH='I96',
 DRAWING='@T6G_MB_LIB.T6G(SCH_1):PAGE175',
 TOLERANCE='10%',
 MATERIAL='X7R',
 PHYS_PAGE='200',
 XY='(-3075,6150)',
 ROT='0',
 VER='1',
 PACK_TYPE='0402',
 LOCATION='PC14',
 CDS_LIB='pure_quanta',
 CDS_PART_NAME='Q_CAP_0402-0.1UF,25V,10%,X7R,CH4104K1B00',
 VOLTAGE='25V',
 PART_NUMBER='CH4104K1B00',
 VALUE='0.1UF',
 PRIM_FILE='./archive_libs/logical/q_cap/chips/chips.prt';

PART_NAME
 PC15 'Q_CAP_0402-0.1UF,25V,10%,X7R,CH4104K1B00':;

SECTION_NUMBER 1
 '@T6G_MB_LIB.T6G(SCH_1):PAGE175_I94@PURE_QUANTA.Q_CAP(CHIPS)':
 C_PATH='@t6g_mb_lib.t6g(sch_1):page175_i94@pure_quanta.q_cap(chips)',
 P_PATH='@t6g_mb_lib.t6g(sch_1):page200_i94@pure_quanta.q_cap(chips)',
 PATH='I94',
 DRAWING='@T6G_MB_LIB.T6G(SCH_1):PAGE175',
 TOLERANCE='10%',
 MATERIAL='X7R',
 PHYS_PAGE='200',
 XY='(-3075,5675)',
 ROT='0',
 VER='1',
 PACK_TYPE='0402',
 LOCATION='PC15',
 CDS_LIB='pure_quanta',
 CDS_PART_NAME='Q_CAP_0402-0.1UF,25V,10%,X7R,CH4104K1B00',
 VOLTAGE='25V',
 PART_NUMBER='CH4104K1B00',
 VALUE='0.1UF',
 PRIM_FILE='./archive_libs/logical/q_cap/chips/chips.prt';

PART_NAME
 PC19 'Q_CAP_0402-0.22UF,16V,10%,X7R,CH4223K1B00':;

SECTION_NUMBER 1
 '@T6G_MB_LIB.T6G(SCH_1):PAGE201_I25@PURE_QUANTA.Q_CAP(CHIPS)':
 C_PATH='@t6g_mb_lib.t6g(sch_1):page201_i25@pure_quanta.q_cap(chips)',
 P_PATH='@t6g_mb_lib.t6g(sch_1):page226_i25@pure_quanta.q_cap(chips)',
 PATH='I25',
 DRAWING='@T6G_MB_LIB.T6G(SCH_1):PAGE201',
 SEC_TYPE='0402',
 TOLERANCE='10%',
 MATERIAL='X7R',
 PHYS_PAGE='226',
 XY='(-3775,4125)',
 ROT='0',
 VER='1',
 PACK_TYPE='0402',
 LOCATION='PC19',
 SEC='1',
 CDS_LIB='pure_quanta',
 CDS_PART_NAME='Q_CAP_0402-0.22UF,16V,10%,X7R,CH4223K1B00',
 VOLTAGE='16V',
 PART_NUMBER='CH4223K1B00',
 VALUE='0.22UF',
 PRIM_FILE='./archive_libs/logical/q_cap/chips/chips.prt';

PART_NAME
 PC20 'Q_CAP_C0402-1UF,25V,10%,X6S,CH5104KEB02':
 SIGNAL_MODEL='DEFAULT_CAPACITOR_100000PF_2_1';

SECTION_NUMBER 1
 '@T6G_MB_LIB.T6G(SCH_1):PAGE201_I53@PURE_QUANTA.Q_CAP(CHIPS)':
 C_PATH='@t6g_mb_lib.t6g(sch_1):page201_i53@pure_quanta.q_cap(chips)',
 P_PATH='@t6g_mb_lib.t6g(sch_1):page226_i53@pure_quanta.q_cap(chips)',
 PATH='I53',
 DRAWING='@T6G_MB_LIB.T6G(SCH_1):PAGE201',
 SEC_TYPE='C0402',
 TOLERANCE='10%',
 MATERIAL='X6S',
 PHYS_PAGE='226',
 XY='(-6875,3035)',
 ROT='2',
 VER='1',
 PACK_TYPE='C0402',
 LOCATION='PC20',
 SEC='1',
 CDS_LIB='pure_quanta',
 CDS_PART_NAME='Q_CAP_C0402-1UF,25V,10%,X6S,CH5104KEB02',
 SIGNAL_MODEL='DEFAULT_CAPACITOR_100000PF_2_1',
 VOLTAGE='25V',
 PART_NUMBER='CH5104KEB02',
 VALUE='1UF',
 PRIM_FILE='./archive_libs/logical/q_cap/chips/chips.prt';

PART_NAME
 PC21 'Q_CAP_0402-0.1UF,25V,10%,X7R,CH4104K1B00':;

SECTION_NUMBER 1
 '@T6G_MB_LIB.T6G(SCH_1):PAGE201_I47@PURE_QUANTA.Q_CAP(CHIPS)':
 C_PATH='@t6g_mb_lib.t6g(sch_1):page201_i47@pure_quanta.q_cap(chips)',
 P_PATH='@t6g_mb_lib.t6g(sch_1):page226_i47@pure_quanta.q_cap(chips)',
 PATH='I47',
 DRAWING='@T6G_MB_LIB.T6G(SCH_1):PAGE201',
 TOLERANCE='10%',
 MATERIAL='X7R',
 PHYS_PAGE='226',
 XY='(-600,3725)',
 ROT='0',
 VER='1',
 PACK_TYPE='0402',
 LOCATION='PC21',
 CDS_LIB='pure_quanta',
 CDS_PART_NAME='Q_CAP_0402-0.1UF,25V,10%,X7R,CH4104K1B00',
 VOLTAGE='25V',
 PART_NUMBER='CH4104K1B00',
 VALUE='0.1UF',
 PRIM_FILE='./archive_libs/logical/q_cap/chips/chips.prt';

PART_NAME
 PC22 'Q_CAP_C0402-1UF,25V,10%,X6S,CH5104KEB02':;

SECTION_NUMBER 1
 '@T6G_MB_LIB.T6G(SCH_1):PAGE201_I24@PURE_QUANTA.Q_CAP(CHIPS)':
 C_PATH='@t6g_mb_lib.t6g(sch_1):page201_i24@pure_quanta.q_cap(chips)',
 P_PATH='@t6g_mb_lib.t6g(sch_1):page226_i24@pure_quanta.q_cap(chips)',
 PATH='I24',
 DRAWING='@T6G_MB_LIB.T6G(SCH_1):PAGE201',
 TOLERANCE='10%',
 MATERIAL='X6S',
 PHYS_PAGE='226',
 XY='(-6325,4550)',
 ROT='0',
 VER='1',
 PACK_TYPE='C0402',
 LOCATION='PC22',
 CDS_LIB='pure_quanta',
 CDS_PART_NAME='Q_CAP_C0402-1UF,25V,10%,X6S,CH5104KEB02',
 VOLTAGE='25V',
 PART_NUMBER='CH5104KEB02',
 VALUE='1UF',
 PRIM_FILE='./archive_libs/logical/q_cap/chips/chips.prt';

PART_NAME
 PC27 'Q_CAP_C0805-22UF,16V,20%,X6S,CH6223MEA01':;

SECTION_NUMBER 1
 '@T6G_MB_LIB.T6G(SCH_1):PAGE200_I58@PURE_QUANTA.Q_CAP(CHIPS)':
 C_PATH='@t6g_mb_lib.t6g(sch_1):page200_i58@pure_quanta.q_cap(chips)',
 P_PATH='@t6g_mb_lib.t6g(sch_1):page225_i58@pure_quanta.q_cap(chips)',
 PATH='I58',
 DRAWING='@T6G_MB_LIB.T6G(SCH_1):PAGE200',
 TOLERANCE='20%',
 MATERIAL='X6S',
 PHYS_PAGE='225',
 XY='(-3725,2600)',
 ROT='0',
 VER='1',
 PACK_TYPE='C0805',
 LOCATION='PC27',
 CDS_LIB='pure_quanta',
 CDS_PART_NAME='Q_CAP_C0805-22UF,16V,20%,X6S,CH6223MEA01',
 VOLTAGE='16V',
 PART_NUMBER='CH6223MEA01',
 VALUE='22UF',
 PRIM_FILE='./archive_libs/logical/q_cap/chips/chips.prt';

PART_NAME
 PC29 'Q_CAP_0402-0.1UF,25V,10%,X7R,CH4104K1B00':;

SECTION_NUMBER 1
 '@T6G_MB_LIB.T6G(SCH_1):PAGE192_I95@PURE_QUANTA.Q_CAP(CHIPS)':
 C_PATH='@t6g_mb_lib.t6g(sch_1):page192_i95@pure_quanta.q_cap(chips)',
 P_PATH='@t6g_mb_lib.t6g(sch_1):page217_i95@pure_quanta.q_cap(chips)',
 PATH='I95',
 DRAWING='@T6G_MB_LIB.T6G(SCH_1):PAGE192',
 TOLERANCE='10%',
 MATERIAL='X7R',
 PHYS_PAGE='217',
 XY='(475,7075)',
 ROT='0',
 VER='1',
 PACK_TYPE='0402',
 LOCATION='PC29',
 CDS_LIB='pure_quanta',
 CDS_PART_NAME='Q_CAP_0402-0.1UF,25V,10%,X7R,CH4104K1B00',
 VOLTAGE='25V',
 PART_NUMBER='CH4104K1B00',
 VALUE='0.1UF',
 PRIM_FILE='./archive_libs/logical/q_cap/chips/chips.prt';

PART_NAME
 PC60 'Q_CAP_C0805-22UF,16V,20%,X6S,CH6223MEA01':;

SECTION_NUMBER 1
 '@T6G_MB_LIB.T6G(SCH_1):PAGE201_I54@PURE_QUANTA.Q_CAP(CHIPS)':
 C_PATH='@t6g_mb_lib.t6g(sch_1):page201_i54@pure_quanta.q_cap(chips)',
 P_PATH='@t6g_mb_lib.t6g(sch_1):page226_i54@pure_quanta.q_cap(chips)',
 PATH='I54',
 DRAWING='@T6G_MB_LIB.T6G(SCH_1):PAGE201',
 TOLERANCE='20%',
 MATERIAL='X6S',
 PHYS_PAGE='226',
 XY='(-7525,4575)',
 ROT='0',
 VER='1',
 PACK_TYPE='C0805',
 LOCATION='PC60',
 CDS_LIB='pure_quanta',
 CDS_PART_NAME='Q_CAP_C0805-22UF,16V,20%,X6S,CH6223MEA01',
 VOLTAGE='16V',
 PART_NUMBER='CH6223MEA01',
 VALUE='22UF',
 PRIM_FILE='./archive_libs/logical/q_cap/chips/chips.prt';

PART_NAME
 PC61 'Q_CAP_C0805-22UF,16V,20%,X6S,CH6223MEA01':;

SECTION_NUMBER 1
 '@T6G_MB_LIB.T6G(SCH_1):PAGE201_I21@PURE_QUANTA.Q_CAP(CHIPS)':
 C_PATH='@t6g_mb_lib.t6g(sch_1):page201_i21@pure_quanta.q_cap(chips)',
 P_PATH='@t6g_mb_lib.t6g(sch_1):page226_i21@pure_quanta.q_cap(chips)',
 PATH='I21',
 DRAWING='@T6G_MB_LIB.T6G(SCH_1):PAGE201',
 TOLERANCE='20%',
 MATERIAL='X6S',
 PHYS_PAGE='226',
 XY='(-7150,4550)',
 ROT='0',
 VER='1',
 PACK_TYPE='C0805',
 LOCATION='PC61',
 CDS_LIB='pure_quanta',
 CDS_PART_NAME='Q_CAP_C0805-22UF,16V,20%,X6S,CH6223MEA01',
 VOLTAGE='16V',
 PART_NUMBER='CH6223MEA01',
 VALUE='22UF',
 PRIM_FILE='./archive_libs/logical/q_cap/chips/chips.prt';

PART_NAME
 PC62 'Q_CAP_0402-0.1UF,25V,10%,X7R,CH4104K1B00':;

SECTION_NUMBER 1
 '@T6G_MB_LIB.T6G(SCH_1):PAGE201_I19@PURE_QUANTA.Q_CAP(CHIPS)':
 C_PATH='@t6g_mb_lib.t6g(sch_1):page201_i19@pure_quanta.q_cap(chips)',
 P_PATH='@t6g_mb_lib.t6g(sch_1):page226_i19@pure_quanta.q_cap(chips)',
 PATH='I19',
 DRAWING='@T6G_MB_LIB.T6G(SCH_1):PAGE201',
 TOLERANCE='10%',
 MATERIAL='X7R',
 PHYS_PAGE='226',
 XY='(-4275,3300)',
 ROT='1',
 VER='1',
 PACK_TYPE='0402',
 LOCATION='PC62',
 CDS_LIB='pure_quanta',
 CDS_PART_NAME='Q_CAP_0402-0.1UF,25V,10%,X7R,CH4104K1B00',
 VOLTAGE='25V',
 PART_NUMBER='CH4104K1B00',
 VALUE='0.1UF',
 PRIM_FILE='./archive_libs/logical/q_cap/chips/chips.prt';

PART_NAME
 PC64 'Q_CAP_0402-220PF,50V,10%,X7R,TMP_QCH12206KB14':;

SECTION_NUMBER 1
 '@T6G_MB_LIB.T6G(SCH_1):PAGE201_I31@PURE_QUANTA.Q_CAP(CHIPS)':
 C_PATH='@t6g_mb_lib.t6g(sch_1):page201_i31@pure_quanta.q_cap(chips)',
 P_PATH='@t6g_mb_lib.t6g(sch_1):page226_i31@pure_quanta.q_cap(chips)',
 PATH='I31',
 DRAWING='@T6G_MB_LIB.T6G(SCH_1):PAGE201',
 TOLERANCE='10%',
 MATERIAL='X7R',
 PHYS_PAGE='226',
 XY='(-3275,3275)',
 ROT='0',
 VER='2',
 PACK_TYPE='0402',
 LOCATION='PC64',
 CDS_LIB='pure_quanta',
 CDS_PART_NAME='Q_CAP_0402-220PF,50V,10%,X7R,TMP_QCH12206KB14',
 VOLTAGE='50V',
 PART_NUMBER='TMP_QCH12206KB14',
 VALUE='220PF',
 PRIM_FILE='./archive_libs/logical/q_cap/chips/chips.prt';

PART_NAME
 PC65 'Q_CAP_C0805-22UF,4V,20%,X6S,CH622KMEA03':;

SECTION_NUMBER 1
 '@T6G_MB_LIB.T6G(SCH_1):PAGE201_I37@PURE_QUANTA.Q_CAP(CHIPS)':
 C_PATH='@t6g_mb_lib.t6g(sch_1):page201_i37@pure_quanta.q_cap(chips)',
 P_PATH='@t6g_mb_lib.t6g(sch_1):page226_i37@pure_quanta.q_cap(chips)',
 PATH='I37',
 DRAWING='@T6G_MB_LIB.T6G(SCH_1):PAGE201',
 TOLERANCE='20%',
 MATERIAL='X6S',
 PHYS_PAGE='226',
 XY='(-2450,3750)',
 ROT='0',
 VER='1',
 PACK_TYPE='C0805',
 LOCATION='PC65',
 CDS_LIB='pure_quanta',
 CDS_PART_NAME='Q_CAP_C0805-22UF,4V,20%,X6S,CH622KMEA03',
 VOLTAGE='4V',
 PART_NUMBER='CH622KMEA03',
 VALUE='22UF',
 PRIM_FILE='./archive_libs/logical/q_cap/chips/chips.prt';

PART_NAME
 PC67 'Q_CAP_0402-0.1UF,25V,10%,X7R,CH4104K1B00':;

SECTION_NUMBER 1
 '@T6G_MB_LIB.T6G(SCH_1):PAGE175_I50@PURE_QUANTA.Q_CAP(CHIPS)':
 C_PATH='@t6g_mb_lib.t6g(sch_1):page175_i50@pure_quanta.q_cap(chips)',
 P_PATH='@t6g_mb_lib.t6g(sch_1):page200_i50@pure_quanta.q_cap(chips)',
 PATH='I50',
 DRAWING='@T6G_MB_LIB.T6G(SCH_1):PAGE175',
 TOLERANCE='10%',
 MATERIAL='X7R',
 PHYS_PAGE='200',
 XY='(-6200,800)',
 ROT='0',
 VER='1',
 PACK_TYPE='0402',
 LOCATION='PC67',
 CDS_LIB='pure_quanta',
 CDS_PART_NAME='Q_CAP_0402-0.1UF,25V,10%,X7R,CH4104K1B00',
 VOLTAGE='25V',
 PART_NUMBER='CH4104K1B00',
 VALUE='0.1UF',
 PRIM_FILE='./archive_libs/logical/q_cap/chips/chips.prt';

PART_NAME
 PC68 'Q_CAP_0402-3300PF,50V,10%,X7R,TMP_QCH2336K1B12':;

SECTION_NUMBER 1
 '@T6G_MB_LIB.T6G(SCH_1):PAGE175_I80@PURE_QUANTA.Q_CAP(CHIPS)':
 C_PATH='@t6g_mb_lib.t6g(sch_1):page175_i80@pure_quanta.q_cap(chips)',
 P_PATH='@t6g_mb_lib.t6g(sch_1):page200_i80@pure_quanta.q_cap(chips)',
 PATH='I80',
 DRAWING='@T6G_MB_LIB.T6G(SCH_1):PAGE175',
 TOLERANCE='10%',
 MATERIAL='X7R',
 PHYS_PAGE='200',
 XY='(-5675,4125)',
 ROT='0',
 VER='1',
 PACK_TYPE='0402',
 LOCATION='PC68',
 CDS_LIB='pure_quanta',
 CDS_PART_NAME='Q_CAP_0402-3300PF,50V,10%,X7R,TMP_QCH2336K1B12',
 VOLTAGE='50V',
 PART_NUMBER='TMP_QCH2336K1B12',
 VALUE='3300PF',
 PRIM_FILE='./archive_libs/logical/q_cap/chips/chips.prt';

PART_NAME
 PC71 'Q_CAP_0402-3300PF,50V,10%,X7R,TMP_QCH2336K1B12':;

SECTION_NUMBER 1
 '@T6G_MB_LIB.T6G(SCH_1):PAGE175_I69@PURE_QUANTA.Q_CAP(CHIPS)':
 C_PATH='@t6g_mb_lib.t6g(sch_1):page175_i69@pure_quanta.q_cap(chips)',
 P_PATH='@t6g_mb_lib.t6g(sch_1):page200_i69@pure_quanta.q_cap(chips)',
 PATH='I69',
 DRAWING='@T6G_MB_LIB.T6G(SCH_1):PAGE175',
 TOLERANCE='10%',
 MATERIAL='X7R',
 PHYS_PAGE='200',
 XY='(-5625,3025)',
 ROT='0',
 VER='1',
 PACK_TYPE='0402',
 LOCATION='PC71',
 CDS_LIB='pure_quanta',
 CDS_PART_NAME='Q_CAP_0402-3300PF,50V,10%,X7R,TMP_QCH2336K1B12',
 VOLTAGE='50V',
 PART_NUMBER='TMP_QCH2336K1B12',
 VALUE='3300PF',
 PRIM_FILE='./archive_libs/logical/q_cap/chips/chips.prt';

PART_NAME
 PC73 'Q_CAP_0402-1UF,6.3V,10%,X7R,CH5101K1B01':;

SECTION_NUMBER 1
 '@T6G_MB_LIB.T6G(SCH_1):PAGE175_I63@PURE_QUANTA.Q_CAP(CHIPS)':
 C_PATH='@t6g_mb_lib.t6g(sch_1):page175_i63@pure_quanta.q_cap(chips)',
 P_PATH='@t6g_mb_lib.t6g(sch_1):page200_i63@pure_quanta.q_cap(chips)',
 PATH='I63',
 DRAWING='@T6G_MB_LIB.T6G(SCH_1):PAGE175',
 TOLERANCE='10%',
 MATERIAL='X7R',
 PHYS_PAGE='200',
 XY='(-5425,1925)',
 ROT='0',
 VER='2',
 PACK_TYPE='0402',
 LOCATION='PC73',
 CDS_LIB='pure_quanta',
 CDS_PART_NAME='Q_CAP_0402-1UF,6.3V,10%,X7R,CH5101K1B01',
 VOLTAGE='6.3V',
 PART_NUMBER='CH5101K1B01',
 VALUE='1UF',
 PRIM_FILE='./archive_libs/logical/q_cap/chips/chips.prt';

PART_NAME
 PC74 'Q_CAP_0402-0.1UF,25V,10%,X7R,CH4104K1B00':;

SECTION_NUMBER 1
 '@T6G_MB_LIB.T6G(SCH_1):PAGE175_I60@PURE_QUANTA.Q_CAP(CHIPS)':
 C_PATH='@t6g_mb_lib.t6g(sch_1):page175_i60@pure_quanta.q_cap(chips)',
 P_PATH='@t6g_mb_lib.t6g(sch_1):page200_i60@pure_quanta.q_cap(chips)',
 PATH='I60',
 DRAWING='@T6G_MB_LIB.T6G(SCH_1):PAGE175',
 TOLERANCE='10%',
 MATERIAL='X7R',
 PHYS_PAGE='200',
 XY='(-5075,575)',
 ROT='0',
 VER='1',
 PACK_TYPE='0402',
 LOCATION='PC74',
 CDS_LIB='pure_quanta',
 CDS_PART_NAME='Q_CAP_0402-0.1UF,25V,10%,X7R,CH4104K1B00',
 VOLTAGE='25V',
 PART_NUMBER='CH4104K1B00',
 VALUE='0.1UF',
 PRIM_FILE='./archive_libs/logical/q_cap/chips/chips.prt';

PART_NAME
 PC75 'Q_CAP_C0402-1UF,16V,10%,X6S,CH5103KEB01':;

SECTION_NUMBER 1
 '@T6G_MB_LIB.T6G(SCH_1):PAGE175_I100@PURE_QUANTA.Q_CAP(CHIPS)':
 C_PATH='@t6g_mb_lib.t6g(sch_1):page175_i100@pure_quanta.q_cap(chips)',
 P_PATH='@t6g_mb_lib.t6g(sch_1):page200_i100@pure_quanta.q_cap(chips)',
 PATH='I100',
 DRAWING='@T6G_MB_LIB.T6G(SCH_1):PAGE175',
 TOLERANCE='10%',
 MATERIAL='X6S',
 PHYS_PAGE='200',
 XY='(-2750,6125)',
 ROT='0',
 VER='1',
 PACK_TYPE='C0402',
 LOCATION='PC75',
 CDS_LIB='pure_quanta',
 CDS_PART_NAME='Q_CAP_C0402-1UF,16V,10%,X6S,CH5103KEB01',
 VOLTAGE='16V',
 PART_NUMBER='CH5103KEB01',
 VALUE='1UF',
 PRIM_FILE='./archive_libs/logical/q_cap/chips/chips.prt';

PART_NAME
 PC76 'Q_CAP_C0402-10UF,6.3V,20%,X6S,CH6101MEB03':;

SECTION_NUMBER 1
 '@T6G_MB_LIB.T6G(SCH_1):PAGE175_I98@PURE_QUANTA.Q_CAP(CHIPS)':
 C_PATH='@t6g_mb_lib.t6g(sch_1):page175_i98@pure_quanta.q_cap(chips)',
 P_PATH='@t6g_mb_lib.t6g(sch_1):page200_i98@pure_quanta.q_cap(chips)',
 PATH='I98',
 DRAWING='@T6G_MB_LIB.T6G(SCH_1):PAGE175',
 TOLERANCE='20%',
 MATERIAL='X6S',
 PHYS_PAGE='200',
 XY='(-2750,5650)',
 ROT='0',
 VER='1',
 PACK_TYPE='C0402',
 LOCATION='PC76',
 CDS_LIB='pure_quanta',
 CDS_PART_NAME='Q_CAP_C0402-10UF,6.3V,20%,X6S,CH6101MEB03',
 VOLTAGE='6.3V',
 PART_NUMBER='CH6101MEB03',
 VALUE='10UF',
 PRIM_FILE='./archive_libs/logical/q_cap/chips/chips.prt';

PART_NAME
 PC77 'Q_CAP_0402-470PF,50V,10%,X7R,TMP_QCH14706KB18':;

SECTION_NUMBER 1
 '@T6G_MB_LIB.T6G(SCH_1):PAGE175_I75@PURE_QUANTA.Q_CAP(CHIPS)':
 C_PATH='@t6g_mb_lib.t6g(sch_1):page175_i75@pure_quanta.q_cap(chips)',
 P_PATH='@t6g_mb_lib.t6g(sch_1):page200_i75@pure_quanta.q_cap(chips)',
 PATH='I75',
 DRAWING='@T6G_MB_LIB.T6G(SCH_1):PAGE175',
 TOLERANCE='10%',
 MATERIAL='X7R',
 PHYS_PAGE='200',
 XY='(-2750,1500)',
 ROT='0',
 VER='1',
 PACK_TYPE='0402',
 LOCATION='PC77',
 CDS_LIB='pure_quanta',
 CDS_PART_NAME='Q_CAP_0402-470PF,50V,10%,X7R,TMP_QCH14706KB18',
 VOLTAGE='50V',
 PART_NUMBER='TMP_QCH14706KB18',
 VALUE='470PF',
 PRIM_FILE='./archive_libs/logical/q_cap/chips/chips.prt';

PART_NAME
 PC78 'Q_CAP_0402-470PF,50V,10%,X7R,TMP_QCH14706KB18':;

SECTION_NUMBER 1
 '@T6G_MB_LIB.T6G(SCH_1):PAGE175_I73@PURE_QUANTA.Q_CAP(CHIPS)':
 C_PATH='@t6g_mb_lib.t6g(sch_1):page175_i73@pure_quanta.q_cap(chips)',
 P_PATH='@t6g_mb_lib.t6g(sch_1):page200_i73@pure_quanta.q_cap(chips)',
 PATH='I73',
 DRAWING='@T6G_MB_LIB.T6G(SCH_1):PAGE175',
 TOLERANCE='10%',
 MATERIAL='X7R',
 PHYS_PAGE='200',
 XY='(-2750,925)',
 ROT='0',
 VER='1',
 PACK_TYPE='0402',
 LOCATION='PC78',
 CDS_LIB='pure_quanta',
 CDS_PART_NAME='Q_CAP_0402-470PF,50V,10%,X7R,TMP_QCH14706KB18',
 VOLTAGE='50V',
 PART_NUMBER='TMP_QCH14706KB18',
 VALUE='470PF',
 PRIM_FILE='./archive_libs/logical/q_cap/chips/chips.prt';

PART_NAME
 PC79 'Q_CAP_C0402-2.2UF,10V,10%,X6S,CH5222KEB01':;

SECTION_NUMBER 1
 '@T6G_MB_LIB.T6G(SCH_1):PAGE176_I24@PURE_QUANTA.Q_CAP(CHIPS)':
 C_PATH='@t6g_mb_lib.t6g(sch_1):page176_i24@pure_quanta.q_cap(chips)',
 P_PATH='@t6g_mb_lib.t6g(sch_1):page201_i24@pure_quanta.q_cap(chips)',
 PATH='I24',
 DRAWING='@T6G_MB_LIB.T6G(SCH_1):PAGE176',
 TOLERANCE='10%',
 MATERIAL='X6S',
 PHYS_PAGE='201',
 XY='(-8975,4575)',
 ROT='0',
 VER='1',
 PACK_TYPE='C0402',
 LOCATION='PC79',
 CDS_LIB='pure_quanta',
 CDS_PART_NAME='Q_CAP_C0402-2.2UF,10V,10%,X6S,CH5222KEB01',
 VOLTAGE='10V',
 PART_NUMBER='CH5222KEB01',
 VALUE='2.2UF',
 PRIM_FILE='./archive_libs/logical/q_cap/chips/chips.prt';

PART_NAME
 PC80 'Q_CAP_C0402-2.2UF,10V,10%,X6S,CH5222KEB01':;

SECTION_NUMBER 1
 '@T6G_MB_LIB.T6G(SCH_1):PAGE176_I10@PURE_QUANTA.Q_CAP(CHIPS)':
 C_PATH='@t6g_mb_lib.t6g(sch_1):page176_i10@pure_quanta.q_cap(chips)',
 P_PATH='@t6g_mb_lib.t6g(sch_1):page201_i10@pure_quanta.q_cap(chips)',
 PATH='I10',
 DRAWING='@T6G_MB_LIB.T6G(SCH_1):PAGE176',
 TOLERANCE='10%',
 MATERIAL='X6S',
 PHYS_PAGE='201',
 XY='(-8875,1600)',
 ROT='0',
 VER='1',
 PACK_TYPE='C0402',
 LOCATION='PC80',
 CDS_LIB='pure_quanta',
 CDS_PART_NAME='Q_CAP_C0402-2.2UF,10V,10%,X6S,CH5222KEB01',
 VOLTAGE='10V',
 PART_NUMBER='CH5222KEB01',
 VALUE='2.2UF',
 PRIM_FILE='./archive_libs/logical/q_cap/chips/chips.prt';

PART_NAME
 PC81 'Q_CAP_C0805-22UF,16V,20%,X6S,CH6223MEA01':;

SECTION_NUMBER 1
 '@T6G_MB_LIB.T6G(SCH_1):PAGE184_I27@PURE_QUANTA.Q_CAP(CHIPS)':
 C_PATH='@t6g_mb_lib.t6g(sch_1):page184_i27@pure_quanta.q_cap(chips)',
 P_PATH='@t6g_mb_lib.t6g(sch_1):page209_i27@pure_quanta.q_cap(chips)',
 PATH='I27',
 DRAWING='@T6G_MB_LIB.T6G(SCH_1):PAGE184',
 TOLERANCE='20%',
 MATERIAL='X6S',
 PHYS_PAGE='209',
 XY='(-6975,4125)',
 ROT='0',
 VER='1',
 PACK_TYPE='C0805',
 LOCATION='PC81',
 CDS_LIB='pure_quanta',
 CDS_PART_NAME='Q_CAP_C0805-22UF,16V,20%,X6S,CH6223MEA01',
 VOLTAGE='16V',
 PART_NUMBER='CH6223MEA01',
 VALUE='22UF',
 PRIM_FILE='./archive_libs/logical/q_cap/chips/chips.prt';

PART_NAME
 PC81_C1P0_1 'Q_CAP_C0402-2.2UF,10V,10%,X6S,CH5222KEB01':;

SECTION_NUMBER 1
 '@T6G_MB_LIB.T6G(SCH_1):PAGE176_I30@PURE_QUANTA.Q_CAP(CHIPS)':
 C_PATH='@t6g_mb_lib.t6g(sch_1):page176_i30@pure_quanta.q_cap(chips)',
 P_PATH='@t6g_mb_lib.t6g(sch_1):page201_i30@pure_quanta.q_cap(chips)',
 PATH='I30',
 DRAWING='@T6G_MB_LIB.T6G(SCH_1):PAGE176',
 TOLERANCE='10%',
 MATERIAL='X6S',
 PHYS_PAGE='201',
 XY='(-8625,5075)',
 ROT='0',
 VER='1',
 PACK_TYPE='C0402',
 LOCATION='PC81_C1P0_1',
 CDS_LIB='pure_quanta',
 CDS_PART_NAME='Q_CAP_C0402-2.2UF,10V,10%,X6S,CH5222KEB01',
 VOLTAGE='10V',
 PART_NUMBER='CH5222KEB01',
 VALUE='2.2UF',
 PRIM_FILE='./archive_libs/logical/q_cap/chips/chips.prt';

PART_NAME
 PC82_C1P0_2 'Q_CAP_C0402-2.2UF,10V,10%,X6S,CH5222KEB01':;

SECTION_NUMBER 1
 '@T6G_MB_LIB.T6G(SCH_1):PAGE176_I15@PURE_QUANTA.Q_CAP(CHIPS)':
 C_PATH='@t6g_mb_lib.t6g(sch_1):page176_i15@pure_quanta.q_cap(chips)',
 P_PATH='@t6g_mb_lib.t6g(sch_1):page201_i15@pure_quanta.q_cap(chips)',
 PATH='I15',
 DRAWING='@T6G_MB_LIB.T6G(SCH_1):PAGE176',
 TOLERANCE='10%',
 MATERIAL='X6S',
 PHYS_PAGE='201',
 XY='(-8525,2175)',
 ROT='0',
 VER='1',
 PACK_TYPE='C0402',
 LOCATION='PC82_C1P0_2',
 CDS_LIB='pure_quanta',
 CDS_PART_NAME='Q_CAP_C0402-2.2UF,10V,10%,X6S,CH5222KEB01',
 VOLTAGE='10V',
 PART_NUMBER='CH5222KEB01',
 VALUE='2.2UF',
 PRIM_FILE='./archive_libs/logical/q_cap/chips/chips.prt';

PART_NAME
 PC83 'Q_CAP_C0805-22UF,4V,20%,X6S,CH622KMEA03':;

SECTION_NUMBER 1
 '@T6G_MB_LIB.T6G(SCH_1):PAGE201_I38@PURE_QUANTA.Q_CAP(CHIPS)':
 C_PATH='@t6g_mb_lib.t6g(sch_1):page201_i38@pure_quanta.q_cap(chips)',
 P_PATH='@t6g_mb_lib.t6g(sch_1):page226_i38@pure_quanta.q_cap(chips)',
 PATH='I38',
 DRAWING='@T6G_MB_LIB.T6G(SCH_1):PAGE201',
 TOLERANCE='20%',
 MATERIAL='X6S',
 PHYS_PAGE='226',
 XY='(-2025,3750)',
 ROT='0',
 VER='1',
 PACK_TYPE='C0805',
 LOCATION='PC83',
 CDS_LIB='pure_quanta',
 CDS_PART_NAME='Q_CAP_C0805-22UF,4V,20%,X6S,CH622KMEA03',
 VOLTAGE='4V',
 PART_NUMBER='CH622KMEA03',
 VALUE='22UF',
 PRIM_FILE='./archive_libs/logical/q_cap/chips/chips.prt';

PART_NAME
 PC83_2 'Q_CAP_0402-0.1UF,25V,10%,X7R,CH4104K1B00':;

SECTION_NUMBER 1
 '@T6G_MB_LIB.T6G(SCH_1):PAGE176_I2@PURE_QUANTA.Q_CAP(CHIPS)':
 C_PATH='@t6g_mb_lib.t6g(sch_1):page176_i2@pure_quanta.q_cap(chips)',
 P_PATH='@t6g_mb_lib.t6g(sch_1):page201_i2@pure_quanta.q_cap(chips)',
 PATH='I2',
 DRAWING='@T6G_MB_LIB.T6G(SCH_1):PAGE176',
 TOLERANCE='10%',
 MATERIAL='X7R',
 PHYS_PAGE='201',
 XY='(-9750,850)',
 ROT='0',
 VER='1',
 PACK_TYPE='0402',
 LOCATION='PC83_2',
 CDS_LIB='pure_quanta',
 CDS_PART_NAME='Q_CAP_0402-0.1UF,25V,10%,X7R,CH4104K1B00',
 VOLTAGE='25V',
 PART_NUMBER='CH4104K1B00',
 VALUE='0.1UF',
 PRIM_FILE='./archive_libs/logical/q_cap/chips/chips.prt';

PART_NAME
 PC84 'Q_CAP_C0805-22UF,4V,20%,X6S,CH622KMEA03':;

SECTION_NUMBER 1
 '@T6G_MB_LIB.T6G(SCH_1):PAGE201_I40@PURE_QUANTA.Q_CAP(CHIPS)':
 C_PATH='@t6g_mb_lib.t6g(sch_1):page201_i40@pure_quanta.q_cap(chips)',
 P_PATH='@t6g_mb_lib.t6g(sch_1):page226_i40@pure_quanta.q_cap(chips)',
 PATH='I40',
 DRAWING='@T6G_MB_LIB.T6G(SCH_1):PAGE201',
 TOLERANCE='20%',
 MATERIAL='X6S',
 PHYS_PAGE='226',
 XY='(-1825,3750)',
 ROT='0',
 VER='1',
 PACK_TYPE='C0805',
 LOCATION='PC84',
 CDS_LIB='pure_quanta',
 CDS_PART_NAME='Q_CAP_C0805-22UF,4V,20%,X6S,CH622KMEA03',
 VOLTAGE='4V',
 PART_NUMBER='CH622KMEA03',
 VALUE='22UF',
 PRIM_FILE='./archive_libs/logical/q_cap/chips/chips.prt';

PART_NAME
 PC84_1 'Q_CAP_0402-0.1UF,25V,10%,X7R,CH4104K1B00':;

SECTION_NUMBER 1
 '@T6G_MB_LIB.T6G(SCH_1):PAGE176_I12@PURE_QUANTA.Q_CAP(CHIPS)':
 C_PATH='@t6g_mb_lib.t6g(sch_1):page176_i12@pure_quanta.q_cap(chips)',
 P_PATH='@t6g_mb_lib.t6g(sch_1):page201_i12@pure_quanta.q_cap(chips)',
 PATH='I12',
 DRAWING='@T6G_MB_LIB.T6G(SCH_1):PAGE176',
 TOLERANCE='10%',
 MATERIAL='X7R',
 PHYS_PAGE='201',
 XY='(-9625,3750)',
 ROT='0',
 VER='1',
 PACK_TYPE='0402',
 LOCATION='PC84_1',
 CDS_LIB='pure_quanta',
 CDS_PART_NAME='Q_CAP_0402-0.1UF,25V,10%,X7R,CH4104K1B00',
 VOLTAGE='25V',
 PART_NUMBER='CH4104K1B00',
 VALUE='0.1UF',
 PRIM_FILE='./archive_libs/logical/q_cap/chips/chips.prt';

PART_NAME
 PC85 'Q_CAP_0402-0.1UF,25V,10%,X7R,CH4104K1B00':;

SECTION_NUMBER 1
 '@T6G_MB_LIB.T6G(SCH_1):PAGE176_I87@PURE_QUANTA.Q_CAP(CHIPS)':
 C_PATH='@t6g_mb_lib.t6g(sch_1):page176_i87@pure_quanta.q_cap(chips)',
 P_PATH='@t6g_mb_lib.t6g(sch_1):page201_i87@pure_quanta.q_cap(chips)',
 PATH='I87',
 DRAWING='@T6G_MB_LIB.T6G(SCH_1):PAGE176',
 TOLERANCE='10%',
 MATERIAL='X7R',
 PHYS_PAGE='201',
 XY='(-3250,5050)',
 ROT='0',
 VER='1',
 PACK_TYPE='0402',
 LOCATION='PC85',
 CDS_LIB='pure_quanta',
 CDS_PART_NAME='Q_CAP_0402-0.1UF,25V,10%,X7R,CH4104K1B00',
 VOLTAGE='25V',
 PART_NUMBER='CH4104K1B00',
 VALUE='0.1UF',
 PRIM_FILE='./archive_libs/logical/q_cap/chips/chips.prt';

PART_NAME
 PC85_1 'Q_CAP_0402-0.1UF,25V,10%,X7R,CH4104K1B00':;

SECTION_NUMBER 1
 '@T6G_MB_LIB.T6G(SCH_1):PAGE176_I55@PURE_QUANTA.Q_CAP(CHIPS)':
 C_PATH='@t6g_mb_lib.t6g(sch_1):page176_i55@pure_quanta.q_cap(chips)',
 P_PATH='@t6g_mb_lib.t6g(sch_1):page201_i55@pure_quanta.q_cap(chips)',
 PATH='I55',
 DRAWING='@T6G_MB_LIB.T6G(SCH_1):PAGE176',
 TOLERANCE='10%',
 MATERIAL='X7R',
 PHYS_PAGE='201',
 XY='(-6425,5025)',
 ROT='0',
 VER='1',
 PACK_TYPE='0402',
 LOCATION='PC85_1',
 CDS_LIB='pure_quanta',
 CDS_PART_NAME='Q_CAP_0402-0.1UF,25V,10%,X7R,CH4104K1B00',
 VOLTAGE='25V',
 PART_NUMBER='CH4104K1B00',
 VALUE='0.1UF',
 PRIM_FILE='./archive_libs/logical/q_cap/chips/chips.prt';

PART_NAME
 PC86_2 'Q_CAP_0402-0.1UF,25V,10%,X7R,CH4104K1B00':;

SECTION_NUMBER 1
 '@T6G_MB_LIB.T6G(SCH_1):PAGE176_I37@PURE_QUANTA.Q_CAP(CHIPS)':
 C_PATH='@t6g_mb_lib.t6g(sch_1):page176_i37@pure_quanta.q_cap(chips)',
 P_PATH='@t6g_mb_lib.t6g(sch_1):page201_i37@pure_quanta.q_cap(chips)',
 PATH='I37',
 DRAWING='@T6G_MB_LIB.T6G(SCH_1):PAGE176',
 TOLERANCE='10%',
 MATERIAL='X7R',
 PHYS_PAGE='201',
 XY='(-6400,2075)',
 ROT='0',
 VER='1',
 PACK_TYPE='0402',
 LOCATION='PC86_2',
 CDS_LIB='pure_quanta',
 CDS_PART_NAME='Q_CAP_0402-0.1UF,25V,10%,X7R,CH4104K1B00',
 VOLTAGE='25V',
 PART_NUMBER='CH4104K1B00',
 VALUE='0.1UF',
 PRIM_FILE='./archive_libs/logical/q_cap/chips/chips.prt';

PART_NAME
 PC87 'Q_CAP_C0805-22UF,4V,20%,EMPTY,CH622KMEA03':;

SECTION_NUMBER 1
 '@T6G_MB_LIB.T6G(SCH_1):PAGE201_I41@PURE_QUANTA.Q_CAP(CHIPS)':
 C_PATH='@t6g_mb_lib.t6g(sch_1):page201_i41@pure_quanta.q_cap(chips)',
 P_PATH='@t6g_mb_lib.t6g(sch_1):page226_i41@pure_quanta.q_cap(chips)',
 PATH='I41',
 DRAWING='@T6G_MB_LIB.T6G(SCH_1):PAGE201',
 TOLERANCE='20%',
 MATERIAL='EMPTY',
 PHYS_PAGE='226',
 XY='(-1575,3750)',
 ROT='0',
 VER='1',
 PACK_TYPE='C0805',
 LOCATION='PC87',
 CDS_LIB='pure_quanta',
 CDS_PART_NAME='Q_CAP_C0805-22UF,4V,20%,EMPTY,CH622KMEA03',
 VOLTAGE='4V',
 PART_NUMBER='CH622KMEA03',
 VALUE='22UF',
 PRIM_FILE='./archive_libs/logical/q_cap/chips/chips.prt';

PART_NAME
 PC87_1 'Q_CAP_C0402-1UF,25V,10%,X6S,CH5104KEB02':;

SECTION_NUMBER 1
 '@T6G_MB_LIB.T6G(SCH_1):PAGE176_I59@PURE_QUANTA.Q_CAP(CHIPS)':
 C_PATH='@t6g_mb_lib.t6g(sch_1):page176_i59@pure_quanta.q_cap(chips)',
 P_PATH='@t6g_mb_lib.t6g(sch_1):page201_i59@pure_quanta.q_cap(chips)',
 PATH='I59',
 DRAWING='@T6G_MB_LIB.T6G(SCH_1):PAGE176',
 TOLERANCE='10%',
 MATERIAL='X6S',
 PHYS_PAGE='201',
 XY='(-6025,5025)',
 ROT='0',
 VER='1',
 PACK_TYPE='C0402',
 LOCATION='PC87_1',
 CDS_LIB='pure_quanta',
 CDS_PART_NAME='Q_CAP_C0402-1UF,25V,10%,X6S,CH5104KEB02',
 VOLTAGE='25V',
 PART_NUMBER='CH5104KEB02',
 VALUE='1UF',
 PRIM_FILE='./archive_libs/logical/q_cap/chips/chips.prt';

PART_NAME
 PC88 'Q_CAP_C0805-22UF,4V,20%,EMPTY,CH622KMEA03':;

SECTION_NUMBER 1
 '@T6G_MB_LIB.T6G(SCH_1):PAGE201_I42@PURE_QUANTA.Q_CAP(CHIPS)':
 C_PATH='@t6g_mb_lib.t6g(sch_1):page201_i42@pure_quanta.q_cap(chips)',
 P_PATH='@t6g_mb_lib.t6g(sch_1):page226_i42@pure_quanta.q_cap(chips)',
 PATH='I42',
 DRAWING='@T6G_MB_LIB.T6G(SCH_1):PAGE201',
 TOLERANCE='20%',
 MATERIAL='EMPTY',
 PHYS_PAGE='226',
 XY='(-1250,3750)',
 ROT='0',
 VER='1',
 PACK_TYPE='C0805',
 LOCATION='PC88',
 CDS_LIB='pure_quanta',
 CDS_PART_NAME='Q_CAP_C0805-22UF,4V,20%,EMPTY,CH622KMEA03',
 VOLTAGE='4V',
 PART_NUMBER='CH622KMEA03',
 VALUE='22UF',
 PRIM_FILE='./archive_libs/logical/q_cap/chips/chips.prt';

PART_NAME
 PC88_2 'Q_CAP_C0402-1UF,25V,10%,X6S,CH5104KEB02':;

SECTION_NUMBER 1
 '@T6G_MB_LIB.T6G(SCH_1):PAGE176_I47@PURE_QUANTA.Q_CAP(CHIPS)':
 C_PATH='@t6g_mb_lib.t6g(sch_1):page176_i47@pure_quanta.q_cap(chips)',
 P_PATH='@t6g_mb_lib.t6g(sch_1):page201_i47@pure_quanta.q_cap(chips)',
 PATH='I47',
 DRAWING='@T6G_MB_LIB.T6G(SCH_1):PAGE176',
 TOLERANCE='10%',
 MATERIAL='X6S',
 PHYS_PAGE='201',
 XY='(-6000,2075)',
 ROT='0',
 VER='1',
 PACK_TYPE='C0402',
 LOCATION='PC88_2',
 CDS_LIB='pure_quanta',
 CDS_PART_NAME='Q_CAP_C0402-1UF,25V,10%,X6S,CH5104KEB02',
 VOLTAGE='25V',
 PART_NUMBER='CH5104KEB02',
 VALUE='1UF',
 PRIM_FILE='./archive_libs/logical/q_cap/chips/chips.prt';

PART_NAME
 PC89 'Q_CAPP_SMLF-390UF,2.5V,20%,ALUM,CC7390JMZ13':;

SECTION_NUMBER 1
 '@T6G_MB_LIB.T6G(SCH_1):PAGE201_I43@PURE_QUANTA.Q_CAPP(CHIPS)':
 C_PATH='@t6g_mb_lib.t6g(sch_1):page201_i43@pure_quanta.q_capp(chips)',
 P_PATH='@t6g_mb_lib.t6g(sch_1):page226_i43@pure_quanta.q_capp(chips)',
 PATH='I43',
 DRAWING='@T6G_MB_LIB.T6G(SCH_1):PAGE201',
 TOLERANCE='20%',
 MATERIAL='ALUM',
 PHYS_PAGE='226',
 XY='(-975,3725)',
 ROT='0',
 VER='1',
 PACK_TYPE='SMLF',
 LOCATION='PC89',
 CDS_LIB='pure_quanta',
 CDS_PART_NAME='Q_CAPP_SMLF-390UF,2.5V,20%,ALUM,CC7390JMZ13',
 VOLTAGE='2.5V',
 PART_NUMBER='CC7390JMZ13',
 VALUE='390UF',
 PRIM_FILE='./archive_libs/logical/q_capp/chips/chips.prt';

PART_NAME
 PC89_1 'Q_CAP_C0805-22UF,16V,20%,X6S,CH6223MEA01':;

SECTION_NUMBER 1
 '@T6G_MB_LIB.T6G(SCH_1):PAGE176_I60@PURE_QUANTA.Q_CAP(CHIPS)':
 C_PATH='@t6g_mb_lib.t6g(sch_1):page176_i60@pure_quanta.q_cap(chips)',
 P_PATH='@t6g_mb_lib.t6g(sch_1):page201_i60@pure_quanta.q_cap(chips)',
 PATH='I60',
 DRAWING='@T6G_MB_LIB.T6G(SCH_1):PAGE176',
 TOLERANCE='20%',
 MATERIAL='X6S',
 PHYS_PAGE='201',
 XY='(-5625,5025)',
 ROT='0',
 VER='1',
 PACK_TYPE='C0805',
 LOCATION='PC89_1',
 CDS_LIB='pure_quanta',
 CDS_PART_NAME='Q_CAP_C0805-22UF,16V,20%,X6S,CH6223MEA01',
 VOLTAGE='16V',
 PART_NUMBER='CH6223MEA01',
 VALUE='22UF',
 PRIM_FILE='./archive_libs/logical/q_cap/chips/chips.prt';

PART_NAME
 PC90_2 'Q_CAP_C0805-22UF,16V,20%,X6S,CH6223MEA01':;

SECTION_NUMBER 1
 '@T6G_MB_LIB.T6G(SCH_1):PAGE176_I48@PURE_QUANTA.Q_CAP(CHIPS)':
 C_PATH='@t6g_mb_lib.t6g(sch_1):page176_i48@pure_quanta.q_cap(chips)',
 P_PATH='@t6g_mb_lib.t6g(sch_1):page201_i48@pure_quanta.q_cap(chips)',
 PATH='I48',
 DRAWING='@T6G_MB_LIB.T6G(SCH_1):PAGE176',
 TOLERANCE='20%',
 MATERIAL='X6S',
 PHYS_PAGE='201',
 XY='(-5600,2075)',
 ROT='0',
 VER='1',
 PACK_TYPE='C0805',
 LOCATION='PC90_2',
 CDS_LIB='pure_quanta',
 CDS_PART_NAME='Q_CAP_C0805-22UF,16V,20%,X6S,CH6223MEA01',
 VOLTAGE='16V',
 PART_NUMBER='CH6223MEA01',
 VALUE='22UF',
 PRIM_FILE='./archive_libs/logical/q_cap/chips/chips.prt';

PART_NAME
 PC91_1 'Q_CAP_C0805-22UF,16V,20%,X6S,CH6223MEA01':;

SECTION_NUMBER 1
 '@T6G_MB_LIB.T6G(SCH_1):PAGE176_I64@PURE_QUANTA.Q_CAP(CHIPS)':
 C_PATH='@t6g_mb_lib.t6g(sch_1):page176_i64@pure_quanta.q_cap(chips)',
 P_PATH='@t6g_mb_lib.t6g(sch_1):page201_i64@pure_quanta.q_cap(chips)',
 PATH='I64',
 DRAWING='@T6G_MB_LIB.T6G(SCH_1):PAGE176',
 TOLERANCE='20%',
 MATERIAL='X6S',
 PHYS_PAGE='201',
 XY='(-5225,5025)',
 ROT='0',
 VER='1',
 PACK_TYPE='C0805',
 LOCATION='PC91_1',
 CDS_LIB='pure_quanta',
 CDS_PART_NAME='Q_CAP_C0805-22UF,16V,20%,X6S,CH6223MEA01',
 VOLTAGE='16V',
 PART_NUMBER='CH6223MEA01',
 VALUE='22UF',
 PRIM_FILE='./archive_libs/logical/q_cap/chips/chips.prt';

PART_NAME
 PC92 'Q_CAP_0402-0.22UF,16V,10%,X7R,CH4223K1B00':;

SECTION_NUMBER 1
 '@T6G_MB_LIB.T6G(SCH_1):PAGE176_I61@PURE_QUANTA.Q_CAP(CHIPS)':
 C_PATH='@t6g_mb_lib.t6g(sch_1):page176_i61@pure_quanta.q_cap(chips)',
 P_PATH='@t6g_mb_lib.t6g(sch_1):page201_i61@pure_quanta.q_cap(chips)',
 PATH='I61',
 DRAWING='@T6G_MB_LIB.T6G(SCH_1):PAGE176',
 TOLERANCE='10%',
 MATERIAL='X7R',
 PHYS_PAGE='201',
 XY='(-5225,4350)',
 ROT='0',
 VER='1',
 PACK_TYPE='0402',
 LOCATION='PC92',
 CDS_LIB='pure_quanta',
 CDS_PART_NAME='Q_CAP_0402-0.22UF,16V,10%,X7R,CH4223K1B00',
 VOLTAGE='16V',
 PART_NUMBER='CH4223K1B00',
 VALUE='0.22UF',
 PRIM_FILE='./archive_libs/logical/q_cap/chips/chips.prt';

PART_NAME
 PC93 'Q_CAP_0402-0.1UF,25V,10%,X7R,CH4104K1B00':;

SECTION_NUMBER 1
 '@T6G_MB_LIB.T6G(SCH_1):PAGE192_I93@PURE_QUANTA.Q_CAP(CHIPS)':
 C_PATH='@t6g_mb_lib.t6g(sch_1):page192_i93@pure_quanta.q_cap(chips)',
 P_PATH='@t6g_mb_lib.t6g(sch_1):page217_i93@pure_quanta.q_cap(chips)',
 PATH='I93',
 DRAWING='@T6G_MB_LIB.T6G(SCH_1):PAGE192',
 TOLERANCE='10%',
 MATERIAL='X7R',
 PHYS_PAGE='217',
 XY='(475,6600)',
 ROT='0',
 VER='1',
 PACK_TYPE='0402',
 LOCATION='PC93',
 CDS_LIB='pure_quanta',
 CDS_PART_NAME='Q_CAP_0402-0.1UF,25V,10%,X7R,CH4104K1B00',
 VOLTAGE='25V',
 PART_NUMBER='CH4104K1B00',
 VALUE='0.1UF',
 PRIM_FILE='./archive_libs/logical/q_cap/chips/chips.prt';

PART_NAME
 PC93_2 'Q_CAP_C0805-22UF,16V,20%,X6S,CH6223MEA01':;

SECTION_NUMBER 1
 '@T6G_MB_LIB.T6G(SCH_1):PAGE176_I51@PURE_QUANTA.Q_CAP(CHIPS)':
 C_PATH='@t6g_mb_lib.t6g(sch_1):page176_i51@pure_quanta.q_cap(chips)',
 P_PATH='@t6g_mb_lib.t6g(sch_1):page201_i51@pure_quanta.q_cap(chips)',
 PATH='I51',
 DRAWING='@T6G_MB_LIB.T6G(SCH_1):PAGE176',
 TOLERANCE='20%',
 MATERIAL='X6S',
 PHYS_PAGE='201',
 XY='(-5200,2075)',
 ROT='0',
 VER='1',
 PACK_TYPE='C0805',
 LOCATION='PC93_2',
 CDS_LIB='pure_quanta',
 CDS_PART_NAME='Q_CAP_C0805-22UF,16V,20%,X6S,CH6223MEA01',
 VOLTAGE='16V',
 PART_NUMBER='CH6223MEA01',
 VALUE='22UF',
 PRIM_FILE='./archive_libs/logical/q_cap/chips/chips.prt';

PART_NAME
 PC94 'Q_CAP_0402-0.22UF,16V,10%,X7R,CH4223K1B00':;

SECTION_NUMBER 1
 '@T6G_MB_LIB.T6G(SCH_1):PAGE176_I44@PURE_QUANTA.Q_CAP(CHIPS)':
 C_PATH='@t6g_mb_lib.t6g(sch_1):page176_i44@pure_quanta.q_cap(chips)',
 P_PATH='@t6g_mb_lib.t6g(sch_1):page201_i44@pure_quanta.q_cap(chips)',
 PATH='I44',
 DRAWING='@T6G_MB_LIB.T6G(SCH_1):PAGE176',
 TOLERANCE='10%',
 MATERIAL='X7R',
 PHYS_PAGE='201',
 XY='(-5175,1400)',
 ROT='0',
 VER='1',
 PACK_TYPE='0402',
 LOCATION='PC94',
 CDS_LIB='pure_quanta',
 CDS_PART_NAME='Q_CAP_0402-0.22UF,16V,10%,X7R,CH4223K1B00',
 VOLTAGE='16V',
 PART_NUMBER='CH4223K1B00',
 VALUE='0.22UF',
 PRIM_FILE='./archive_libs/logical/q_cap/chips/chips.prt';

PART_NAME
 PC95 'Q_CAP_0402-0.1UF,25V,10%,X7R,CH4104K1B00':;

SECTION_NUMBER 1
 '@T6G_MB_LIB.T6G(SCH_1):PAGE199_I73@PURE_QUANTA.Q_CAP(CHIPS)':
 C_PATH='@t6g_mb_lib.t6g(sch_1):page199_i73@pure_quanta.q_cap(chips)',
 P_PATH='@t6g_mb_lib.t6g(sch_1):page224_i73@pure_quanta.q_cap(chips)',
 PATH='I73',
 DRAWING='@T6G_MB_LIB.T6G(SCH_1):PAGE199',
 TOLERANCE='10%',
 MATERIAL='X7R',
 PHYS_PAGE='224',
 XY='(-3375,6150)',
 ROT='0',
 VER='1',
 PACK_TYPE='0402',
 LOCATION='PC95',
 CDS_LIB='pure_quanta',
 CDS_PART_NAME='Q_CAP_0402-0.1UF,25V,10%,X7R,CH4104K1B00',
 VOLTAGE='25V',
 PART_NUMBER='CH4104K1B00',
 VALUE='0.1UF',
 PRIM_FILE='./archive_libs/logical/q_cap/chips/chips.prt';

PART_NAME
 PC95_1 'Q_CAP_C0805-22UF,16V,20%,X6S,CH6223MEA01':;

SECTION_NUMBER 1
 '@T6G_MB_LIB.T6G(SCH_1):PAGE176_I65@PURE_QUANTA.Q_CAP(CHIPS)':
 C_PATH='@t6g_mb_lib.t6g(sch_1):page176_i65@pure_quanta.q_cap(chips)',
 P_PATH='@t6g_mb_lib.t6g(sch_1):page201_i65@pure_quanta.q_cap(chips)',
 PATH='I65',
 DRAWING='@T6G_MB_LIB.T6G(SCH_1):PAGE176',
 TOLERANCE='20%',
 MATERIAL='X6S',
 PHYS_PAGE='201',
 XY='(-4850,5025)',
 ROT='0',
 VER='1',
 PACK_TYPE='C0805',
 LOCATION='PC95_1',
 CDS_LIB='pure_quanta',
 CDS_PART_NAME='Q_CAP_C0805-22UF,16V,20%,X6S,CH6223MEA01',
 VOLTAGE='16V',
 PART_NUMBER='CH6223MEA01',
 VALUE='22UF',
 PRIM_FILE='./archive_libs/logical/q_cap/chips/chips.prt';

PART_NAME
 PC96 'Q_CAP_0402-0.1UF,25V,10%,X7R,CH4104K1B00':;

SECTION_NUMBER 1
 '@T6G_MB_LIB.T6G(SCH_1):PAGE199_I72@PURE_QUANTA.Q_CAP(CHIPS)':
 C_PATH='@t6g_mb_lib.t6g(sch_1):page199_i72@pure_quanta.q_cap(chips)',
 P_PATH='@t6g_mb_lib.t6g(sch_1):page224_i72@pure_quanta.q_cap(chips)',
 PATH='I72',
 DRAWING='@T6G_MB_LIB.T6G(SCH_1):PAGE199',
 TOLERANCE='10%',
 MATERIAL='X7R',
 PHYS_PAGE='224',
 XY='(-3375,5675)',
 ROT='0',
 VER='1',
 PACK_TYPE='0402',
 LOCATION='PC96',
 CDS_LIB='pure_quanta',
 CDS_PART_NAME='Q_CAP_0402-0.1UF,25V,10%,X7R,CH4104K1B00',
 VOLTAGE='25V',
 PART_NUMBER='CH4104K1B00',
 VALUE='0.1UF',
 PRIM_FILE='./archive_libs/logical/q_cap/chips/chips.prt';

PART_NAME
 PC96_2 'Q_CAP_C0805-22UF,16V,20%,X6S,CH6223MEA01':;

SECTION_NUMBER 1
 '@T6G_MB_LIB.T6G(SCH_1):PAGE176_I52@PURE_QUANTA.Q_CAP(CHIPS)':
 C_PATH='@t6g_mb_lib.t6g(sch_1):page176_i52@pure_quanta.q_cap(chips)',
 P_PATH='@t6g_mb_lib.t6g(sch_1):page201_i52@pure_quanta.q_cap(chips)',
 PATH='I52',
 DRAWING='@T6G_MB_LIB.T6G(SCH_1):PAGE176',
 TOLERANCE='20%',
 MATERIAL='X6S',
 PHYS_PAGE='201',
 XY='(-4825,2075)',
 ROT='0',
 VER='1',
 PACK_TYPE='C0805',
 LOCATION='PC96_2',
 CDS_LIB='pure_quanta',
 CDS_PART_NAME='Q_CAP_C0805-22UF,16V,20%,X6S,CH6223MEA01',
 VOLTAGE='16V',
 PART_NUMBER='CH6223MEA01',
 VALUE='22UF',
 PRIM_FILE='./archive_libs/logical/q_cap/chips/chips.prt';

PART_NAME
 PC97 'Q_CAPP_SMLF-220UF,4V,20%,SPCAP,CH122KM8801':;

SECTION_NUMBER 1
 '@T6G_MB_LIB.T6G(SCH_1):PAGE176_I71@PURE_QUANTA.Q_CAPP(CHIPS)':
 C_PATH='@t6g_mb_lib.t6g(sch_1):page176_i71@pure_quanta.q_capp(chips)',
 P_PATH='@t6g_mb_lib.t6g(sch_1):page201_i71@pure_quanta.q_capp(chips)',
 PATH='I71',
 DRAWING='@T6G_MB_LIB.T6G(SCH_1):PAGE176',
 TOLERANCE='20%',
 MATERIAL='SPCAP',
 PHYS_PAGE='201',
 XY='(-3350,2675)',
 ROT='0',
 VER='1',
 PACK_TYPE='SMLF',
 LOCATION='PC97',
 CDS_LIB='pure_quanta',
 CDS_PART_NAME='Q_CAPP_SMLF-220UF,4V,20%,SPCAP,CH122KM8801',
 VOLTAGE='4V',
 PART_NUMBER='CH122KM8801',
 VALUE='220UF',
 PRIM_FILE='./archive_libs/logical/q_capp/chips/chips.prt';

PART_NAME
 PC98 'Q_CAPP_SMLF-220UF,4V,20%,SPCAP,CH122KM8801':;

SECTION_NUMBER 1
 '@T6G_MB_LIB.T6G(SCH_1):PAGE176_I72@PURE_QUANTA.Q_CAPP(CHIPS)':
 C_PATH='@t6g_mb_lib.t6g(sch_1):page176_i72@pure_quanta.q_capp(chips)',
 P_PATH='@t6g_mb_lib.t6g(sch_1):page201_i72@pure_quanta.q_capp(chips)',
 PATH='I72',
 DRAWING='@T6G_MB_LIB.T6G(SCH_1):PAGE176',
 TOLERANCE='20%',
 MATERIAL='SPCAP',
 PHYS_PAGE='201',
 XY='(-3025,2675)',
 ROT='0',
 VER='1',
 PACK_TYPE='SMLF',
 LOCATION='PC98',
 CDS_LIB='pure_quanta',
 CDS_PART_NAME='Q_CAPP_SMLF-220UF,4V,20%,SPCAP,CH122KM8801',
 VOLTAGE='4V',
 PART_NUMBER='CH122KM8801',
 VALUE='220UF',
 PRIM_FILE='./archive_libs/logical/q_capp/chips/chips.prt';

PART_NAME
 PC99 'Q_CAP_0402-0.1UF,25V,10%,X7R,CH4104K1B00':;

SECTION_NUMBER 1
 '@T6G_MB_LIB.T6G(SCH_1):PAGE176_I84@PURE_QUANTA.Q_CAP(CHIPS)':
 C_PATH='@t6g_mb_lib.t6g(sch_1):page176_i84@pure_quanta.q_cap(chips)',
 P_PATH='@t6g_mb_lib.t6g(sch_1):page201_i84@pure_quanta.q_cap(chips)',
 PATH='I84',
 DRAWING='@T6G_MB_LIB.T6G(SCH_1):PAGE176',
 TOLERANCE='10%',
 MATERIAL='X7R',
 PHYS_PAGE='201',
 XY='(-2975,3925)',
 ROT='0',
 VER='1',
 PACK_TYPE='0402',
 LOCATION='PC99',
 CDS_LIB='pure_quanta',
 CDS_PART_NAME='Q_CAP_0402-0.1UF,25V,10%,X7R,CH4104K1B00',
 VOLTAGE='25V',
 PART_NUMBER='CH4104K1B00',
 VALUE='0.1UF',
 PRIM_FILE='./archive_libs/logical/q_cap/chips/chips.prt';

PART_NAME
 PC100 'Q_CAPP_SMLF-220UF,4V,20%,SPCAP,CH122KM8801':;

SECTION_NUMBER 1
 '@T6G_MB_LIB.T6G(SCH_1):PAGE176_I73@PURE_QUANTA.Q_CAPP(CHIPS)':
 C_PATH='@t6g_mb_lib.t6g(sch_1):page176_i73@pure_quanta.q_capp(chips)',
 P_PATH='@t6g_mb_lib.t6g(sch_1):page201_i73@pure_quanta.q_capp(chips)',
 PATH='I73',
 DRAWING='@T6G_MB_LIB.T6G(SCH_1):PAGE176',
 TOLERANCE='20%',
 MATERIAL='SPCAP',
 PHYS_PAGE='201',
 XY='(-2700,2675)',
 ROT='0',
 VER='1',
 PACK_TYPE='SMLF',
 LOCATION='PC100',
 CDS_LIB='pure_quanta',
 CDS_PART_NAME='Q_CAPP_SMLF-220UF,4V,20%,SPCAP,CH122KM8801',
 VOLTAGE='4V',
 PART_NUMBER='CH122KM8801',
 VALUE='220UF',
 PRIM_FILE='./archive_libs/logical/q_capp/chips/chips.prt';

PART_NAME
 PC101 'Q_CAPP_THLF-270UF,16V,20%,OSCON,CC72703MD38':;

SECTION_NUMBER 1
 '@T6G_MB_LIB.T6G(SCH_1):PAGE176_I66@PURE_QUANTA.Q_CAPP(CHIPS)':
 C_PATH='@t6g_mb_lib.t6g(sch_1):page176_i66@pure_quanta.q_capp(chips)',
 P_PATH='@t6g_mb_lib.t6g(sch_1):page201_i66@pure_quanta.q_capp(chips)',
 PATH='I66',
 DRAWING='@T6G_MB_LIB.T6G(SCH_1):PAGE176',
 TOLERANCE='20%',
 MATERIAL='OSCON',
 PHYS_PAGE='201',
 XY='(-4425,5025)',
 ROT='0',
 VER='1',
 PACK_TYPE='THLF',
 LOCATION='PC101',
 CDS_LIB='pure_quanta',
 CDS_PART_NAME='Q_CAPP_THLF-270UF,16V,20%,OSCON,CC72703MD38',
 VOLTAGE='16V',
 PART_NUMBER='CC72703MD38',
 VALUE='270UF',
 PRIM_FILE='./archive_libs/logical/q_capp/chips/chips.prt';

PART_NAME
 PC102 'Q_CAPP_SMLF-220UF,4V,20%,SPCAP,CH122KM8801':;

SECTION_NUMBER 1
 '@T6G_MB_LIB.T6G(SCH_1):PAGE176_I70@PURE_QUANTA.Q_CAPP(CHIPS)':
 C_PATH='@t6g_mb_lib.t6g(sch_1):page176_i70@pure_quanta.q_capp(chips)',
 P_PATH='@t6g_mb_lib.t6g(sch_1):page201_i70@pure_quanta.q_capp(chips)',
 PATH='I70',
 DRAWING='@T6G_MB_LIB.T6G(SCH_1):PAGE176',
 TOLERANCE='20%',
 MATERIAL='SPCAP',
 PHYS_PAGE='201',
 XY='(-3700,2675)',
 ROT='0',
 VER='1',
 PACK_TYPE='SMLF',
 LOCATION='PC102',
 CDS_LIB='pure_quanta',
 CDS_PART_NAME='Q_CAPP_SMLF-220UF,4V,20%,SPCAP,CH122KM8801',
 VOLTAGE='4V',
 PART_NUMBER='CH122KM8801',
 VALUE='220UF',
 PRIM_FILE='./archive_libs/logical/q_capp/chips/chips.prt';

PART_NAME
 PC102_1 'Q_CAP_C0805-22UF,4V,20%,X6S,CH622KMEA03':;

SECTION_NUMBER 1
 '@T6G_MB_LIB.T6G(SCH_1):PAGE176_I86@PURE_QUANTA.Q_CAP(CHIPS)':
 C_PATH='@t6g_mb_lib.t6g(sch_1):page176_i86@pure_quanta.q_cap(chips)',
 P_PATH='@t6g_mb_lib.t6g(sch_1):page201_i86@pure_quanta.q_cap(chips)',
 PATH='I86',
 DRAWING='@T6G_MB_LIB.T6G(SCH_1):PAGE176',
 TOLERANCE='20%',
 MATERIAL='X6S',
 PHYS_PAGE='201',
 XY='(-2575,3925)',
 ROT='0',
 VER='1',
 PACK_TYPE='C0805',
 LOCATION='PC102_1',
 CDS_LIB='pure_quanta',
 CDS_PART_NAME='Q_CAP_C0805-22UF,4V,20%,X6S,CH622KMEA03',
 VOLTAGE='4V',
 PART_NUMBER='CH622KMEA03',
 VALUE='22UF',
 PRIM_FILE='./archive_libs/logical/q_cap/chips/chips.prt';

PART_NAME
 PC103 'Q_CAPP_SMLF-220UF,4V,20%,SPCAP,CH122KM8801':;

SECTION_NUMBER 1
 '@T6G_MB_LIB.T6G(SCH_1):PAGE176_I75@PURE_QUANTA.Q_CAPP(CHIPS)':
 C_PATH='@t6g_mb_lib.t6g(sch_1):page176_i75@pure_quanta.q_capp(chips)',
 P_PATH='@t6g_mb_lib.t6g(sch_1):page201_i75@pure_quanta.q_capp(chips)',
 PATH='I75',
 DRAWING='@T6G_MB_LIB.T6G(SCH_1):PAGE176',
 TOLERANCE='20%',
 MATERIAL='SPCAP',
 PHYS_PAGE='201',
 XY='(-2400,2675)',
 ROT='0',
 VER='1',
 PACK_TYPE='SMLF',
 LOCATION='PC103',
 CDS_LIB='pure_quanta',
 CDS_PART_NAME='Q_CAPP_SMLF-220UF,4V,20%,SPCAP,CH122KM8801',
 VOLTAGE='4V',
 PART_NUMBER='CH122KM8801',
 VALUE='220UF',
 PRIM_FILE='./archive_libs/logical/q_capp/chips/chips.prt';

PART_NAME
 PC104 'Q_CAPP_THLF-270UF,16V,20%,OSCON,CC72703MD38':;

SECTION_NUMBER 1
 '@T6G_MB_LIB.T6G(SCH_1):PAGE176_I82@PURE_QUANTA.Q_CAPP(CHIPS)':
 C_PATH='@t6g_mb_lib.t6g(sch_1):page176_i82@pure_quanta.q_capp(chips)',
 P_PATH='@t6g_mb_lib.t6g(sch_1):page201_i82@pure_quanta.q_capp(chips)',
 PATH='I82',
 DRAWING='@T6G_MB_LIB.T6G(SCH_1):PAGE176',
 TOLERANCE='20%',
 MATERIAL='OSCON',
 PHYS_PAGE='201',
 XY='(-4025,5025)',
 ROT='0',
 VER='1',
 PACK_TYPE='THLF',
 LOCATION='PC104',
 CDS_LIB='pure_quanta',
 CDS_PART_NAME='Q_CAPP_THLF-270UF,16V,20%,OSCON,CC72703MD38',
 VOLTAGE='16V',
 PART_NUMBER='CC72703MD38',
 VALUE='270UF',
 PRIM_FILE='./archive_libs/logical/q_capp/chips/chips.prt';

PART_NAME
 PC105 'Q_CAPP_SMLF-220UF,4V,20%,SPCAP,CH122KM8801':;

SECTION_NUMBER 1
 '@T6G_MB_LIB.T6G(SCH_1):PAGE186_I84@PURE_QUANTA.Q_CAPP(CHIPS)':
 C_PATH='@t6g_mb_lib.t6g(sch_1):page186_i84@pure_quanta.q_capp(chips)',
 P_PATH='@t6g_mb_lib.t6g(sch_1):page211_i84@pure_quanta.q_capp(chips)',
 PATH='I84',
 DRAWING='@T6G_MB_LIB.T6G(SCH_1):PAGE186',
 TOLERANCE='20%',
 MATERIAL='SPCAP',
 PHYS_PAGE='211',
 XY='(-3100,2900)',
 ROT='0',
 VER='1',
 PACK_TYPE='SMLF',
 LOCATION='PC105',
 CDS_LIB='pure_quanta',
 CDS_PART_NAME='Q_CAPP_SMLF-220UF,4V,20%,SPCAP,CH122KM8801',
 VOLTAGE='4V',
 PART_NUMBER='CH122KM8801',
 VALUE='220UF',
 PRIM_FILE='./archive_libs/logical/q_capp/chips/chips.prt';

PART_NAME
 PC105_1 'Q_CAP_C0805-22UF,4V,20%,X6S,CH622KMEA03':;

SECTION_NUMBER 1
 '@T6G_MB_LIB.T6G(SCH_1):PAGE176_I89@PURE_QUANTA.Q_CAP(CHIPS)':
 C_PATH='@t6g_mb_lib.t6g(sch_1):page176_i89@pure_quanta.q_cap(chips)',
 P_PATH='@t6g_mb_lib.t6g(sch_1):page201_i89@pure_quanta.q_cap(chips)',
 PATH='I89',
 DRAWING='@T6G_MB_LIB.T6G(SCH_1):PAGE176',
 TOLERANCE='20%',
 MATERIAL='X6S',
 PHYS_PAGE='201',
 XY='(-2150,3925)',
 ROT='0',
 VER='1',
 PACK_TYPE='C0805',
 LOCATION='PC105_1',
 CDS_LIB='pure_quanta',
 CDS_PART_NAME='Q_CAP_C0805-22UF,4V,20%,X6S,CH622KMEA03',
 VOLTAGE='4V',
 PART_NUMBER='CH622KMEA03',
 VALUE='22UF',
 PRIM_FILE='./archive_libs/logical/q_cap/chips/chips.prt';

PART_NAME
 PC106 'Q_CAPP_SMLF-220UF,4V,20%,SPCAP,CH122KM8801':;

SECTION_NUMBER 1
 '@T6G_MB_LIB.T6G(SCH_1):PAGE193_I65@PURE_QUANTA.Q_CAPP(CHIPS)':
 C_PATH='@t6g_mb_lib.t6g(sch_1):page193_i65@pure_quanta.q_capp(chips)',
 P_PATH='@t6g_mb_lib.t6g(sch_1):page218_i65@pure_quanta.q_capp(chips)',
 PATH='I65',
 DRAWING='@T6G_MB_LIB.T6G(SCH_1):PAGE193',
 TOLERANCE='20%',
 MATERIAL='SPCAP',
 PHYS_PAGE='218',
 XY='(-2800,2925)',
 ROT='0',
 VER='1',
 PACK_TYPE='SMLF',
 LOCATION='PC106',
 CDS_LIB='pure_quanta',
 CDS_PART_NAME='Q_CAPP_SMLF-220UF,4V,20%,SPCAP,CH122KM8801',
 VOLTAGE='4V',
 PART_NUMBER='CH122KM8801',
 VALUE='220UF',
 PRIM_FILE='./archive_libs/logical/q_capp/chips/chips.prt';

PART_NAME
 PC106_2 'Q_CAP_C0805-22UF,4V,20%,X6S,CH622KMEA03':;

SECTION_NUMBER 1
 '@T6G_MB_LIB.T6G(SCH_1):PAGE176_I69@PURE_QUANTA.Q_CAP(CHIPS)':
 C_PATH='@t6g_mb_lib.t6g(sch_1):page176_i69@pure_quanta.q_cap(chips)',
 P_PATH='@t6g_mb_lib.t6g(sch_1):page201_i69@pure_quanta.q_cap(chips)',
 PATH='I69',
 DRAWING='@T6G_MB_LIB.T6G(SCH_1):PAGE176',
 TOLERANCE='20%',
 MATERIAL='X6S',
 PHYS_PAGE='201',
 XY='(-2725,975)',
 ROT='0',
 VER='1',
 PACK_TYPE='C0805',
 LOCATION='PC106_2',
 CDS_LIB='pure_quanta',
 CDS_PART_NAME='Q_CAP_C0805-22UF,4V,20%,X6S,CH622KMEA03',
 VOLTAGE='4V',
 PART_NUMBER='CH622KMEA03',
 VALUE='22UF',
 PRIM_FILE='./archive_libs/logical/q_cap/chips/chips.prt';

PART_NAME
 PC107 'Q_CAP_0402-0.1UF,25V,10%,X7R,CH4104K1B00':;

SECTION_NUMBER 1
 '@T6G_MB_LIB.T6G(SCH_1):PAGE180_I73@PURE_QUANTA.Q_CAP(CHIPS)':
 C_PATH='@t6g_mb_lib.t6g(sch_1):page180_i73@pure_quanta.q_cap(chips)',
 P_PATH='@t6g_mb_lib.t6g(sch_1):page205_i73@pure_quanta.q_cap(chips)',
 PATH='I73',
 DRAWING='@T6G_MB_LIB.T6G(SCH_1):PAGE180',
 TOLERANCE='10%',
 MATERIAL='X7R',
 PHYS_PAGE='205',
 XY='(7200,4775)',
 ROT='0',
 VER='1',
 PACK_TYPE='0402',
 LOCATION='PC107',
 CDS_LIB='pure_quanta',
 CDS_PART_NAME='Q_CAP_0402-0.1UF,25V,10%,X7R,CH4104K1B00',
 VOLTAGE='25V',
 PART_NUMBER='CH4104K1B00',
 VALUE='0.1UF',
 PRIM_FILE='./archive_libs/logical/q_cap/chips/chips.prt';

PART_NAME
 PC108 'Q_CAPP_SMLF-220UF,4V,20%,SPCAP,CH122KM8801':;

SECTION_NUMBER 1
 '@T6G_MB_LIB.T6G(SCH_1):PAGE169_I64@PURE_QUANTA.Q_CAPP(CHIPS)':
 C_PATH='@t6g_mb_lib.t6g(sch_1):page169_i64@pure_quanta.q_capp(chips)',
 P_PATH='@t6g_mb_lib.t6g(sch_1):page194_i64@pure_quanta.q_capp(chips)',
 PATH='I64',
 DRAWING='@T6G_MB_LIB.T6G(SCH_1):PAGE169',
 TOLERANCE='20%',
 MATERIAL='SPCAP',
 PHYS_PAGE='194',
 XY='(-3175,2800)',
 ROT='0',
 VER='1',
 PACK_TYPE='SMLF',
 LOCATION='PC108',
 CDS_LIB='pure_quanta',
 CDS_PART_NAME='Q_CAPP_SMLF-220UF,4V,20%,SPCAP,CH122KM8801',
 VOLTAGE='4V',
 PART_NUMBER='CH122KM8801',
 VALUE='220UF',
 PRIM_FILE='./archive_libs/logical/q_capp/chips/chips.prt';

PART_NAME
 PC108_2 'Q_CAP_C0805-22UF,4V,20%,X6S,CH622KMEA03':;

SECTION_NUMBER 1
 '@T6G_MB_LIB.T6G(SCH_1):PAGE176_I77@PURE_QUANTA.Q_CAP(CHIPS)':
 C_PATH='@t6g_mb_lib.t6g(sch_1):page176_i77@pure_quanta.q_cap(chips)',
 P_PATH='@t6g_mb_lib.t6g(sch_1):page201_i77@pure_quanta.q_cap(chips)',
 PATH='I77',
 DRAWING='@T6G_MB_LIB.T6G(SCH_1):PAGE176',
 TOLERANCE='20%',
 MATERIAL='X6S',
 PHYS_PAGE='201',
 XY='(-2300,975)',
 ROT='0',
 VER='1',
 PACK_TYPE='C0805',
 LOCATION='PC108_2',
 CDS_LIB='pure_quanta',
 CDS_PART_NAME='Q_CAP_C0805-22UF,4V,20%,X6S,CH622KMEA03',
 VOLTAGE='4V',
 PART_NUMBER='CH622KMEA03',
 VALUE='22UF',
 PRIM_FILE='./archive_libs/logical/q_cap/chips/chips.prt';

PART_NAME
 PC109 'Q_CAP_C0402-2.2UF,10V,10%,X6S,CH5222KEB01':;

SECTION_NUMBER 1
 '@T6G_MB_LIB.T6G(SCH_1):PAGE177_I7@PURE_QUANTA.Q_CAP(CHIPS)':
 C_PATH='@t6g_mb_lib.t6g(sch_1):page177_i7@pure_quanta.q_cap(chips)',
 P_PATH='@t6g_mb_lib.t6g(sch_1):page202_i7@pure_quanta.q_cap(chips)',
 PATH='I7',
 DRAWING='@T6G_MB_LIB.T6G(SCH_1):PAGE177',
 TOLERANCE='10%',
 MATERIAL='X6S',
 PHYS_PAGE='202',
 XY='(1475,1975)',
 ROT='0',
 VER='1',
 PACK_TYPE='C0402',
 LOCATION='PC109',
 CDS_LIB='pure_quanta',
 CDS_PART_NAME='Q_CAP_C0402-2.2UF,10V,10%,X6S,CH5222KEB01',
 VOLTAGE='10V',
 PART_NUMBER='CH5222KEB01',
 VALUE='2.2UF',
 PRIM_FILE='./archive_libs/logical/q_cap/chips/chips.prt';

PART_NAME
 PC110 'Q_CAP_C0402-2.2UF,10V,10%,X6S,CH5222KEB01':;

SECTION_NUMBER 1
 '@T6G_MB_LIB.T6G(SCH_1):PAGE177_I28@PURE_QUANTA.Q_CAP(CHIPS)':
 C_PATH='@t6g_mb_lib.t6g(sch_1):page177_i28@pure_quanta.q_cap(chips)',
 P_PATH='@t6g_mb_lib.t6g(sch_1):page202_i28@pure_quanta.q_cap(chips)',
 PATH='I28',
 DRAWING='@T6G_MB_LIB.T6G(SCH_1):PAGE177',
 TOLERANCE='10%',
 MATERIAL='X6S',
 PHYS_PAGE='202',
 XY='(1650,4800)',
 ROT='0',
 VER='1',
 PACK_TYPE='C0402',
 LOCATION='PC110',
 CDS_LIB='pure_quanta',
 CDS_PART_NAME='Q_CAP_C0402-2.2UF,10V,10%,X6S,CH5222KEB01',
 VOLTAGE='10V',
 PART_NUMBER='CH5222KEB01',
 VALUE='2.2UF',
 PRIM_FILE='./archive_libs/logical/q_cap/chips/chips.prt';

PART_NAME
 PC111 'Q_CAP_C0805-22UF,16V,20%,X6S,CH6223MEA01':;

SECTION_NUMBER 1
 '@T6G_MB_LIB.T6G(SCH_1):PAGE184_I8@PURE_QUANTA.Q_CAP(CHIPS)':
 C_PATH='@t6g_mb_lib.t6g(sch_1):page184_i8@pure_quanta.q_cap(chips)',
 P_PATH='@t6g_mb_lib.t6g(sch_1):page209_i8@pure_quanta.q_cap(chips)',
 PATH='I8',
 DRAWING='@T6G_MB_LIB.T6G(SCH_1):PAGE184',
 TOLERANCE='20%',
 MATERIAL='X6S',
 PHYS_PAGE='209',
 XY='(-7875,4125)',
 ROT='0',
 VER='1',
 PACK_TYPE='C0805',
 LOCATION='PC111',
 CDS_LIB='pure_quanta',
 CDS_PART_NAME='Q_CAP_C0805-22UF,16V,20%,X6S,CH6223MEA01',
 VOLTAGE='16V',
 PART_NUMBER='CH6223MEA01',
 VALUE='22UF',
 PRIM_FILE='./archive_libs/logical/q_cap/chips/chips.prt';

PART_NAME
 PC111_6 'Q_CAP_0402-0.1UF,25V,10%,X7R,CH4104K1B00':;

SECTION_NUMBER 1
 '@T6G_MB_LIB.T6G(SCH_1):PAGE178_I2@PURE_QUANTA.Q_CAP(CHIPS)':
 C_PATH='@t6g_mb_lib.t6g(sch_1):page178_i2@pure_quanta.q_cap(chips)',
 P_PATH='@t6g_mb_lib.t6g(sch_1):page203_i2@pure_quanta.q_cap(chips)',
 PATH='I2',
 DRAWING='@T6G_MB_LIB.T6G(SCH_1):PAGE178',
 TOLERANCE='10%',
 MATERIAL='X7R',
 PHYS_PAGE='203',
 XY='(950,1850)',
 ROT='0',
 VER='1',
 PACK_TYPE='0402',
 LOCATION='PC111_6',
 CDS_LIB='pure_quanta',
 CDS_PART_NAME='Q_CAP_0402-0.1UF,25V,10%,X7R,CH4104K1B00',
 VOLTAGE='25V',
 PART_NUMBER='CH4104K1B00',
 VALUE='0.1UF',
 PRIM_FILE='./archive_libs/logical/q_cap/chips/chips.prt';

PART_NAME
 PC111_C1P0_4 'Q_CAP_C0402-2.2UF,10V,10%,X6S,CH5222KEB01':;

SECTION_NUMBER 1
 '@T6G_MB_LIB.T6G(SCH_1):PAGE177_I16@PURE_QUANTA.Q_CAP(CHIPS)':
 C_PATH='@t6g_mb_lib.t6g(sch_1):page177_i16@pure_quanta.q_cap(chips)',
 P_PATH='@t6g_mb_lib.t6g(sch_1):page202_i16@pure_quanta.q_cap(chips)',
 PATH='I16',
 DRAWING='@T6G_MB_LIB.T6G(SCH_1):PAGE177',
 TOLERANCE='10%',
 MATERIAL='X6S',
 PHYS_PAGE='202',
 XY='(1825,2550)',
 ROT='0',
 VER='1',
 PACK_TYPE='C0402',
 LOCATION='PC111_C1P0_4',
 CDS_LIB='pure_quanta',
 CDS_PART_NAME='Q_CAP_C0402-2.2UF,10V,10%,X6S,CH5222KEB01',
 VOLTAGE='10V',
 PART_NUMBER='CH5222KEB01',
 VALUE='2.2UF',
 PRIM_FILE='./archive_libs/logical/q_cap/chips/chips.prt';

PART_NAME
 PC112 'Q_CAP_C0402-2.2UF,10V,10%,X6S,CH5222KEB01':;

SECTION_NUMBER 1
 '@T6G_MB_LIB.T6G(SCH_1):PAGE178_I11@PURE_QUANTA.Q_CAP(CHIPS)':
 C_PATH='@t6g_mb_lib.t6g(sch_1):page178_i11@pure_quanta.q_cap(chips)',
 P_PATH='@t6g_mb_lib.t6g(sch_1):page203_i11@pure_quanta.q_cap(chips)',
 PATH='I11',
 DRAWING='@T6G_MB_LIB.T6G(SCH_1):PAGE178',
 TOLERANCE='10%',
 MATERIAL='X6S',
 PHYS_PAGE='203',
 XY='(1900,2650)',
 ROT='0',
 VER='1',
 PACK_TYPE='C0402',
 LOCATION='PC112',
 CDS_LIB='pure_quanta',
 CDS_PART_NAME='Q_CAP_C0402-2.2UF,10V,10%,X6S,CH5222KEB01',
 VOLTAGE='10V',
 PART_NUMBER='CH5222KEB01',
 VALUE='2.2UF',
 PRIM_FILE='./archive_libs/logical/q_cap/chips/chips.prt';

PART_NAME
 PC112_C1P0_3 'Q_CAP_C0402-2.2UF,10V,10%,X6S,CH5222KEB01':;

SECTION_NUMBER 1
 '@T6G_MB_LIB.T6G(SCH_1):PAGE177_I32@PURE_QUANTA.Q_CAP(CHIPS)':
 C_PATH='@t6g_mb_lib.t6g(sch_1):page177_i32@pure_quanta.q_cap(chips)',
 P_PATH='@t6g_mb_lib.t6g(sch_1):page202_i32@pure_quanta.q_cap(chips)',
 PATH='I32',
 DRAWING='@T6G_MB_LIB.T6G(SCH_1):PAGE177',
 TOLERANCE='10%',
 MATERIAL='X6S',
 PHYS_PAGE='202',
 XY='(2000,5375)',
 ROT='0',
 VER='1',
 PACK_TYPE='C0402',
 LOCATION='PC112_C1P0_3',
 CDS_LIB='pure_quanta',
 CDS_PART_NAME='Q_CAP_C0402-2.2UF,10V,10%,X6S,CH5222KEB01',
 VOLTAGE='10V',
 PART_NUMBER='CH5222KEB01',
 VALUE='2.2UF',
 PRIM_FILE='./archive_libs/logical/q_cap/chips/chips.prt';

PART_NAME
 PC113 'Q_CAP_0402-0.1UF,25V,10%,X7R,CH4104K1B00':;

SECTION_NUMBER 1
 '@T6G_MB_LIB.T6G(SCH_1):PAGE184_I22@PURE_QUANTA.Q_CAP(CHIPS)':
 C_PATH='@t6g_mb_lib.t6g(sch_1):page184_i22@pure_quanta.q_cap(chips)',
 P_PATH='@t6g_mb_lib.t6g(sch_1):page209_i22@pure_quanta.q_cap(chips)',
 PATH='I22',
 DRAWING='@T6G_MB_LIB.T6G(SCH_1):PAGE184',
 TOLERANCE='10%',
 MATERIAL='X7R',
 PHYS_PAGE='209',
 XY='(-4575,2875)',
 ROT='1',
 VER='1',
 PACK_TYPE='0402',
 LOCATION='PC113',
 CDS_LIB='pure_quanta',
 CDS_PART_NAME='Q_CAP_0402-0.1UF,25V,10%,X7R,CH4104K1B00',
 VOLTAGE='25V',
 PART_NUMBER='CH4104K1B00',
 VALUE='0.1UF',
 PRIM_FILE='./archive_libs/logical/q_cap/chips/chips.prt';

PART_NAME
 PC113_4 'Q_CAP_0402-0.1UF,25V,10%,X7R,CH4104K1B00':;

SECTION_NUMBER 1
 '@T6G_MB_LIB.T6G(SCH_1):PAGE177_I2@PURE_QUANTA.Q_CAP(CHIPS)':
 C_PATH='@t6g_mb_lib.t6g(sch_1):page177_i2@pure_quanta.q_cap(chips)',
 P_PATH='@t6g_mb_lib.t6g(sch_1):page202_i2@pure_quanta.q_cap(chips)',
 PATH='I2',
 DRAWING='@T6G_MB_LIB.T6G(SCH_1):PAGE177',
 TOLERANCE='10%',
 MATERIAL='X7R',
 PHYS_PAGE='202',
 XY='(825,1150)',
 ROT='0',
 VER='1',
 PACK_TYPE='0402',
 LOCATION='PC113_4',
 CDS_LIB='pure_quanta',
 CDS_PART_NAME='Q_CAP_0402-0.1UF,25V,10%,X7R,CH4104K1B00',
 VOLTAGE='25V',
 PART_NUMBER='CH4104K1B00',
 VALUE='0.1UF',
 PRIM_FILE='./archive_libs/logical/q_cap/chips/chips.prt';

PART_NAME
 PC113_C1P0_6 'Q_CAP_C0402-2.2UF,10V,10%,X6S,CH5222KEB01':;

SECTION_NUMBER 1
 '@T6G_MB_LIB.T6G(SCH_1):PAGE178_I20@PURE_QUANTA.Q_CAP(CHIPS)':
 C_PATH='@t6g_mb_lib.t6g(sch_1):page178_i20@pure_quanta.q_cap(chips)',
 P_PATH='@t6g_mb_lib.t6g(sch_1):page203_i20@pure_quanta.q_cap(chips)',
 PATH='I20',
 DRAWING='@T6G_MB_LIB.T6G(SCH_1):PAGE178',
 TOLERANCE='10%',
 MATERIAL='X6S',
 PHYS_PAGE='203',
 XY='(2250,3225)',
 ROT='0',
 VER='1',
 PACK_TYPE='C0402',
 LOCATION='PC113_C1P0_6',
 CDS_LIB='pure_quanta',
 CDS_PART_NAME='Q_CAP_C0402-2.2UF,10V,10%,X6S,CH5222KEB01',
 VOLTAGE='10V',
 PART_NUMBER='CH5222KEB01',
 VALUE='2.2UF',
 PRIM_FILE='./archive_libs/logical/q_cap/chips/chips.prt';

PART_NAME
 PC114 'Q_CAP_C0805-22UF,4V,20%,X6S,CH622KMEA03':;

SECTION_NUMBER 1
 '@T6G_MB_LIB.T6G(SCH_1):PAGE184_I39@PURE_QUANTA.Q_CAP(CHIPS)':
 C_PATH='@t6g_mb_lib.t6g(sch_1):page184_i39@pure_quanta.q_cap(chips)',
 P_PATH='@t6g_mb_lib.t6g(sch_1):page209_i39@pure_quanta.q_cap(chips)',
 PATH='I39',
 DRAWING='@T6G_MB_LIB.T6G(SCH_1):PAGE184',
 TOLERANCE='20%',
 MATERIAL='X6S',
 PHYS_PAGE='209',
 XY='(-2925,3325)',
 ROT='0',
 VER='1',
 PACK_TYPE='C0805',
 LOCATION='PC114',
 CDS_LIB='pure_quanta',
 CDS_PART_NAME='Q_CAP_C0805-22UF,4V,20%,X6S,CH622KMEA03',
 VOLTAGE='4V',
 PART_NUMBER='CH622KMEA03',
 VALUE='22UF',
 PRIM_FILE='./archive_libs/logical/q_cap/chips/chips.prt';

PART_NAME
 PC114_3 'Q_CAP_0402-0.1UF,25V,10%,X7R,CH4104K1B00':;

SECTION_NUMBER 1
 '@T6G_MB_LIB.T6G(SCH_1):PAGE177_I12@PURE_QUANTA.Q_CAP(CHIPS)':
 C_PATH='@t6g_mb_lib.t6g(sch_1):page177_i12@pure_quanta.q_cap(chips)',
 P_PATH='@t6g_mb_lib.t6g(sch_1):page202_i12@pure_quanta.q_cap(chips)',
 PATH='I12',
 DRAWING='@T6G_MB_LIB.T6G(SCH_1):PAGE177',
 TOLERANCE='10%',
 MATERIAL='X7R',
 PHYS_PAGE='202',
 XY='(850,3975)',
 ROT='0',
 VER='1',
 PACK_TYPE='0402',
 LOCATION='PC114_3',
 CDS_LIB='pure_quanta',
 CDS_PART_NAME='Q_CAP_0402-0.1UF,25V,10%,X7R,CH4104K1B00',
 VOLTAGE='25V',
 PART_NUMBER='CH4104K1B00',
 VALUE='0.1UF',
 PRIM_FILE='./archive_libs/logical/q_cap/chips/chips.prt';

PART_NAME
 PC114_6 'Q_CAP_0402-0.1UF,25V,10%,X7R,CH4104K1B00':;

SECTION_NUMBER 1
 '@T6G_MB_LIB.T6G(SCH_1):PAGE178_I40@PURE_QUANTA.Q_CAP(CHIPS)':
 C_PATH='@t6g_mb_lib.t6g(sch_1):page178_i40@pure_quanta.q_cap(chips)',
 P_PATH='@t6g_mb_lib.t6g(sch_1):page203_i40@pure_quanta.q_cap(chips)',
 PATH='I40',
 DRAWING='@T6G_MB_LIB.T6G(SCH_1):PAGE178',
 TOLERANCE='10%',
 MATERIAL='X7R',
 PHYS_PAGE='203',
 XY='(4225,3125)',
 ROT='0',
 VER='1',
 PACK_TYPE='0402',
 LOCATION='PC114_6',
 CDS_LIB='pure_quanta',
 CDS_PART_NAME='Q_CAP_0402-0.1UF,25V,10%,X7R,CH4104K1B00',
 VOLTAGE='25V',
 PART_NUMBER='CH4104K1B00',
 VALUE='0.1UF',
 PRIM_FILE='./archive_libs/logical/q_cap/chips/chips.prt';

PART_NAME
 PC115 'Q_CAPP_SMLF-390UF,2.5V,20%,ALUM,CC7390JMZ13':;

SECTION_NUMBER 1
 '@T6G_MB_LIB.T6G(SCH_1):PAGE184_I47@PURE_QUANTA.Q_CAPP(CHIPS)':
 C_PATH='@t6g_mb_lib.t6g(sch_1):page184_i47@pure_quanta.q_capp(chips)',
 P_PATH='@t6g_mb_lib.t6g(sch_1):page209_i47@pure_quanta.q_capp(chips)',
 PATH='I47',
 DRAWING='@T6G_MB_LIB.T6G(SCH_1):PAGE184',
 TOLERANCE='20%',
 MATERIAL='ALUM',
 PHYS_PAGE='209',
 XY='(-1425,3325)',
 ROT='0',
 VER='1',
 PACK_TYPE='SMLF',
 LOCATION='PC115',
 CDS_LIB='pure_quanta',
 CDS_PART_NAME='Q_CAPP_SMLF-390UF,2.5V,20%,ALUM,CC7390JMZ13',
 VOLTAGE='2.5V',
 PART_NUMBER='CC7390JMZ13',
 VALUE='390UF',
 PRIM_FILE='./archive_libs/logical/q_capp/chips/chips.prt';

PART_NAME
 PC115_4 'Q_CAP_0402-0.1UF,25V,10%,X7R,CH4104K1B00':;

SECTION_NUMBER 1
 '@T6G_MB_LIB.T6G(SCH_1):PAGE177_I24@PURE_QUANTA.Q_CAP(CHIPS)':
 C_PATH='@t6g_mb_lib.t6g(sch_1):page177_i24@pure_quanta.q_cap(chips)',
 P_PATH='@t6g_mb_lib.t6g(sch_1):page202_i24@pure_quanta.q_cap(chips)',
 PATH='I24',
 DRAWING='@T6G_MB_LIB.T6G(SCH_1):PAGE177',
 TOLERANCE='10%',
 MATERIAL='X7R',
 PHYS_PAGE='202',
 XY='(4050,2450)',
 ROT='0',
 VER='1',
 PACK_TYPE='0402',
 LOCATION='PC115_4',
 CDS_LIB='pure_quanta',
 CDS_PART_NAME='Q_CAP_0402-0.1UF,25V,10%,X7R,CH4104K1B00',
 VOLTAGE='25V',
 PART_NUMBER='CH4104K1B00',
 VALUE='0.1UF',
 PRIM_FILE='./archive_libs/logical/q_cap/chips/chips.prt';

PART_NAME
 PC115_6 'Q_CAP_C0402-1UF,25V,10%,X6S,CH5104KEB02':;

SECTION_NUMBER 1
 '@T6G_MB_LIB.T6G(SCH_1):PAGE178_I41@PURE_QUANTA.Q_CAP(CHIPS)':
 C_PATH='@t6g_mb_lib.t6g(sch_1):page178_i41@pure_quanta.q_cap(chips)',
 P_PATH='@t6g_mb_lib.t6g(sch_1):page203_i41@pure_quanta.q_cap(chips)',
 PATH='I41',
 DRAWING='@T6G_MB_LIB.T6G(SCH_1):PAGE178',
 TOLERANCE='10%',
 MATERIAL='X6S',
 PHYS_PAGE='203',
 XY='(4650,3125)',
 ROT='0',
 VER='1',
 PACK_TYPE='C0402',
 LOCATION='PC115_6',
 CDS_LIB='pure_quanta',
 CDS_PART_NAME='Q_CAP_C0402-1UF,25V,10%,X6S,CH5104KEB02',
 VOLTAGE='25V',
 PART_NUMBER='CH5104KEB02',
 VALUE='1UF',
 PRIM_FILE='./archive_libs/logical/q_cap/chips/chips.prt';

PART_NAME
 PC116_3 'Q_CAP_0402-0.1UF,25V,10%,X7R,CH4104K1B00':;

SECTION_NUMBER 1
 '@T6G_MB_LIB.T6G(SCH_1):PAGE177_I34@PURE_QUANTA.Q_CAP(CHIPS)':
 C_PATH='@t6g_mb_lib.t6g(sch_1):page177_i34@pure_quanta.q_cap(chips)',
 P_PATH='@t6g_mb_lib.t6g(sch_1):page202_i34@pure_quanta.q_cap(chips)',
 PATH='I34',
 DRAWING='@T6G_MB_LIB.T6G(SCH_1):PAGE177',
 TOLERANCE='10%',
 MATERIAL='X7R',
 PHYS_PAGE='202',
 XY='(4100,5300)',
 ROT='0',
 VER='1',
 PACK_TYPE='0402',
 LOCATION='PC116_3',
 CDS_LIB='pure_quanta',
 CDS_PART_NAME='Q_CAP_0402-0.1UF,25V,10%,X7R,CH4104K1B00',
 VOLTAGE='25V',
 PART_NUMBER='CH4104K1B00',
 VALUE='0.1UF',
 PRIM_FILE='./archive_libs/logical/q_cap/chips/chips.prt';

PART_NAME
 PC116_6 'Q_CAP_C0805-22UF,16V,20%,X6S,CH6223MEA01':;

SECTION_NUMBER 1
 '@T6G_MB_LIB.T6G(SCH_1):PAGE178_I42@PURE_QUANTA.Q_CAP(CHIPS)':
 C_PATH='@t6g_mb_lib.t6g(sch_1):page178_i42@pure_quanta.q_cap(chips)',
 P_PATH='@t6g_mb_lib.t6g(sch_1):page203_i42@pure_quanta.q_cap(chips)',
 PATH='I42',
 DRAWING='@T6G_MB_LIB.T6G(SCH_1):PAGE178',
 TOLERANCE='20%',
 MATERIAL='X6S',
 PHYS_PAGE='203',
 XY='(5050,3125)',
 ROT='0',
 VER='1',
 PACK_TYPE='C0805',
 LOCATION='PC116_6',
 CDS_LIB='pure_quanta',
 CDS_PART_NAME='Q_CAP_C0805-22UF,16V,20%,X6S,CH6223MEA01',
 VOLTAGE='16V',
 PART_NUMBER='CH6223MEA01',
 VALUE='22UF',
 PRIM_FILE='./archive_libs/logical/q_cap/chips/chips.prt';

PART_NAME
 PC117 'Q_CAP_0402-0.22UF,16V,10%,X7R,CH4223K1B00':;

SECTION_NUMBER 1
 '@T6G_MB_LIB.T6G(SCH_1):PAGE178_I37@PURE_QUANTA.Q_CAP(CHIPS)':
 C_PATH='@t6g_mb_lib.t6g(sch_1):page178_i37@pure_quanta.q_cap(chips)',
 P_PATH='@t6g_mb_lib.t6g(sch_1):page203_i37@pure_quanta.q_cap(chips)',
 PATH='I37',
 DRAWING='@T6G_MB_LIB.T6G(SCH_1):PAGE178',
 TOLERANCE='10%',
 MATERIAL='X7R',
 PHYS_PAGE='203',
 XY='(5350,2450)',
 ROT='0',
 VER='1',
 PACK_TYPE='0402',
 LOCATION='PC117',
 CDS_LIB='pure_quanta',
 CDS_PART_NAME='Q_CAP_0402-0.22UF,16V,10%,X7R,CH4223K1B00',
 VOLTAGE='16V',
 PART_NUMBER='CH4223K1B00',
 VALUE='0.22UF',
 PRIM_FILE='./archive_libs/logical/q_cap/chips/chips.prt';

PART_NAME
 PC117_4 'Q_CAP_C0402-1UF,25V,10%,X6S,CH5104KEB02':;

SECTION_NUMBER 1
 '@T6G_MB_LIB.T6G(SCH_1):PAGE177_I43@PURE_QUANTA.Q_CAP(CHIPS)':
 C_PATH='@t6g_mb_lib.t6g(sch_1):page177_i43@pure_quanta.q_cap(chips)',
 P_PATH='@t6g_mb_lib.t6g(sch_1):page202_i43@pure_quanta.q_cap(chips)',
 PATH='I43',
 DRAWING='@T6G_MB_LIB.T6G(SCH_1):PAGE177',
 TOLERANCE='10%',
 MATERIAL='X6S',
 PHYS_PAGE='202',
 XY='(4450,2425)',
 ROT='0',
 VER='1',
 PACK_TYPE='C0402',
 LOCATION='PC117_4',
 CDS_LIB='pure_quanta',
 CDS_PART_NAME='Q_CAP_C0402-1UF,25V,10%,X6S,CH5104KEB02',
 VOLTAGE='25V',
 PART_NUMBER='CH5104KEB02',
 VALUE='1UF',
 PRIM_FILE='./archive_libs/logical/q_cap/chips/chips.prt';

PART_NAME
 PC118 'Q_CAP_C0402-1UF,25V,10%,X6S,CH5104KEB02':
 SIGNAL_MODEL='DEFAULT_CAPACITOR_100000PF_2_1';

SECTION_NUMBER 1
 '@T6G_MB_LIB.T6G(SCH_1):PAGE167_I2@PURE_QUANTA.Q_CAP(CHIPS)':
 C_PATH='@t6g_mb_lib.t6g(sch_1):page167_i2@pure_quanta.q_cap(chips)',
 P_PATH='@t6g_mb_lib.t6g(sch_1):page192_i2@pure_quanta.q_cap(chips)',
 PATH='I2',
 DRAWING='@T6G_MB_LIB.T6G(SCH_1):PAGE167',
 SEC_TYPE='C0402',
 TOLERANCE='10%',
 MATERIAL='X6S',
 PHYS_PAGE='192',
 XY='(-8450,2500)',
 ROT='2',
 VER='1',
 PACK_TYPE='C0402',
 LOCATION='PC118',
 SEC='1',
 CDS_LIB='pure_quanta',
 CDS_PART_NAME='Q_CAP_C0402-1UF,25V,10%,X6S,CH5104KEB02',
 SIGNAL_MODEL='DEFAULT_CAPACITOR_100000PF_2_1',
 VOLTAGE='25V',
 PART_NUMBER='CH5104KEB02',
 VALUE='1UF',
 PRIM_FILE='./archive_libs/logical/q_cap/chips/chips.prt';

PART_NAME
 PC118_3 'Q_CAP_C0402-1UF,25V,10%,X6S,CH5104KEB02':;

SECTION_NUMBER 1
 '@T6G_MB_LIB.T6G(SCH_1):PAGE177_I60@PURE_QUANTA.Q_CAP(CHIPS)':
 C_PATH='@t6g_mb_lib.t6g(sch_1):page177_i60@pure_quanta.q_cap(chips)',
 P_PATH='@t6g_mb_lib.t6g(sch_1):page202_i60@pure_quanta.q_cap(chips)',
 PATH='I60',
 DRAWING='@T6G_MB_LIB.T6G(SCH_1):PAGE177',
 TOLERANCE='10%',
 MATERIAL='X6S',
 PHYS_PAGE='202',
 XY='(4500,5275)',
 ROT='0',
 VER='1',
 PACK_TYPE='C0402',
 LOCATION='PC118_3',
 CDS_LIB='pure_quanta',
 CDS_PART_NAME='Q_CAP_C0402-1UF,25V,10%,X6S,CH5104KEB02',
 VOLTAGE='25V',
 PART_NUMBER='CH5104KEB02',
 VALUE='1UF',
 PRIM_FILE='./archive_libs/logical/q_cap/chips/chips.prt';

PART_NAME
 PC118_6 'Q_CAP_C0805-22UF,16V,20%,X6S,CH6223MEA01':;

SECTION_NUMBER 1
 '@T6G_MB_LIB.T6G(SCH_1):PAGE178_I45@PURE_QUANTA.Q_CAP(CHIPS)':
 C_PATH='@t6g_mb_lib.t6g(sch_1):page178_i45@pure_quanta.q_cap(chips)',
 P_PATH='@t6g_mb_lib.t6g(sch_1):page203_i45@pure_quanta.q_cap(chips)',
 PATH='I45',
 DRAWING='@T6G_MB_LIB.T6G(SCH_1):PAGE178',
 TOLERANCE='20%',
 MATERIAL='X6S',
 PHYS_PAGE='203',
 XY='(5450,3125)',
 ROT='0',
 VER='1',
 PACK_TYPE='C0805',
 LOCATION='PC118_6',
 CDS_LIB='pure_quanta',
 CDS_PART_NAME='Q_CAP_C0805-22UF,16V,20%,X6S,CH6223MEA01',
 VOLTAGE='16V',
 PART_NUMBER='CH6223MEA01',
 VALUE='22UF',
 PRIM_FILE='./archive_libs/logical/q_cap/chips/chips.prt';

PART_NAME
 PC119 'Q_CAP_C0805-22UF,16V,20%,X6S,CH6223MEA01':;

SECTION_NUMBER 1
 '@T6G_MB_LIB.T6G(SCH_1):PAGE167_I12@PURE_QUANTA.Q_CAP(CHIPS)':
 C_PATH='@t6g_mb_lib.t6g(sch_1):page167_i12@pure_quanta.q_cap(chips)',
 P_PATH='@t6g_mb_lib.t6g(sch_1):page192_i12@pure_quanta.q_cap(chips)',
 PATH='I12',
 DRAWING='@T6G_MB_LIB.T6G(SCH_1):PAGE167',
 SEC_TYPE='C0805',
 TOLERANCE='20%',
 MATERIAL='X6S',
 PHYS_PAGE='192',
 XY='(-9025,4500)',
 ROT='0',
 VER='1',
 PACK_TYPE='C0805',
 LOCATION='PC119',
 SEC='1',
 CDS_LIB='pure_quanta',
 CDS_PART_NAME='Q_CAP_C0805-22UF,16V,20%,X6S,CH6223MEA01',
 VOLTAGE='16V',
 PART_NUMBER='CH6223MEA01',
 VALUE='22UF',
 PRIM_FILE='./archive_libs/logical/q_cap/chips/chips.prt';

PART_NAME
 PC119_4 'Q_CAP_C0805-22UF,16V,20%,X6S,CH6223MEA01':;

SECTION_NUMBER 1
 '@T6G_MB_LIB.T6G(SCH_1):PAGE177_I44@PURE_QUANTA.Q_CAP(CHIPS)':
 C_PATH='@t6g_mb_lib.t6g(sch_1):page177_i44@pure_quanta.q_cap(chips)',
 P_PATH='@t6g_mb_lib.t6g(sch_1):page202_i44@pure_quanta.q_cap(chips)',
 PATH='I44',
 DRAWING='@T6G_MB_LIB.T6G(SCH_1):PAGE177',
 TOLERANCE='20%',
 MATERIAL='X6S',
 PHYS_PAGE='202',
 XY='(4850,2425)',
 ROT='0',
 VER='1',
 PACK_TYPE='C0805',
 LOCATION='PC119_4',
 CDS_LIB='pure_quanta',
 CDS_PART_NAME='Q_CAP_C0805-22UF,16V,20%,X6S,CH6223MEA01',
 VOLTAGE='16V',
 PART_NUMBER='CH6223MEA01',
 VALUE='22UF',
 PRIM_FILE='./archive_libs/logical/q_cap/chips/chips.prt';

PART_NAME
 PC119_6 'Q_CAP_C0805-22UF,16V,20%,X6S,CH6223MEA01':;

SECTION_NUMBER 1
 '@T6G_MB_LIB.T6G(SCH_1):PAGE178_I47@PURE_QUANTA.Q_CAP(CHIPS)':
 C_PATH='@t6g_mb_lib.t6g(sch_1):page178_i47@pure_quanta.q_cap(chips)',
 P_PATH='@t6g_mb_lib.t6g(sch_1):page203_i47@pure_quanta.q_cap(chips)',
 PATH='I47',
 DRAWING='@T6G_MB_LIB.T6G(SCH_1):PAGE178',
 TOLERANCE='20%',
 MATERIAL='X6S',
 PHYS_PAGE='203',
 XY='(5825,3125)',
 ROT='0',
 VER='1',
 PACK_TYPE='C0805',
 LOCATION='PC119_6',
 CDS_LIB='pure_quanta',
 CDS_PART_NAME='Q_CAP_C0805-22UF,16V,20%,X6S,CH6223MEA01',
 VOLTAGE='16V',
 PART_NUMBER='CH6223MEA01',
 VALUE='22UF',
 PRIM_FILE='./archive_libs/logical/q_cap/chips/chips.prt';

PART_NAME
 PC120 'Q_CAP_C0805-22UF,16V,20%,X6S,CH6223MEA01':;

SECTION_NUMBER 1
 '@T6G_MB_LIB.T6G(SCH_1):PAGE167_I13@PURE_QUANTA.Q_CAP(CHIPS)':
 C_PATH='@t6g_mb_lib.t6g(sch_1):page167_i13@pure_quanta.q_cap(chips)',
 P_PATH='@t6g_mb_lib.t6g(sch_1):page192_i13@pure_quanta.q_cap(chips)',
 PATH='I13',
 DRAWING='@T6G_MB_LIB.T6G(SCH_1):PAGE167',
 SEC_TYPE='C0805',
 TOLERANCE='20%',
 MATERIAL='X6S',
 PHYS_PAGE='192',
 XY='(-8675,4475)',
 ROT='0',
 VER='1',
 PACK_TYPE='C0805',
 LOCATION='PC120',
 SEC='1',
 CDS_LIB='pure_quanta',
 CDS_PART_NAME='Q_CAP_C0805-22UF,16V,20%,X6S,CH6223MEA01',
 VOLTAGE='16V',
 PART_NUMBER='CH6223MEA01',
 VALUE='22UF',
 PRIM_FILE='./archive_libs/logical/q_cap/chips/chips.prt';

PART_NAME
 PC120_3 'Q_CAP_C0805-22UF,16V,20%,X6S,CH6223MEA01':;

SECTION_NUMBER 1
 '@T6G_MB_LIB.T6G(SCH_1):PAGE177_I61@PURE_QUANTA.Q_CAP(CHIPS)':
 C_PATH='@t6g_mb_lib.t6g(sch_1):page177_i61@pure_quanta.q_cap(chips)',
 P_PATH='@t6g_mb_lib.t6g(sch_1):page202_i61@pure_quanta.q_cap(chips)',
 PATH='I61',
 DRAWING='@T6G_MB_LIB.T6G(SCH_1):PAGE177',
 TOLERANCE='20%',
 MATERIAL='X6S',
 PHYS_PAGE='202',
 XY='(4900,5275)',
 ROT='0',
 VER='1',
 PACK_TYPE='C0805',
 LOCATION='PC120_3',
 CDS_LIB='pure_quanta',
 CDS_PART_NAME='Q_CAP_C0805-22UF,16V,20%,X6S,CH6223MEA01',
 VOLTAGE='16V',
 PART_NUMBER='CH6223MEA01',
 VALUE='22UF',
 PRIM_FILE='./archive_libs/logical/q_cap/chips/chips.prt';

PART_NAME
 PC120_6 'Q_CAP_C0805-22UF,4V,20%,X6S,CH622KMEA03':;

SECTION_NUMBER 1
 '@T6G_MB_LIB.T6G(SCH_1):PAGE178_I51@PURE_QUANTA.Q_CAP(CHIPS)':
 C_PATH='@t6g_mb_lib.t6g(sch_1):page178_i51@pure_quanta.q_cap(chips)',
 P_PATH='@t6g_mb_lib.t6g(sch_1):page203_i51@pure_quanta.q_cap(chips)',
 PATH='I51',
 DRAWING='@T6G_MB_LIB.T6G(SCH_1):PAGE178',
 TOLERANCE='20%',
 MATERIAL='X6S',
 PHYS_PAGE='203',
 XY='(7675,2025)',
 ROT='0',
 VER='1',
 PACK_TYPE='C0805',
 LOCATION='PC120_6',
 CDS_LIB='pure_quanta',
 CDS_PART_NAME='Q_CAP_C0805-22UF,4V,20%,X6S,CH622KMEA03',
 VOLTAGE='4V',
 PART_NUMBER='CH622KMEA03',
 VALUE='22UF',
 PRIM_FILE='./archive_libs/logical/q_cap/chips/chips.prt';

PART_NAME
 PC121 'Q_CAP_0402-0.22UF,16V,10%,X7R,CH4223K1B00':;

SECTION_NUMBER 1
 '@T6G_MB_LIB.T6G(SCH_1):PAGE177_I41@PURE_QUANTA.Q_CAP(CHIPS)':
 C_PATH='@t6g_mb_lib.t6g(sch_1):page177_i41@pure_quanta.q_cap(chips)',
 P_PATH='@t6g_mb_lib.t6g(sch_1):page202_i41@pure_quanta.q_cap(chips)',
 PATH='I41',
 DRAWING='@T6G_MB_LIB.T6G(SCH_1):PAGE177',
 TOLERANCE='10%',
 MATERIAL='X7R',
 PHYS_PAGE='202',
 XY='(5225,1750)',
 ROT='0',
 VER='1',
 PACK_TYPE='0402',
 LOCATION='PC121',
 CDS_LIB='pure_quanta',
 CDS_PART_NAME='Q_CAP_0402-0.22UF,16V,10%,X7R,CH4223K1B00',
 VOLTAGE='16V',
 PART_NUMBER='CH4223K1B00',
 VALUE='0.22UF',
 PRIM_FILE='./archive_libs/logical/q_cap/chips/chips.prt';

PART_NAME
 PC122 'Q_CAP_0402-0.22UF,16V,10%,X7R,CH4223K1B00':;

SECTION_NUMBER 1
 '@T6G_MB_LIB.T6G(SCH_1):PAGE177_I62@PURE_QUANTA.Q_CAP(CHIPS)':
 C_PATH='@t6g_mb_lib.t6g(sch_1):page177_i62@pure_quanta.q_cap(chips)',
 P_PATH='@t6g_mb_lib.t6g(sch_1):page202_i62@pure_quanta.q_cap(chips)',
 PATH='I62',
 DRAWING='@T6G_MB_LIB.T6G(SCH_1):PAGE177',
 TOLERANCE='10%',
 MATERIAL='X7R',
 PHYS_PAGE='202',
 XY='(5250,4575)',
 ROT='0',
 VER='1',
 PACK_TYPE='0402',
 LOCATION='PC122',
 CDS_LIB='pure_quanta',
 CDS_PART_NAME='Q_CAP_0402-0.22UF,16V,10%,X7R,CH4223K1B00',
 VOLTAGE='16V',
 PART_NUMBER='CH4223K1B00',
 VALUE='0.22UF',
 PRIM_FILE='./archive_libs/logical/q_cap/chips/chips.prt';

PART_NAME
 PC123 'Q_CAP_C0805-22UF,16V,20%,X6S,CH6223MEA01':;

SECTION_NUMBER 1
 '@T6G_MB_LIB.T6G(SCH_1):PAGE167_I29@PURE_QUANTA.Q_CAP(CHIPS)':
 C_PATH='@t6g_mb_lib.t6g(sch_1):page167_i29@pure_quanta.q_cap(chips)',
 P_PATH='@t6g_mb_lib.t6g(sch_1):page192_i29@pure_quanta.q_cap(chips)',
 PATH='I29',
 DRAWING='@T6G_MB_LIB.T6G(SCH_1):PAGE167',
 SEC_TYPE='C0805',
 TOLERANCE='20%',
 MATERIAL='X6S',
 PHYS_PAGE='192',
 XY='(-8275,4475)',
 ROT='0',
 VER='1',
 PACK_TYPE='C0805',
 LOCATION='PC123',
 SEC='1',
 CDS_LIB='pure_quanta',
 CDS_PART_NAME='Q_CAP_C0805-22UF,16V,20%,X6S,CH6223MEA01',
 VOLTAGE='16V',
 PART_NUMBER='CH6223MEA01',
 VALUE='22UF',
 PRIM_FILE='./archive_libs/logical/q_cap/chips/chips.prt';

PART_NAME
 PC123_4 'Q_CAP_C0805-22UF,16V,20%,X6S,CH6223MEA01':;

SECTION_NUMBER 1
 '@T6G_MB_LIB.T6G(SCH_1):PAGE177_I47@PURE_QUANTA.Q_CAP(CHIPS)':
 C_PATH='@t6g_mb_lib.t6g(sch_1):page177_i47@pure_quanta.q_cap(chips)',
 P_PATH='@t6g_mb_lib.t6g(sch_1):page202_i47@pure_quanta.q_cap(chips)',
 PATH='I47',
 DRAWING='@T6G_MB_LIB.T6G(SCH_1):PAGE177',
 TOLERANCE='20%',
 MATERIAL='X6S',
 PHYS_PAGE='202',
 XY='(5250,2425)',
 ROT='0',
 VER='1',
 PACK_TYPE='C0805',
 LOCATION='PC123_4',
 CDS_LIB='pure_quanta',
 CDS_PART_NAME='Q_CAP_C0805-22UF,16V,20%,X6S,CH6223MEA01',
 VOLTAGE='16V',
 PART_NUMBER='CH6223MEA01',
 VALUE='22UF',
 PRIM_FILE='./archive_libs/logical/q_cap/chips/chips.prt';

PART_NAME
 PC123_6 'Q_CAP_C0805-22UF,4V,20%,X6S,CH622KMEA03':;

SECTION_NUMBER 1
 '@T6G_MB_LIB.T6G(SCH_1):PAGE178_I53@PURE_QUANTA.Q_CAP(CHIPS)':
 C_PATH='@t6g_mb_lib.t6g(sch_1):page178_i53@pure_quanta.q_cap(chips)',
 P_PATH='@t6g_mb_lib.t6g(sch_1):page203_i53@pure_quanta.q_cap(chips)',
 PATH='I53',
 DRAWING='@T6G_MB_LIB.T6G(SCH_1):PAGE178',
 TOLERANCE='20%',
 MATERIAL='X6S',
 PHYS_PAGE='203',
 XY='(8100,2025)',
 ROT='0',
 VER='1',
 PACK_TYPE='C0805',
 LOCATION='PC123_6',
 CDS_LIB='pure_quanta',
 CDS_PART_NAME='Q_CAP_C0805-22UF,4V,20%,X6S,CH622KMEA03',
 VOLTAGE='4V',
 PART_NUMBER='CH622KMEA03',
 VALUE='22UF',
 PRIM_FILE='./archive_libs/logical/q_cap/chips/chips.prt';

PART_NAME
 PC124_3 'Q_CAP_C0805-22UF,16V,20%,X6S,CH6223MEA01':;

SECTION_NUMBER 1
 '@T6G_MB_LIB.T6G(SCH_1):PAGE177_I65@PURE_QUANTA.Q_CAP(CHIPS)':
 C_PATH='@t6g_mb_lib.t6g(sch_1):page177_i65@pure_quanta.q_cap(chips)',
 P_PATH='@t6g_mb_lib.t6g(sch_1):page202_i65@pure_quanta.q_cap(chips)',
 PATH='I65',
 DRAWING='@T6G_MB_LIB.T6G(SCH_1):PAGE177',
 TOLERANCE='20%',
 MATERIAL='X6S',
 PHYS_PAGE='202',
 XY='(5300,5275)',
 ROT='0',
 VER='1',
 PACK_TYPE='C0805',
 LOCATION='PC124_3',
 CDS_LIB='pure_quanta',
 CDS_PART_NAME='Q_CAP_C0805-22UF,16V,20%,X6S,CH6223MEA01',
 VOLTAGE='16V',
 PART_NUMBER='CH6223MEA01',
 VALUE='22UF',
 PRIM_FILE='./archive_libs/logical/q_cap/chips/chips.prt';

PART_NAME
 PC124_6 'Q_CAP_0402-0.1UF,25V,10%,X7R,CH4104K1B00':;

SECTION_NUMBER 1
 '@T6G_MB_LIB.T6G(SCH_1):PAGE188_I4@PURE_QUANTA.Q_CAP(CHIPS)':
 C_PATH='@t6g_mb_lib.t6g(sch_1):page188_i4@pure_quanta.q_cap(chips)',
 P_PATH='@t6g_mb_lib.t6g(sch_1):page213_i4@pure_quanta.q_cap(chips)',
 PATH='I4',
 DRAWING='@T6G_MB_LIB.T6G(SCH_1):PAGE188',
 TOLERANCE='10%',
 MATERIAL='X7R',
 PHYS_PAGE='213',
 XY='(-7475,1675)',
 ROT='0',
 VER='1',
 PACK_TYPE='0402',
 LOCATION='PC124_6',
 CDS_LIB='pure_quanta',
 CDS_PART_NAME='Q_CAP_0402-0.1UF,25V,10%,X7R,CH4104K1B00',
 VOLTAGE='25V',
 PART_NUMBER='CH4104K1B00',
 VALUE='0.1UF',
 PRIM_FILE='./archive_libs/logical/q_cap/chips/chips.prt';

PART_NAME
 PC125 'Q_CAP_C0402-2.2UF,10V,10%,X6S,CH5222KEB01':;

SECTION_NUMBER 1
 '@T6G_MB_LIB.T6G(SCH_1):PAGE188_I10@PURE_QUANTA.Q_CAP(CHIPS)':
 C_PATH='@t6g_mb_lib.t6g(sch_1):page188_i10@pure_quanta.q_cap(chips)',
 P_PATH='@t6g_mb_lib.t6g(sch_1):page213_i10@pure_quanta.q_cap(chips)',
 PATH='I10',
 DRAWING='@T6G_MB_LIB.T6G(SCH_1):PAGE188',
 TOLERANCE='10%',
 MATERIAL='X6S',
 PHYS_PAGE='213',
 XY='(-7150,2300)',
 ROT='0',
 VER='1',
 PACK_TYPE='C0402',
 LOCATION='PC125',
 CDS_LIB='pure_quanta',
 CDS_PART_NAME='Q_CAP_C0402-2.2UF,10V,10%,X6S,CH5222KEB01',
 VOLTAGE='10V',
 PART_NUMBER='CH5222KEB01',
 VALUE='2.2UF',
 PRIM_FILE='./archive_libs/logical/q_cap/chips/chips.prt';

PART_NAME
 PC125_4 'Q_CAP_C0805-22UF,16V,20%,X6S,CH6223MEA01':;

SECTION_NUMBER 1
 '@T6G_MB_LIB.T6G(SCH_1):PAGE177_I49@PURE_QUANTA.Q_CAP(CHIPS)':
 C_PATH='@t6g_mb_lib.t6g(sch_1):page177_i49@pure_quanta.q_cap(chips)',
 P_PATH='@t6g_mb_lib.t6g(sch_1):page202_i49@pure_quanta.q_cap(chips)',
 PATH='I49',
 DRAWING='@T6G_MB_LIB.T6G(SCH_1):PAGE177',
 TOLERANCE='20%',
 MATERIAL='X6S',
 PHYS_PAGE='202',
 XY='(5625,2425)',
 ROT='0',
 VER='1',
 PACK_TYPE='C0805',
 LOCATION='PC125_4',
 CDS_LIB='pure_quanta',
 CDS_PART_NAME='Q_CAP_C0805-22UF,16V,20%,X6S,CH6223MEA01',
 VOLTAGE='16V',
 PART_NUMBER='CH6223MEA01',
 VALUE='22UF',
 PRIM_FILE='./archive_libs/logical/q_cap/chips/chips.prt';

PART_NAME
 PC126 'Q_CAP_C0402-1UF,25V,10%,X6S,CH5104KEB02':;

SECTION_NUMBER 1
 '@T6G_MB_LIB.T6G(SCH_1):PAGE167_I30@PURE_QUANTA.Q_CAP(CHIPS)':
 C_PATH='@t6g_mb_lib.t6g(sch_1):page167_i30@pure_quanta.q_cap(chips)',
 P_PATH='@t6g_mb_lib.t6g(sch_1):page192_i30@pure_quanta.q_cap(chips)',
 PATH='I30',
 DRAWING='@T6G_MB_LIB.T6G(SCH_1):PAGE167',
 TOLERANCE='10%',
 MATERIAL='X6S',
 PHYS_PAGE='192',
 XY='(-7850,4475)',
 ROT='0',
 VER='1',
 PACK_TYPE='C0402',
 LOCATION='PC126',
 CDS_LIB='pure_quanta',
 CDS_PART_NAME='Q_CAP_C0402-1UF,25V,10%,X6S,CH5104KEB02',
 VOLTAGE='25V',
 PART_NUMBER='CH5104KEB02',
 VALUE='1UF',
 PRIM_FILE='./archive_libs/logical/q_cap/chips/chips.prt';

PART_NAME
 PC126_3 'Q_CAP_C0805-22UF,16V,20%,X6S,CH6223MEA01':;

SECTION_NUMBER 1
 '@T6G_MB_LIB.T6G(SCH_1):PAGE177_I66@PURE_QUANTA.Q_CAP(CHIPS)':
 C_PATH='@t6g_mb_lib.t6g(sch_1):page177_i66@pure_quanta.q_cap(chips)',
 P_PATH='@t6g_mb_lib.t6g(sch_1):page202_i66@pure_quanta.q_cap(chips)',
 PATH='I66',
 DRAWING='@T6G_MB_LIB.T6G(SCH_1):PAGE177',
 TOLERANCE='20%',
 MATERIAL='X6S',
 PHYS_PAGE='202',
 XY='(5675,5275)',
 ROT='0',
 VER='1',
 PACK_TYPE='C0805',
 LOCATION='PC126_3',
 CDS_LIB='pure_quanta',
 CDS_PART_NAME='Q_CAP_C0805-22UF,16V,20%,X6S,CH6223MEA01',
 VOLTAGE='16V',
 PART_NUMBER='CH6223MEA01',
 VALUE='22UF',
 PRIM_FILE='./archive_libs/logical/q_cap/chips/chips.prt';

PART_NAME
 PC126_C0P1_6 'Q_CAP_C0402-2.2UF,10V,10%,X6S,CH5222KEB01':;

SECTION_NUMBER 1
 '@T6G_MB_LIB.T6G(SCH_1):PAGE188_I15@PURE_QUANTA.Q_CAP(CHIPS)':
 C_PATH='@t6g_mb_lib.t6g(sch_1):page188_i15@pure_quanta.q_cap(chips)',
 P_PATH='@t6g_mb_lib.t6g(sch_1):page213_i15@pure_quanta.q_cap(chips)',
 PATH='I15',
 DRAWING='@T6G_MB_LIB.T6G(SCH_1):PAGE188',
 TOLERANCE='10%',
 MATERIAL='X6S',
 PHYS_PAGE='213',
 XY='(-6800,2875)',
 ROT='0',
 VER='1',
 PACK_TYPE='C0402',
 LOCATION='PC126_C0P1_6',
 CDS_LIB='pure_quanta',
 CDS_PART_NAME='Q_CAP_C0402-2.2UF,10V,10%,X6S,CH5222KEB01',
 VOLTAGE='10V',
 PART_NUMBER='CH5222KEB01',
 VALUE='2.2UF',
 PRIM_FILE='./archive_libs/logical/q_cap/chips/chips.prt';

PART_NAME
 PC127 'Q_CAP_0402-0.1UF,25V,10%,X7R,CH4104K1B00':;

SECTION_NUMBER 1
 '@T6G_MB_LIB.T6G(SCH_1):PAGE167_I19@PURE_QUANTA.Q_CAP(CHIPS)':
 C_PATH='@t6g_mb_lib.t6g(sch_1):page167_i19@pure_quanta.q_cap(chips)',
 P_PATH='@t6g_mb_lib.t6g(sch_1):page192_i19@pure_quanta.q_cap(chips)',
 PATH='I19',
 DRAWING='@T6G_MB_LIB.T6G(SCH_1):PAGE167',
 SEC_TYPE='0402',
 TOLERANCE='10%',
 MATERIAL='X7R',
 PHYS_PAGE='192',
 XY='(-6125,2750)',
 ROT='0',
 VER='1',
 PACK_TYPE='0402',
 LOCATION='PC127',
 SEC='1',
 CDS_LIB='pure_quanta',
 CDS_PART_NAME='Q_CAP_0402-0.1UF,25V,10%,X7R,CH4104K1B00',
 VOLTAGE='25V',
 PART_NUMBER='CH4104K1B00',
 VALUE='0.1UF',
 PRIM_FILE='./archive_libs/logical/q_cap/chips/chips.prt';

PART_NAME
 PC127_4 'Q_CAP_C0805-22UF,4V,20%,X6S,CH622KMEA03':;

SECTION_NUMBER 1
 '@T6G_MB_LIB.T6G(SCH_1):PAGE177_I54@PURE_QUANTA.Q_CAP(CHIPS)':
 C_PATH='@t6g_mb_lib.t6g(sch_1):page177_i54@pure_quanta.q_cap(chips)',
 P_PATH='@t6g_mb_lib.t6g(sch_1):page202_i54@pure_quanta.q_cap(chips)',
 PATH='I54',
 DRAWING='@T6G_MB_LIB.T6G(SCH_1):PAGE177',
 TOLERANCE='20%',
 MATERIAL='X6S',
 PHYS_PAGE='202',
 XY='(7500,1325)',
 ROT='0',
 VER='1',
 PACK_TYPE='C0805',
 LOCATION='PC127_4',
 CDS_LIB='pure_quanta',
 CDS_PART_NAME='Q_CAP_C0805-22UF,4V,20%,X6S,CH622KMEA03',
 VOLTAGE='4V',
 PART_NUMBER='CH622KMEA03',
 VALUE='22UF',
 PRIM_FILE='./archive_libs/logical/q_cap/chips/chips.prt';

PART_NAME
 PC127_6 'Q_CAP_0402-0.1UF,25V,10%,X7R,CH4104K1B00':;

SECTION_NUMBER 1
 '@T6G_MB_LIB.T6G(SCH_1):PAGE188_I25@PURE_QUANTA.Q_CAP(CHIPS)':
 C_PATH='@t6g_mb_lib.t6g(sch_1):page188_i25@pure_quanta.q_cap(chips)',
 P_PATH='@t6g_mb_lib.t6g(sch_1):page213_i25@pure_quanta.q_cap(chips)',
 PATH='I25',
 DRAWING='@T6G_MB_LIB.T6G(SCH_1):PAGE188',
 TOLERANCE='10%',
 MATERIAL='X7R',
 PHYS_PAGE='213',
 XY='(-4900,2825)',
 ROT='0',
 VER='1',
 PACK_TYPE='0402',
 LOCATION='PC127_6',
 CDS_LIB='pure_quanta',
 CDS_PART_NAME='Q_CAP_0402-0.1UF,25V,10%,X7R,CH4104K1B00',
 VOLTAGE='25V',
 PART_NUMBER='CH4104K1B00',
 VALUE='0.1UF',
 PRIM_FILE='./archive_libs/logical/q_cap/chips/chips.prt';

PART_NAME
 PC128 'Q_CAP_0402-0.1UF,25V,10%,X7R,CH4104K1B00':;

SECTION_NUMBER 1
 '@T6G_MB_LIB.T6G(SCH_1):PAGE167_I40@PURE_QUANTA.Q_CAP(CHIPS)':
 C_PATH='@t6g_mb_lib.t6g(sch_1):page167_i40@pure_quanta.q_cap(chips)',
 P_PATH='@t6g_mb_lib.t6g(sch_1):page192_i40@pure_quanta.q_cap(chips)',
 PATH='I40',
 DRAWING='@T6G_MB_LIB.T6G(SCH_1):PAGE167',
 SEC_TYPE='0402',
 TOLERANCE='10%',
 MATERIAL='X7R',
 PHYS_PAGE='192',
 XY='(-5425,3725)',
 ROT='0',
 VER='1',
 PACK_TYPE='0402',
 LOCATION='PC128',
 SEC='1',
 CDS_LIB='pure_quanta',
 CDS_PART_NAME='Q_CAP_0402-0.1UF,25V,10%,X7R,CH4104K1B00',
 VOLTAGE='25V',
 PART_NUMBER='CH4104K1B00',
 VALUE='0.1UF',
 PRIM_FILE='./archive_libs/logical/q_cap/chips/chips.prt';

PART_NAME
 PC128_4 'Q_CAP_C0805-22UF,4V,20%,X6S,CH622KMEA03':;

SECTION_NUMBER 1
 '@T6G_MB_LIB.T6G(SCH_1):PAGE177_I55@PURE_QUANTA.Q_CAP(CHIPS)':
 C_PATH='@t6g_mb_lib.t6g(sch_1):page177_i55@pure_quanta.q_cap(chips)',
 P_PATH='@t6g_mb_lib.t6g(sch_1):page202_i55@pure_quanta.q_cap(chips)',
 PATH='I55',
 DRAWING='@T6G_MB_LIB.T6G(SCH_1):PAGE177',
 TOLERANCE='20%',
 MATERIAL='X6S',
 PHYS_PAGE='202',
 XY='(7925,1325)',
 ROT='0',
 VER='1',
 PACK_TYPE='C0805',
 LOCATION='PC128_4',
 CDS_LIB='pure_quanta',
 CDS_PART_NAME='Q_CAP_C0805-22UF,4V,20%,X6S,CH622KMEA03',
 VOLTAGE='4V',
 PART_NUMBER='CH622KMEA03',
 VALUE='22UF',
 PRIM_FILE='./archive_libs/logical/q_cap/chips/chips.prt';

PART_NAME
 PC128_6 'Q_CAP_C0402-1UF,25V,10%,X6S,CH5104KEB02':;

SECTION_NUMBER 1
 '@T6G_MB_LIB.T6G(SCH_1):PAGE188_I27@PURE_QUANTA.Q_CAP(CHIPS)':
 C_PATH='@t6g_mb_lib.t6g(sch_1):page188_i27@pure_quanta.q_cap(chips)',
 P_PATH='@t6g_mb_lib.t6g(sch_1):page213_i27@pure_quanta.q_cap(chips)',
 PATH='I27',
 DRAWING='@T6G_MB_LIB.T6G(SCH_1):PAGE188',
 TOLERANCE='10%',
 MATERIAL='X6S',
 PHYS_PAGE='213',
 XY='(-4525,2825)',
 ROT='0',
 VER='1',
 PACK_TYPE='C0402',
 LOCATION='PC128_6',
 CDS_LIB='pure_quanta',
 CDS_PART_NAME='Q_CAP_C0402-1UF,25V,10%,X6S,CH5104KEB02',
 VOLTAGE='25V',
 PART_NUMBER='CH5104KEB02',
 VALUE='1UF',
 PRIM_FILE='./archive_libs/logical/q_cap/chips/chips.prt';

PART_NAME
 PC129 'Q_CAP_C0805-22UF,16V,20%,X6S,CH6223MEA01':;

SECTION_NUMBER 1
 '@T6G_MB_LIB.T6G(SCH_1):PAGE167_I27@PURE_QUANTA.Q_CAP(CHIPS)':
 C_PATH='@t6g_mb_lib.t6g(sch_1):page167_i27@pure_quanta.q_cap(chips)',
 P_PATH='@t6g_mb_lib.t6g(sch_1):page192_i27@pure_quanta.q_cap(chips)',
 PATH='I27',
 DRAWING='@T6G_MB_LIB.T6G(SCH_1):PAGE167',
 SEC_TYPE='C0805',
 TOLERANCE='20%',
 MATERIAL='X6S',
 PHYS_PAGE='192',
 XY='(-4575,3300)',
 ROT='0',
 VER='1',
 PACK_TYPE='C0805',
 LOCATION='PC129',
 SEC='1',
 CDS_LIB='pure_quanta',
 CDS_PART_NAME='Q_CAP_C0805-22UF,16V,20%,X6S,CH6223MEA01',
 VOLTAGE='16V',
 PART_NUMBER='CH6223MEA01',
 VALUE='22UF',
 PRIM_FILE='./archive_libs/logical/q_cap/chips/chips.prt';

PART_NAME
 PC129_3 'Q_CAP_C0805-22UF,4V,20%,X6S,CH622KMEA03':;

SECTION_NUMBER 1
 '@T6G_MB_LIB.T6G(SCH_1):PAGE177_I69@PURE_QUANTA.Q_CAP(CHIPS)':
 C_PATH='@t6g_mb_lib.t6g(sch_1):page177_i69@pure_quanta.q_cap(chips)',
 P_PATH='@t6g_mb_lib.t6g(sch_1):page202_i69@pure_quanta.q_cap(chips)',
 PATH='I69',
 DRAWING='@T6G_MB_LIB.T6G(SCH_1):PAGE177',
 TOLERANCE='20%',
 MATERIAL='X6S',
 PHYS_PAGE='202',
 XY='(7950,4150)',
 ROT='0',
 VER='1',
 PACK_TYPE='C0805',
 LOCATION='PC129_3',
 CDS_LIB='pure_quanta',
 CDS_PART_NAME='Q_CAP_C0805-22UF,4V,20%,X6S,CH622KMEA03',
 VOLTAGE='4V',
 PART_NUMBER='CH622KMEA03',
 VALUE='22UF',
 PRIM_FILE='./archive_libs/logical/q_cap/chips/chips.prt';

PART_NAME
 PC129_6 'Q_CAP_C0805-22UF,16V,20%,X6S,CH6223MEA01':;

SECTION_NUMBER 1
 '@T6G_MB_LIB.T6G(SCH_1):PAGE188_I29@PURE_QUANTA.Q_CAP(CHIPS)':
 C_PATH='@t6g_mb_lib.t6g(sch_1):page188_i29@pure_quanta.q_cap(chips)',
 P_PATH='@t6g_mb_lib.t6g(sch_1):page213_i29@pure_quanta.q_cap(chips)',
 PATH='I29',
 DRAWING='@T6G_MB_LIB.T6G(SCH_1):PAGE188',
 TOLERANCE='20%',
 MATERIAL='X6S',
 PHYS_PAGE='213',
 XY='(-4200,2825)',
 ROT='0',
 VER='1',
 PACK_TYPE='C0805',
 LOCATION='PC129_6',
 CDS_LIB='pure_quanta',
 CDS_PART_NAME='Q_CAP_C0805-22UF,16V,20%,X6S,CH6223MEA01',
 VOLTAGE='16V',
 PART_NUMBER='CH6223MEA01',
 VALUE='22UF',
 PRIM_FILE='./archive_libs/logical/q_cap/chips/chips.prt';

PART_NAME
 PC130 'Q_CAP_C0805-22UF,16V,20%,X6S,CH6223MEA01':;

SECTION_NUMBER 1
 '@T6G_MB_LIB.T6G(SCH_1):PAGE167_I28@PURE_QUANTA.Q_CAP(CHIPS)':
 C_PATH='@t6g_mb_lib.t6g(sch_1):page167_i28@pure_quanta.q_cap(chips)',
 P_PATH='@t6g_mb_lib.t6g(sch_1):page192_i28@pure_quanta.q_cap(chips)',
 PATH='I28',
 DRAWING='@T6G_MB_LIB.T6G(SCH_1):PAGE167',
 SEC_TYPE='C0805',
 TOLERANCE='20%',
 MATERIAL='X6S',
 PHYS_PAGE='192',
 XY='(-4275,3300)',
 ROT='0',
 VER='1',
 PACK_TYPE='C0805',
 LOCATION='PC130',
 SEC='1',
 CDS_LIB='pure_quanta',
 CDS_PART_NAME='Q_CAP_C0805-22UF,16V,20%,X6S,CH6223MEA01',
 VOLTAGE='16V',
 PART_NUMBER='CH6223MEA01',
 VALUE='22UF',
 PRIM_FILE='./archive_libs/logical/q_cap/chips/chips.prt';

PART_NAME
 PC130_3 'Q_CAP_C0805-22UF,4V,20%,X6S,CH622KMEA03':;

SECTION_NUMBER 1
 '@T6G_MB_LIB.T6G(SCH_1):PAGE177_I71@PURE_QUANTA.Q_CAP(CHIPS)':
 C_PATH='@t6g_mb_lib.t6g(sch_1):page177_i71@pure_quanta.q_cap(chips)',
 P_PATH='@t6g_mb_lib.t6g(sch_1):page202_i71@pure_quanta.q_cap(chips)',
 PATH='I71',
 DRAWING='@T6G_MB_LIB.T6G(SCH_1):PAGE177',
 TOLERANCE='20%',
 MATERIAL='X6S',
 PHYS_PAGE='202',
 XY='(8375,4150)',
 ROT='0',
 VER='1',
 PACK_TYPE='C0805',
 LOCATION='PC130_3',
 CDS_LIB='pure_quanta',
 CDS_PART_NAME='Q_CAP_C0805-22UF,4V,20%,X6S,CH622KMEA03',
 VOLTAGE='4V',
 PART_NUMBER='CH622KMEA03',
 VALUE='22UF',
 PRIM_FILE='./archive_libs/logical/q_cap/chips/chips.prt';

PART_NAME
 PC130_6 'Q_CAP_C0805-22UF,16V,20%,X6S,CH6223MEA01':;

SECTION_NUMBER 1
 '@T6G_MB_LIB.T6G(SCH_1):PAGE188_I30@PURE_QUANTA.Q_CAP(CHIPS)':
 C_PATH='@t6g_mb_lib.t6g(sch_1):page188_i30@pure_quanta.q_cap(chips)',
 P_PATH='@t6g_mb_lib.t6g(sch_1):page213_i30@pure_quanta.q_cap(chips)',
 PATH='I30',
 DRAWING='@T6G_MB_LIB.T6G(SCH_1):PAGE188',
 TOLERANCE='20%',
 MATERIAL='X6S',
 PHYS_PAGE='213',
 XY='(-3875,2825)',
 ROT='0',
 VER='1',
 PACK_TYPE='C0805',
 LOCATION='PC130_6',
 CDS_LIB='pure_quanta',
 CDS_PART_NAME='Q_CAP_C0805-22UF,16V,20%,X6S,CH6223MEA01',
 VOLTAGE='16V',
 PART_NUMBER='CH6223MEA01',
 VALUE='22UF',
 PRIM_FILE='./archive_libs/logical/q_cap/chips/chips.prt';

PART_NAME
 PC131 'Q_CAP_C0402-2.2UF,10V,10%,X6S,CH5222KEB01':;

SECTION_NUMBER 1
 '@T6G_MB_LIB.T6G(SCH_1):PAGE178_I27@PURE_QUANTA.Q_CAP(CHIPS)':
 C_PATH='@t6g_mb_lib.t6g(sch_1):page178_i27@pure_quanta.q_cap(chips)',
 P_PATH='@t6g_mb_lib.t6g(sch_1):page203_i27@pure_quanta.q_cap(chips)',
 PATH='I27',
 DRAWING='@T6G_MB_LIB.T6G(SCH_1):PAGE178',
 TOLERANCE='10%',
 MATERIAL='X6S',
 PHYS_PAGE='203',
 XY='(1925,5300)',
 ROT='0',
 VER='1',
 PACK_TYPE='C0402',
 LOCATION='PC131',
 CDS_LIB='pure_quanta',
 CDS_PART_NAME='Q_CAP_C0402-2.2UF,10V,10%,X6S,CH5222KEB01',
 VOLTAGE='10V',
 PART_NUMBER='CH5222KEB01',
 VALUE='2.2UF',
 PRIM_FILE='./archive_libs/logical/q_cap/chips/chips.prt';

PART_NAME
 PC132 'Q_CAP_0402-100PF,50V,5%,NPO,CH11006JB00':;

SECTION_NUMBER 1
 '@T6G_MB_LIB.T6G(SCH_1):PAGE167_I24@PURE_QUANTA.Q_CAP(CHIPS)':
 C_PATH='@t6g_mb_lib.t6g(sch_1):page167_i24@pure_quanta.q_cap(chips)',
 P_PATH='@t6g_mb_lib.t6g(sch_1):page192_i24@pure_quanta.q_cap(chips)',
 PATH='I24',
 DRAWING='@T6G_MB_LIB.T6G(SCH_1):PAGE167',
 SEC_TYPE='0402',
 TOLERANCE='5%',
 MATERIAL='NPO',
 PHYS_PAGE='192',
 XY='(-4225,2250)',
 ROT='1',
 VER='1',
 PACK_TYPE='0402',
 LOCATION='PC132',
 SEC='1',
 CDS_LIB='pure_quanta',
 CDS_PART_NAME='Q_CAP_0402-100PF,50V,5%,NPO,CH11006JB00',
 VOLTAGE='50V',
 PART_NUMBER='CH11006JB00',
 VALUE='100PF',
 PRIM_FILE='./archive_libs/logical/q_cap/chips/chips.prt';

PART_NAME
 PC132_5 'Q_CAP_0402-0.1UF,25V,10%,X7R,CH4104K1B00':;

SECTION_NUMBER 1
 '@T6G_MB_LIB.T6G(SCH_1):PAGE178_I10@PURE_QUANTA.Q_CAP(CHIPS)':
 C_PATH='@t6g_mb_lib.t6g(sch_1):page178_i10@pure_quanta.q_cap(chips)',
 P_PATH='@t6g_mb_lib.t6g(sch_1):page203_i10@pure_quanta.q_cap(chips)',
 PATH='I10',
 DRAWING='@T6G_MB_LIB.T6G(SCH_1):PAGE178',
 TOLERANCE='10%',
 MATERIAL='X7R',
 PHYS_PAGE='203',
 XY='(975,4500)',
 ROT='0',
 VER='1',
 PACK_TYPE='0402',
 LOCATION='PC132_5',
 CDS_LIB='pure_quanta',
 CDS_PART_NAME='Q_CAP_0402-0.1UF,25V,10%,X7R,CH4104K1B00',
 VOLTAGE='25V',
 PART_NUMBER='CH4104K1B00',
 VALUE='0.1UF',
 PRIM_FILE='./archive_libs/logical/q_cap/chips/chips.prt';

PART_NAME
 PC132_6 'Q_CAP_C0805-22UF,16V,20%,X6S,CH6223MEA01':;

SECTION_NUMBER 1
 '@T6G_MB_LIB.T6G(SCH_1):PAGE188_I55@PURE_QUANTA.Q_CAP(CHIPS)':
 C_PATH='@t6g_mb_lib.t6g(sch_1):page188_i55@pure_quanta.q_cap(chips)',
 P_PATH='@t6g_mb_lib.t6g(sch_1):page213_i55@pure_quanta.q_cap(chips)',
 PATH='I55',
 DRAWING='@T6G_MB_LIB.T6G(SCH_1):PAGE188',
 TOLERANCE='20%',
 MATERIAL='X6S',
 PHYS_PAGE='213',
 XY='(-3575,2825)',
 ROT='0',
 VER='1',
 PACK_TYPE='C0805',
 LOCATION='PC132_6',
 CDS_LIB='pure_quanta',
 CDS_PART_NAME='Q_CAP_C0805-22UF,16V,20%,X6S,CH6223MEA01',
 VOLTAGE='16V',
 PART_NUMBER='CH6223MEA01',
 VALUE='22UF',
 PRIM_FILE='./archive_libs/logical/q_cap/chips/chips.prt';

PART_NAME
 PC133 'Q_CAP_0402-0.22UF,16V,10%,X7R,CH4223K1B00':;

SECTION_NUMBER 1
 '@T6G_MB_LIB.T6G(SCH_1):PAGE188_I52@PURE_QUANTA.Q_CAP(CHIPS)':
 C_PATH='@t6g_mb_lib.t6g(sch_1):page188_i52@pure_quanta.q_cap(chips)',
 P_PATH='@t6g_mb_lib.t6g(sch_1):page213_i52@pure_quanta.q_cap(chips)',
 PATH='I52',
 DRAWING='@T6G_MB_LIB.T6G(SCH_1):PAGE188',
 TOLERANCE='10%',
 MATERIAL='X7R',
 PHYS_PAGE='213',
 XY='(-3275,2175)',
 ROT='0',
 VER='1',
 PACK_TYPE='0402',
 LOCATION='PC133',
 CDS_LIB='pure_quanta',
 CDS_PART_NAME='Q_CAP_0402-0.22UF,16V,10%,X7R,CH4223K1B00',
 VOLTAGE='16V',
 PART_NUMBER='CH4223K1B00',
 VALUE='0.22UF',
 PRIM_FILE='./archive_libs/logical/q_cap/chips/chips.prt';

PART_NAME
 PC133_C1P0_5 'Q_CAP_C0402-2.2UF,10V,10%,X6S,CH5222KEB01':;

SECTION_NUMBER 1
 '@T6G_MB_LIB.T6G(SCH_1):PAGE178_I31@PURE_QUANTA.Q_CAP(CHIPS)':
 C_PATH='@t6g_mb_lib.t6g(sch_1):page178_i31@pure_quanta.q_cap(chips)',
 P_PATH='@t6g_mb_lib.t6g(sch_1):page203_i31@pure_quanta.q_cap(chips)',
 PATH='I31',
 DRAWING='@T6G_MB_LIB.T6G(SCH_1):PAGE178',
 TOLERANCE='10%',
 MATERIAL='X6S',
 PHYS_PAGE='203',
 XY='(2275,5875)',
 ROT='0',
 VER='1',
 PACK_TYPE='C0402',
 LOCATION='PC133_C1P0_5',
 CDS_LIB='pure_quanta',
 CDS_PART_NAME='Q_CAP_C0402-2.2UF,10V,10%,X6S,CH5222KEB01',
 VOLTAGE='10V',
 PART_NUMBER='CH5222KEB01',
 VALUE='2.2UF',
 PRIM_FILE='./archive_libs/logical/q_cap/chips/chips.prt';

PART_NAME
 PC134 'Q_CAP_C0805-22UF,16V,20%,X6S,CH6223MEA01':;

SECTION_NUMBER 1
 '@T6G_MB_LIB.T6G(SCH_1):PAGE167_I35@PURE_QUANTA.Q_CAP(CHIPS)':
 C_PATH='@t6g_mb_lib.t6g(sch_1):page167_i35@pure_quanta.q_cap(chips)',
 P_PATH='@t6g_mb_lib.t6g(sch_1):page192_i35@pure_quanta.q_cap(chips)',
 PATH='I35',
 DRAWING='@T6G_MB_LIB.T6G(SCH_1):PAGE167',
 SEC_TYPE='C0805',
 TOLERANCE='20%',
 MATERIAL='X6S',
 PHYS_PAGE='192',
 XY='(-3975,3300)',
 ROT='0',
 VER='1',
 PACK_TYPE='C0805',
 LOCATION='PC134',
 SEC='1',
 CDS_LIB='pure_quanta',
 CDS_PART_NAME='Q_CAP_C0805-22UF,16V,20%,X6S,CH6223MEA01',
 VOLTAGE='16V',
 PART_NUMBER='CH6223MEA01',
 VALUE='22UF',
 PRIM_FILE='./archive_libs/logical/q_cap/chips/chips.prt';

PART_NAME
 PC134_5 'Q_CAP_0402-0.1UF,25V,10%,X7R,CH4104K1B00':;

SECTION_NUMBER 1
 '@T6G_MB_LIB.T6G(SCH_1):PAGE178_I58@PURE_QUANTA.Q_CAP(CHIPS)':
 C_PATH='@t6g_mb_lib.t6g(sch_1):page178_i58@pure_quanta.q_cap(chips)',
 P_PATH='@t6g_mb_lib.t6g(sch_1):page203_i58@pure_quanta.q_cap(chips)',
 PATH='I58',
 DRAWING='@T6G_MB_LIB.T6G(SCH_1):PAGE178',
 TOLERANCE='10%',
 MATERIAL='X7R',
 PHYS_PAGE='203',
 XY='(4250,5775)',
 ROT='0',
 VER='1',
 PACK_TYPE='0402',
 LOCATION='PC134_5',
 CDS_LIB='pure_quanta',
 CDS_PART_NAME='Q_CAP_0402-0.1UF,25V,10%,X7R,CH4104K1B00',
 VOLTAGE='25V',
 PART_NUMBER='CH4104K1B00',
 VALUE='0.1UF',
 PRIM_FILE='./archive_libs/logical/q_cap/chips/chips.prt';

PART_NAME
 PC134_6 'Q_CAP_C0805-22UF,4V,20%,X6S,CH622KMEA03':;

SECTION_NUMBER 1
 '@T6G_MB_LIB.T6G(SCH_1):PAGE188_I58@PURE_QUANTA.Q_CAP(CHIPS)':
 C_PATH='@t6g_mb_lib.t6g(sch_1):page188_i58@pure_quanta.q_cap(chips)',
 P_PATH='@t6g_mb_lib.t6g(sch_1):page213_i58@pure_quanta.q_cap(chips)',
 PATH='I58',
 DRAWING='@T6G_MB_LIB.T6G(SCH_1):PAGE188',
 TOLERANCE='20%',
 MATERIAL='X6S',
 PHYS_PAGE='213',
 XY='(-1125,1775)',
 ROT='0',
 VER='1',
 PACK_TYPE='C0805',
 LOCATION='PC134_6',
 CDS_LIB='pure_quanta',
 CDS_PART_NAME='Q_CAP_C0805-22UF,4V,20%,X6S,CH622KMEA03',
 VOLTAGE='4V',
 PART_NUMBER='CH622KMEA03',
 VALUE='22UF',
 PRIM_FILE='./archive_libs/logical/q_cap/chips/chips.prt';

PART_NAME
 PC135 'Q_CAP_C0805-22UF,16V,20%,X6S,CH6223MEA01':;

SECTION_NUMBER 1
 '@T6G_MB_LIB.T6G(SCH_1):PAGE167_I36@PURE_QUANTA.Q_CAP(CHIPS)':
 C_PATH='@t6g_mb_lib.t6g(sch_1):page167_i36@pure_quanta.q_cap(chips)',
 P_PATH='@t6g_mb_lib.t6g(sch_1):page192_i36@pure_quanta.q_cap(chips)',
 PATH='I36',
 DRAWING='@T6G_MB_LIB.T6G(SCH_1):PAGE167',
 SEC_TYPE='C0805',
 TOLERANCE='20%',
 MATERIAL='X6S',
 PHYS_PAGE='192',
 XY='(-3675,3300)',
 ROT='0',
 VER='1',
 PACK_TYPE='C0805',
 LOCATION='PC135',
 SEC='1',
 CDS_LIB='pure_quanta',
 CDS_PART_NAME='Q_CAP_C0805-22UF,16V,20%,X6S,CH6223MEA01',
 VOLTAGE='16V',
 PART_NUMBER='CH6223MEA01',
 VALUE='22UF',
 PRIM_FILE='./archive_libs/logical/q_cap/chips/chips.prt';

PART_NAME
 PC135_5 'Q_CAP_C0402-1UF,25V,10%,X6S,CH5104KEB02':;

SECTION_NUMBER 1
 '@T6G_MB_LIB.T6G(SCH_1):PAGE178_I59@PURE_QUANTA.Q_CAP(CHIPS)':
 C_PATH='@t6g_mb_lib.t6g(sch_1):page178_i59@pure_quanta.q_cap(chips)',
 P_PATH='@t6g_mb_lib.t6g(sch_1):page203_i59@pure_quanta.q_cap(chips)',
 PATH='I59',
 DRAWING='@T6G_MB_LIB.T6G(SCH_1):PAGE178',
 TOLERANCE='10%',
 MATERIAL='X6S',
 PHYS_PAGE='203',
 XY='(4675,5775)',
 ROT='0',
 VER='1',
 PACK_TYPE='C0402',
 LOCATION='PC135_5',
 CDS_LIB='pure_quanta',
 CDS_PART_NAME='Q_CAP_C0402-1UF,25V,10%,X6S,CH5104KEB02',
 VOLTAGE='25V',
 PART_NUMBER='CH5104KEB02',
 VALUE='1UF',
 PRIM_FILE='./archive_libs/logical/q_cap/chips/chips.prt';

PART_NAME
 PC135_6 'Q_CAP_C0805-22UF,4V,20%,X6S,CH622KMEA03':;

SECTION_NUMBER 1
 '@T6G_MB_LIB.T6G(SCH_1):PAGE188_I60@PURE_QUANTA.Q_CAP(CHIPS)':
 C_PATH='@t6g_mb_lib.t6g(sch_1):page188_i60@pure_quanta.q_cap(chips)',
 P_PATH='@t6g_mb_lib.t6g(sch_1):page213_i60@pure_quanta.q_cap(chips)',
 PATH='I60',
 DRAWING='@T6G_MB_LIB.T6G(SCH_1):PAGE188',
 TOLERANCE='20%',
 MATERIAL='X6S',
 PHYS_PAGE='213',
 XY='(-700,1775)',
 ROT='0',
 VER='1',
 PACK_TYPE='C0805',
 LOCATION='PC135_6',
 CDS_LIB='pure_quanta',
 CDS_PART_NAME='Q_CAP_C0805-22UF,4V,20%,X6S,CH622KMEA03',
 VOLTAGE='4V',
 PART_NUMBER='CH622KMEA03',
 VALUE='22UF',
 PRIM_FILE='./archive_libs/logical/q_cap/chips/chips.prt';

PART_NAME
 PC136 'Q_CAP_0402-0.1UF,25V,10%,X7R,CH4104K1B00':;

SECTION_NUMBER 1
 '@T6G_MB_LIB.T6G(SCH_1):PAGE167_I37@PURE_QUANTA.Q_CAP(CHIPS)':
 C_PATH='@t6g_mb_lib.t6g(sch_1):page167_i37@pure_quanta.q_cap(chips)',
 P_PATH='@t6g_mb_lib.t6g(sch_1):page192_i37@pure_quanta.q_cap(chips)',
 PATH='I37',
 DRAWING='@T6G_MB_LIB.T6G(SCH_1):PAGE167',
 SEC_TYPE='0402',
 TOLERANCE='10%',
 MATERIAL='X7R',
 PHYS_PAGE='192',
 XY='(-3275,3300)',
 ROT='0',
 VER='1',
 PACK_TYPE='0402',
 LOCATION='PC136',
 SEC='1',
 CDS_LIB='pure_quanta',
 CDS_PART_NAME='Q_CAP_0402-0.1UF,25V,10%,X7R,CH4104K1B00',
 VOLTAGE='25V',
 PART_NUMBER='CH4104K1B00',
 VALUE='0.1UF',
 PRIM_FILE='./archive_libs/logical/q_cap/chips/chips.prt';

PART_NAME
 PC136_5 'Q_CAP_C0805-22UF,16V,20%,X6S,CH6223MEA01':;

SECTION_NUMBER 1
 '@T6G_MB_LIB.T6G(SCH_1):PAGE178_I60@PURE_QUANTA.Q_CAP(CHIPS)':
 C_PATH='@t6g_mb_lib.t6g(sch_1):page178_i60@pure_quanta.q_cap(chips)',
 P_PATH='@t6g_mb_lib.t6g(sch_1):page203_i60@pure_quanta.q_cap(chips)',
 PATH='I60',
 DRAWING='@T6G_MB_LIB.T6G(SCH_1):PAGE178',
 TOLERANCE='20%',
 MATERIAL='X6S',
 PHYS_PAGE='203',
 XY='(5075,5775)',
 ROT='0',
 VER='1',
 PACK_TYPE='C0805',
 LOCATION='PC136_5',
 CDS_LIB='pure_quanta',
 CDS_PART_NAME='Q_CAP_C0805-22UF,16V,20%,X6S,CH6223MEA01',
 VOLTAGE='16V',
 PART_NUMBER='CH6223MEA01',
 VALUE='22UF',
 PRIM_FILE='./archive_libs/logical/q_cap/chips/chips.prt';

PART_NAME
 PC136_6 'Q_CAP_0402-0.1UF,25V,10%,X7R,CH4104K1B00':;

SECTION_NUMBER 1
 '@T6G_MB_LIB.T6G(SCH_1):PAGE195_I1@PURE_QUANTA.Q_CAP(CHIPS)':
 C_PATH='@t6g_mb_lib.t6g(sch_1):page195_i1@pure_quanta.q_cap(chips)',
 P_PATH='@t6g_mb_lib.t6g(sch_1):page220_i1@pure_quanta.q_cap(chips)',
 PATH='I1',
 DRAWING='@T6G_MB_LIB.T6G(SCH_1):PAGE195',
 TOLERANCE='10%',
 MATERIAL='X7R',
 PHYS_PAGE='220',
 XY='(775,1850)',
 ROT='0',
 VER='1',
 PACK_TYPE='0402',
 LOCATION='PC136_6',
 CDS_LIB='pure_quanta',
 CDS_PART_NAME='Q_CAP_0402-0.1UF,25V,10%,X7R,CH4104K1B00',
 VOLTAGE='25V',
 PART_NUMBER='CH4104K1B00',
 VALUE='0.1UF',
 PRIM_FILE='./archive_libs/logical/q_cap/chips/chips.prt';

PART_NAME
 PC137 'Q_CAP_0402-0.22UF,16V,10%,X7R,CH4223K1B00':;

SECTION_NUMBER 1
 '@T6G_MB_LIB.T6G(SCH_1):PAGE178_I62@PURE_QUANTA.Q_CAP(CHIPS)':
 C_PATH='@t6g_mb_lib.t6g(sch_1):page178_i62@pure_quanta.q_cap(chips)',
 P_PATH='@t6g_mb_lib.t6g(sch_1):page203_i62@pure_quanta.q_cap(chips)',
 PATH='I62',
 DRAWING='@T6G_MB_LIB.T6G(SCH_1):PAGE178',
 TOLERANCE='10%',
 MATERIAL='X7R',
 PHYS_PAGE='203',
 XY='(5375,5100)',
 ROT='0',
 VER='1',
 PACK_TYPE='0402',
 LOCATION='PC137',
 CDS_LIB='pure_quanta',
 CDS_PART_NAME='Q_CAP_0402-0.22UF,16V,10%,X7R,CH4223K1B00',
 VOLTAGE='16V',
 PART_NUMBER='CH4223K1B00',
 VALUE='0.22UF',
 PRIM_FILE='./archive_libs/logical/q_cap/chips/chips.prt';

PART_NAME
 PC138 'Q_CAP_C0402-2.2UF,10V,10%,X6S,CH5222KEB01':;

SECTION_NUMBER 1
 '@T6G_MB_LIB.T6G(SCH_1):PAGE195_I12@PURE_QUANTA.Q_CAP(CHIPS)':
 C_PATH='@t6g_mb_lib.t6g(sch_1):page195_i12@pure_quanta.q_cap(chips)',
 P_PATH='@t6g_mb_lib.t6g(sch_1):page220_i12@pure_quanta.q_cap(chips)',
 PATH='I12',
 DRAWING='@T6G_MB_LIB.T6G(SCH_1):PAGE195',
 TOLERANCE='10%',
 MATERIAL='X6S',
 PHYS_PAGE='220',
 XY='(1725,2650)',
 ROT='0',
 VER='1',
 PACK_TYPE='C0402',
 LOCATION='PC138',
 CDS_LIB='pure_quanta',
 CDS_PART_NAME='Q_CAP_C0402-2.2UF,10V,10%,X6S,CH5222KEB01',
 VOLTAGE='10V',
 PART_NUMBER='CH5222KEB01',
 VALUE='2.2UF',
 PRIM_FILE='./archive_libs/logical/q_cap/chips/chips.prt';

PART_NAME
 PC138_5 'Q_CAP_C0805-22UF,16V,20%,X6S,CH6223MEA01':;

SECTION_NUMBER 1
 '@T6G_MB_LIB.T6G(SCH_1):PAGE178_I65@PURE_QUANTA.Q_CAP(CHIPS)':
 C_PATH='@t6g_mb_lib.t6g(sch_1):page178_i65@pure_quanta.q_cap(chips)',
 P_PATH='@t6g_mb_lib.t6g(sch_1):page203_i65@pure_quanta.q_cap(chips)',
 PATH='I65',
 DRAWING='@T6G_MB_LIB.T6G(SCH_1):PAGE178',
 TOLERANCE='20%',
 MATERIAL='X6S',
 PHYS_PAGE='203',
 XY='(5475,5775)',
 ROT='0',
 VER='1',
 PACK_TYPE='C0805',
 LOCATION='PC138_5',
 CDS_LIB='pure_quanta',
 CDS_PART_NAME='Q_CAP_C0805-22UF,16V,20%,X6S,CH6223MEA01',
 VOLTAGE='16V',
 PART_NUMBER='CH6223MEA01',
 VALUE='22UF',
 PRIM_FILE='./archive_libs/logical/q_cap/chips/chips.prt';

PART_NAME
 PC139_5 'Q_CAP_C0805-22UF,16V,20%,X6S,CH6223MEA01':;

SECTION_NUMBER 1
 '@T6G_MB_LIB.T6G(SCH_1):PAGE178_I66@PURE_QUANTA.Q_CAP(CHIPS)':
 C_PATH='@t6g_mb_lib.t6g(sch_1):page178_i66@pure_quanta.q_cap(chips)',
 P_PATH='@t6g_mb_lib.t6g(sch_1):page203_i66@pure_quanta.q_cap(chips)',
 PATH='I66',
 DRAWING='@T6G_MB_LIB.T6G(SCH_1):PAGE178',
 TOLERANCE='20%',
 MATERIAL='X6S',
 PHYS_PAGE='203',
 XY='(5850,5775)',
 ROT='0',
 VER='1',
 PACK_TYPE='C0805',
 LOCATION='PC139_5',
 CDS_LIB='pure_quanta',
 CDS_PART_NAME='Q_CAP_C0805-22UF,16V,20%,X6S,CH6223MEA01',
 VOLTAGE='16V',
 PART_NUMBER='CH6223MEA01',
 VALUE='22UF',
 PRIM_FILE='./archive_libs/logical/q_cap/chips/chips.prt';

PART_NAME
 PC139_C1P1_6 'Q_CAP_C0402-2.2UF,10V,10%,X6S,CH5222KEB01':;

SECTION_NUMBER 1
 '@T6G_MB_LIB.T6G(SCH_1):PAGE195_I22@PURE_QUANTA.Q_CAP(CHIPS)':
 C_PATH='@t6g_mb_lib.t6g(sch_1):page195_i22@pure_quanta.q_cap(chips)',
 P_PATH='@t6g_mb_lib.t6g(sch_1):page220_i22@pure_quanta.q_cap(chips)',
 PATH='I22',
 DRAWING='@T6G_MB_LIB.T6G(SCH_1):PAGE195',
 TOLERANCE='10%',
 MATERIAL='X6S',
 PHYS_PAGE='220',
 XY='(2075,3225)',
 ROT='0',
 VER='1',
 PACK_TYPE='C0402',
 LOCATION='PC139_C1P1_6',
 CDS_LIB='pure_quanta',
 CDS_PART_NAME='Q_CAP_C0402-2.2UF,10V,10%,X6S,CH5222KEB01',
 VOLTAGE='10V',
 PART_NUMBER='CH5222KEB01',
 VALUE='2.2UF',
 PRIM_FILE='./archive_libs/logical/q_cap/chips/chips.prt';

PART_NAME
 PC140_5 'Q_CAP_C0805-22UF,4V,20%,X6S,CH622KMEA03':;

SECTION_NUMBER 1
 '@T6G_MB_LIB.T6G(SCH_1):PAGE178_I69@PURE_QUANTA.Q_CAP(CHIPS)':
 C_PATH='@t6g_mb_lib.t6g(sch_1):page178_i69@pure_quanta.q_cap(chips)',
 P_PATH='@t6g_mb_lib.t6g(sch_1):page203_i69@pure_quanta.q_cap(chips)',
 PATH='I69',
 DRAWING='@T6G_MB_LIB.T6G(SCH_1):PAGE178',
 TOLERANCE='20%',
 MATERIAL='X6S',
 PHYS_PAGE='203',
 XY='(7700,4675)',
 ROT='0',
 VER='1',
 PACK_TYPE='C0805',
 LOCATION='PC140_5',
 CDS_LIB='pure_quanta',
 CDS_PART_NAME='Q_CAP_C0805-22UF,4V,20%,X6S,CH622KMEA03',
 VOLTAGE='4V',
 PART_NUMBER='CH622KMEA03',
 VALUE='22UF',
 PRIM_FILE='./archive_libs/logical/q_cap/chips/chips.prt';

PART_NAME
 PC140_6 'Q_CAP_C0402-1UF,25V,10%,X6S,CH5104KEB02':;

SECTION_NUMBER 1
 '@T6G_MB_LIB.T6G(SCH_1):PAGE195_I40@PURE_QUANTA.Q_CAP(CHIPS)':
 C_PATH='@t6g_mb_lib.t6g(sch_1):page195_i40@pure_quanta.q_cap(chips)',
 P_PATH='@t6g_mb_lib.t6g(sch_1):page220_i40@pure_quanta.q_cap(chips)',
 PATH='I40',
 DRAWING='@T6G_MB_LIB.T6G(SCH_1):PAGE195',
 TOLERANCE='10%',
 MATERIAL='X6S',
 PHYS_PAGE='220',
 XY='(4475,3125)',
 ROT='0',
 VER='1',
 PACK_TYPE='C0402',
 LOCATION='PC140_6',
 CDS_LIB='pure_quanta',
 CDS_PART_NAME='Q_CAP_C0402-1UF,25V,10%,X6S,CH5104KEB02',
 VOLTAGE='25V',
 PART_NUMBER='CH5104KEB02',
 VALUE='1UF',
 PRIM_FILE='./archive_libs/logical/q_cap/chips/chips.prt';

PART_NAME
 PC141 'Q_CAP_C0402-560PF,50V,10%,EMPTY,CH1566K1B09':;

SECTION_NUMBER 1
 '@T6G_MB_LIB.T6G(SCH_1):PAGE190_I45@PURE_QUANTA.Q_CAP(CHIPS)':
 C_PATH='@t6g_mb_lib.t6g(sch_1):page190_i45@pure_quanta.q_cap(chips)',
 P_PATH='@t6g_mb_lib.t6g(sch_1):page215_i45@pure_quanta.q_cap(chips)',
 PATH='I45',
 DRAWING='@T6G_MB_LIB.T6G(SCH_1):PAGE190',
 TOLERANCE='10%',
 MATERIAL='EMPTY',
 PHYS_PAGE='215',
 XY='(-4700,4550)',
 ROT='0',
 VER='1',
 PACK_TYPE='C0402',
 LOCATION='PC141',
 CDS_LIB='pure_quanta',
 CDS_PART_NAME='Q_CAP_C0402-560PF,50V,10%,EMPTY,CH1566K1B09',
 VOLTAGE='50V',
 PART_NUMBER='CH1566K1B09',
 VALUE='560PF',
 PRIM_FILE='./archive_libs/logical/q_cap/chips/chips.prt';

PART_NAME
 PC141_5 'Q_CAP_C0805-22UF,4V,20%,X6S,CH622KMEA03':;

SECTION_NUMBER 1
 '@T6G_MB_LIB.T6G(SCH_1):PAGE178_I70@PURE_QUANTA.Q_CAP(CHIPS)':
 C_PATH='@t6g_mb_lib.t6g(sch_1):page178_i70@pure_quanta.q_cap(chips)',
 P_PATH='@t6g_mb_lib.t6g(sch_1):page203_i70@pure_quanta.q_cap(chips)',
 PATH='I70',
 DRAWING='@T6G_MB_LIB.T6G(SCH_1):PAGE178',
 TOLERANCE='20%',
 MATERIAL='X6S',
 PHYS_PAGE='203',
 XY='(8125,4675)',
 ROT='0',
 VER='1',
 PACK_TYPE='C0805',
 LOCATION='PC141_5',
 CDS_LIB='pure_quanta',
 CDS_PART_NAME='Q_CAP_C0805-22UF,4V,20%,X6S,CH622KMEA03',
 VOLTAGE='4V',
 PART_NUMBER='CH622KMEA03',
 VALUE='22UF',
 PRIM_FILE='./archive_libs/logical/q_cap/chips/chips.prt';

PART_NAME
 PC141_6 'Q_CAP_0402-0.1UF,25V,10%,X7R,CH4104K1B00':;

SECTION_NUMBER 1
 '@T6G_MB_LIB.T6G(SCH_1):PAGE195_I38@PURE_QUANTA.Q_CAP(CHIPS)':
 C_PATH='@t6g_mb_lib.t6g(sch_1):page195_i38@pure_quanta.q_cap(chips)',
 P_PATH='@t6g_mb_lib.t6g(sch_1):page220_i38@pure_quanta.q_cap(chips)',
 PATH='I38',
 DRAWING='@T6G_MB_LIB.T6G(SCH_1):PAGE195',
 TOLERANCE='10%',
 MATERIAL='X7R',
 PHYS_PAGE='220',
 XY='(4050,3125)',
 ROT='0',
 VER='1',
 PACK_TYPE='0402',
 LOCATION='PC141_6',
 CDS_LIB='pure_quanta',
 CDS_PART_NAME='Q_CAP_0402-0.1UF,25V,10%,X7R,CH4104K1B00',
 VOLTAGE='25V',
 PART_NUMBER='CH4104K1B00',
 VALUE='0.1UF',
 PRIM_FILE='./archive_libs/logical/q_cap/chips/chips.prt';

PART_NAME
 PC142 'Q_CAP_C0402-2.2UF,10V,10%,X6S,CH5222KEB01':;

SECTION_NUMBER 1
 '@T6G_MB_LIB.T6G(SCH_1):PAGE180_I10@PURE_QUANTA.Q_CAP(CHIPS)':
 C_PATH='@t6g_mb_lib.t6g(sch_1):page180_i10@pure_quanta.q_cap(chips)',
 P_PATH='@t6g_mb_lib.t6g(sch_1):page205_i10@pure_quanta.q_cap(chips)',
 PATH='I10',
 DRAWING='@T6G_MB_LIB.T6G(SCH_1):PAGE180',
 TOLERANCE='10%',
 MATERIAL='X6S',
 PHYS_PAGE='205',
 XY='(1175,2575)',
 ROT='0',
 VER='1',
 PACK_TYPE='C0402',
 LOCATION='PC142',
 CDS_LIB='pure_quanta',
 CDS_PART_NAME='Q_CAP_C0402-2.2UF,10V,10%,X6S,CH5222KEB01',
 VOLTAGE='10V',
 PART_NUMBER='CH5222KEB01',
 VALUE='2.2UF',
 PRIM_FILE='./archive_libs/logical/q_cap/chips/chips.prt';

PART_NAME
 PC143 'Q_CAP_C0402-2.2UF,10V,10%,X6S,CH5222KEB01':;

SECTION_NUMBER 1
 '@T6G_MB_LIB.T6G(SCH_1):PAGE180_I28@PURE_QUANTA.Q_CAP(CHIPS)':
 C_PATH='@t6g_mb_lib.t6g(sch_1):page180_i28@pure_quanta.q_cap(chips)',
 P_PATH='@t6g_mb_lib.t6g(sch_1):page205_i28@pure_quanta.q_cap(chips)',
 PATH='I28',
 DRAWING='@T6G_MB_LIB.T6G(SCH_1):PAGE180',
 TOLERANCE='10%',
 MATERIAL='X6S',
 PHYS_PAGE='205',
 XY='(1275,5250)',
 ROT='0',
 VER='1',
 PACK_TYPE='C0402',
 LOCATION='PC143',
 CDS_LIB='pure_quanta',
 CDS_PART_NAME='Q_CAP_C0402-2.2UF,10V,10%,X6S,CH5222KEB01',
 VOLTAGE='10V',
 PART_NUMBER='CH5222KEB01',
 VALUE='2.2UF',
 PRIM_FILE='./archive_libs/logical/q_cap/chips/chips.prt';

PART_NAME
 PC144_6 'Q_CAP_C0805-22UF,16V,20%,X6S,CH6223MEA01':;

SECTION_NUMBER 1
 '@T6G_MB_LIB.T6G(SCH_1):PAGE195_I41@PURE_QUANTA.Q_CAP(CHIPS)':
 C_PATH='@t6g_mb_lib.t6g(sch_1):page195_i41@pure_quanta.q_cap(chips)',
 P_PATH='@t6g_mb_lib.t6g(sch_1):page220_i41@pure_quanta.q_cap(chips)',
 PATH='I41',
 DRAWING='@T6G_MB_LIB.T6G(SCH_1):PAGE195',
 TOLERANCE='20%',
 MATERIAL='X6S',
 PHYS_PAGE='220',
 XY='(4875,3125)',
 ROT='0',
 VER='1',
 PACK_TYPE='C0805',
 LOCATION='PC144_6',
 CDS_LIB='pure_quanta',
 CDS_PART_NAME='Q_CAP_C0805-22UF,16V,20%,X6S,CH6223MEA01',
 VOLTAGE='16V',
 PART_NUMBER='CH6223MEA01',
 VALUE='22UF',
 PRIM_FILE='./archive_libs/logical/q_cap/chips/chips.prt';

PART_NAME
 PC144_IOP0_2 'Q_CAP_C0402-2.2UF,10V,10%,X6S,CH5222KEB01':;

SECTION_NUMBER 1
 '@T6G_MB_LIB.T6G(SCH_1):PAGE180_I13@PURE_QUANTA.Q_CAP(CHIPS)':
 C_PATH='@t6g_mb_lib.t6g(sch_1):page180_i13@pure_quanta.q_cap(chips)',
 P_PATH='@t6g_mb_lib.t6g(sch_1):page205_i13@pure_quanta.q_cap(chips)',
 PATH='I13',
 DRAWING='@T6G_MB_LIB.T6G(SCH_1):PAGE180',
 TOLERANCE='10%',
 MATERIAL='X6S',
 PHYS_PAGE='205',
 XY='(1525,3150)',
 ROT='0',
 VER='1',
 PACK_TYPE='C0402',
 LOCATION='PC144_IOP0_2',
 CDS_LIB='pure_quanta',
 CDS_PART_NAME='Q_CAP_C0402-2.2UF,10V,10%,X6S,CH5222KEB01',
 VOLTAGE='10V',
 PART_NUMBER='CH5222KEB01',
 VALUE='2.2UF',
 PRIM_FILE='./archive_libs/logical/q_cap/chips/chips.prt';

PART_NAME
 PC145_6 'Q_CAP_C0805-22UF,16V,20%,X6S,CH6223MEA01':;

SECTION_NUMBER 1
 '@T6G_MB_LIB.T6G(SCH_1):PAGE195_I44@PURE_QUANTA.Q_CAP(CHIPS)':
 C_PATH='@t6g_mb_lib.t6g(sch_1):page195_i44@pure_quanta.q_cap(chips)',
 P_PATH='@t6g_mb_lib.t6g(sch_1):page220_i44@pure_quanta.q_cap(chips)',
 PATH='I44',
 DRAWING='@T6G_MB_LIB.T6G(SCH_1):PAGE195',
 TOLERANCE='20%',
 MATERIAL='X6S',
 PHYS_PAGE='220',
 XY='(5275,3125)',
 ROT='0',
 VER='1',
 PACK_TYPE='C0805',
 LOCATION='PC145_6',
 CDS_LIB='pure_quanta',
 CDS_PART_NAME='Q_CAP_C0805-22UF,16V,20%,X6S,CH6223MEA01',
 VOLTAGE='16V',
 PART_NUMBER='CH6223MEA01',
 VALUE='22UF',
 PRIM_FILE='./archive_libs/logical/q_cap/chips/chips.prt';

PART_NAME
 PC145_7 'Q_CAP_0402-0.1UF,25V,10%,X7R,CH4104K1B00':;

SECTION_NUMBER 1
 '@T6G_MB_LIB.T6G(SCH_1):PAGE180_I20@PURE_QUANTA.Q_CAP(CHIPS)':
 C_PATH='@t6g_mb_lib.t6g(sch_1):page180_i20@pure_quanta.q_cap(chips)',
 P_PATH='@t6g_mb_lib.t6g(sch_1):page205_i20@pure_quanta.q_cap(chips)',
 PATH='I20',
 DRAWING='@T6G_MB_LIB.T6G(SCH_1):PAGE180',
 TOLERANCE='10%',
 MATERIAL='X7R',
 PHYS_PAGE='205',
 XY='(250,4600)',
 ROT='0',
 VER='1',
 PACK_TYPE='0402',
 LOCATION='PC145_7',
 CDS_LIB='pure_quanta',
 CDS_PART_NAME='Q_CAP_0402-0.1UF,25V,10%,X7R,CH4104K1B00',
 VOLTAGE='25V',
 PART_NUMBER='CH4104K1B00',
 VALUE='0.1UF',
 PRIM_FILE='./archive_libs/logical/q_cap/chips/chips.prt';

PART_NAME
 PC146 'Q_CAP_0402-0.22UF,16V,10%,X7R,CH4223K1B00':;

SECTION_NUMBER 1
 '@T6G_MB_LIB.T6G(SCH_1):PAGE195_I45@PURE_QUANTA.Q_CAP(CHIPS)':
 C_PATH='@t6g_mb_lib.t6g(sch_1):page195_i45@pure_quanta.q_cap(chips)',
 P_PATH='@t6g_mb_lib.t6g(sch_1):page220_i45@pure_quanta.q_cap(chips)',
 PATH='I45',
 DRAWING='@T6G_MB_LIB.T6G(SCH_1):PAGE195',
 TOLERANCE='10%',
 MATERIAL='X7R',
 PHYS_PAGE='220',
 XY='(5450,2450)',
 ROT='0',
 VER='1',
 PACK_TYPE='0402',
 LOCATION='PC146',
 CDS_LIB='pure_quanta',
 CDS_PART_NAME='Q_CAP_0402-0.22UF,16V,10%,X7R,CH4223K1B00',
 VOLTAGE='16V',
 PART_NUMBER='CH4223K1B00',
 VALUE='0.22UF',
 PRIM_FILE='./archive_libs/logical/q_cap/chips/chips.prt';

PART_NAME
 PC146_8 'Q_CAP_0402-0.1UF,25V,10%,X7R,CH4104K1B00':;

SECTION_NUMBER 1
 '@T6G_MB_LIB.T6G(SCH_1):PAGE180_I2@PURE_QUANTA.Q_CAP(CHIPS)':
 C_PATH='@t6g_mb_lib.t6g(sch_1):page180_i2@pure_quanta.q_cap(chips)',
 P_PATH='@t6g_mb_lib.t6g(sch_1):page205_i2@pure_quanta.q_cap(chips)',
 PATH='I2',
 DRAWING='@T6G_MB_LIB.T6G(SCH_1):PAGE180',
 TOLERANCE='10%',
 MATERIAL='X7R',
 PHYS_PAGE='205',
 XY='(275,1800)',
 ROT='0',
 VER='1',
 PACK_TYPE='0402',
 LOCATION='PC146_8',
 CDS_LIB='pure_quanta',
 CDS_PART_NAME='Q_CAP_0402-0.1UF,25V,10%,X7R,CH4104K1B00',
 VOLTAGE='25V',
 PART_NUMBER='CH4104K1B00',
 VALUE='0.1UF',
 PRIM_FILE='./archive_libs/logical/q_cap/chips/chips.prt';

PART_NAME
 PC147_6 'Q_CAP_C0805-22UF,16V,20%,X6S,CH6223MEA01':;

SECTION_NUMBER 1
 '@T6G_MB_LIB.T6G(SCH_1):PAGE195_I47@PURE_QUANTA.Q_CAP(CHIPS)':
 C_PATH='@t6g_mb_lib.t6g(sch_1):page195_i47@pure_quanta.q_cap(chips)',
 P_PATH='@t6g_mb_lib.t6g(sch_1):page220_i47@pure_quanta.q_cap(chips)',
 PATH='I47',
 DRAWING='@T6G_MB_LIB.T6G(SCH_1):PAGE195',
 TOLERANCE='20%',
 MATERIAL='X6S',
 PHYS_PAGE='220',
 XY='(5650,3125)',
 ROT='0',
 VER='1',
 PACK_TYPE='C0805',
 LOCATION='PC147_6',
 CDS_LIB='pure_quanta',
 CDS_PART_NAME='Q_CAP_C0805-22UF,16V,20%,X6S,CH6223MEA01',
 VOLTAGE='16V',
 PART_NUMBER='CH6223MEA01',
 VALUE='22UF',
 PRIM_FILE='./archive_libs/logical/q_cap/chips/chips.prt';

PART_NAME
 PC147_IOP0_1 'Q_CAP_C0402-2.2UF,10V,10%,X6S,CH5222KEB01':;

SECTION_NUMBER 1
 '@T6G_MB_LIB.T6G(SCH_1):PAGE180_I31@PURE_QUANTA.Q_CAP(CHIPS)':
 C_PATH='@t6g_mb_lib.t6g(sch_1):page180_i31@pure_quanta.q_cap(chips)',
 P_PATH='@t6g_mb_lib.t6g(sch_1):page205_i31@pure_quanta.q_cap(chips)',
 PATH='I31',
 DRAWING='@T6G_MB_LIB.T6G(SCH_1):PAGE180',
 TOLERANCE='10%',
 MATERIAL='X6S',
 PHYS_PAGE='205',
 XY='(1625,5825)',
 ROT='0',
 VER='1',
 PACK_TYPE='C0402',
 LOCATION='PC147_IOP0_1',
 CDS_LIB='pure_quanta',
 CDS_PART_NAME='Q_CAP_C0402-2.2UF,10V,10%,X6S,CH5222KEB01',
 VOLTAGE='10V',
 PART_NUMBER='CH5222KEB01',
 VALUE='2.2UF',
 PRIM_FILE='./archive_libs/logical/q_cap/chips/chips.prt';

PART_NAME
 PC148 'Q_CAP_0402-0.1UF,25V,10%,X7R,CH4104K1B00':;

SECTION_NUMBER 1
 '@T6G_MB_LIB.T6G(SCH_1):PAGE180_I72@PURE_QUANTA.Q_CAP(CHIPS)':
 C_PATH='@t6g_mb_lib.t6g(sch_1):page180_i72@pure_quanta.q_cap(chips)',
 P_PATH='@t6g_mb_lib.t6g(sch_1):page205_i72@pure_quanta.q_cap(chips)',
 PATH='I72',
 DRAWING='@T6G_MB_LIB.T6G(SCH_1):PAGE180',
 TOLERANCE='10%',
 MATERIAL='X7R',
 PHYS_PAGE='205',
 XY='(6600,5925)',
 ROT='0',
 VER='1',
 PACK_TYPE='0402',
 LOCATION='PC148',
 CDS_LIB='pure_quanta',
 CDS_PART_NAME='Q_CAP_0402-0.1UF,25V,10%,X7R,CH4104K1B00',
 VOLTAGE='25V',
 PART_NUMBER='CH4104K1B00',
 VALUE='0.1UF',
 PRIM_FILE='./archive_libs/logical/q_cap/chips/chips.prt';

PART_NAME
 PC148_1 'Q_CAP_0402-0.1UF,25V,10%,X7R,CH4104K1B00':;

SECTION_NUMBER 1
 '@T6G_MB_LIB.T6G(SCH_1):PAGE180_I83@PURE_QUANTA.Q_CAP(CHIPS)':
 C_PATH='@t6g_mb_lib.t6g(sch_1):page180_i83@pure_quanta.q_cap(chips)',
 P_PATH='@t6g_mb_lib.t6g(sch_1):page205_i83@pure_quanta.q_cap(chips)',
 PATH='I83',
 DRAWING='@T6G_MB_LIB.T6G(SCH_1):PAGE180',
 TOLERANCE='10%',
 MATERIAL='X7R',
 PHYS_PAGE='205',
 XY='(3600,5875)',
 ROT='0',
 VER='1',
 PACK_TYPE='0402',
 LOCATION='PC148_1',
 CDS_LIB='pure_quanta',
 CDS_PART_NAME='Q_CAP_0402-0.1UF,25V,10%,X7R,CH4104K1B00',
 VOLTAGE='25V',
 PART_NUMBER='CH4104K1B00',
 VALUE='0.1UF',
 PRIM_FILE='./archive_libs/logical/q_cap/chips/chips.prt';

PART_NAME
 PC148_6 'Q_CAP_C0805-22UF,4V,20%,X6S,CH622KMEA03':;

SECTION_NUMBER 1
 '@T6G_MB_LIB.T6G(SCH_1):PAGE195_I65@PURE_QUANTA.Q_CAP(CHIPS)':
 C_PATH='@t6g_mb_lib.t6g(sch_1):page195_i65@pure_quanta.q_cap(chips)',
 P_PATH='@t6g_mb_lib.t6g(sch_1):page220_i65@pure_quanta.q_cap(chips)',
 PATH='I65',
 DRAWING='@T6G_MB_LIB.T6G(SCH_1):PAGE195',
 TOLERANCE='20%',
 MATERIAL='X6S',
 PHYS_PAGE='220',
 XY='(8150,2025)',
 ROT='0',
 VER='1',
 PACK_TYPE='C0805',
 LOCATION='PC148_6',
 CDS_LIB='pure_quanta',
 CDS_PART_NAME='Q_CAP_C0805-22UF,4V,20%,X6S,CH622KMEA03',
 VOLTAGE='4V',
 PART_NUMBER='CH622KMEA03',
 VALUE='22UF',
 PRIM_FILE='./archive_libs/logical/q_cap/chips/chips.prt';

PART_NAME
 PC149 'Q_CAP_C0402-560PF,50V,10%,EMPTY,CH1566K1B09':;

SECTION_NUMBER 1
 '@T6G_MB_LIB.T6G(SCH_1):PAGE190_I20@PURE_QUANTA.Q_CAP(CHIPS)':
 C_PATH='@t6g_mb_lib.t6g(sch_1):page190_i20@pure_quanta.q_cap(chips)',
 P_PATH='@t6g_mb_lib.t6g(sch_1):page215_i20@pure_quanta.q_cap(chips)',
 PATH='I20',
 DRAWING='@T6G_MB_LIB.T6G(SCH_1):PAGE190',
 TOLERANCE='10%',
 MATERIAL='EMPTY',
 PHYS_PAGE='215',
 XY='(-4625,1775)',
 ROT='0',
 VER='1',
 PACK_TYPE='C0402',
 LOCATION='PC149',
 CDS_LIB='pure_quanta',
 CDS_PART_NAME='Q_CAP_C0402-560PF,50V,10%,EMPTY,CH1566K1B09',
 VOLTAGE='50V',
 PART_NUMBER='CH1566K1B09',
 VALUE='560PF',
 PRIM_FILE='./archive_libs/logical/q_cap/chips/chips.prt';

PART_NAME
 PC149_2 'Q_CAP_0402-0.1UF,25V,10%,X7R,CH4104K1B00':;

SECTION_NUMBER 1
 '@T6G_MB_LIB.T6G(SCH_1):PAGE180_I18@PURE_QUANTA.Q_CAP(CHIPS)':
 C_PATH='@t6g_mb_lib.t6g(sch_1):page180_i18@pure_quanta.q_cap(chips)',
 P_PATH='@t6g_mb_lib.t6g(sch_1):page205_i18@pure_quanta.q_cap(chips)',
 PATH='I18',
 DRAWING='@T6G_MB_LIB.T6G(SCH_1):PAGE180',
 TOLERANCE='10%',
 MATERIAL='X7R',
 PHYS_PAGE='205',
 XY='(3675,3100)',
 ROT='0',
 VER='1',
 PACK_TYPE='0402',
 LOCATION='PC149_2',
 CDS_LIB='pure_quanta',
 CDS_PART_NAME='Q_CAP_0402-0.1UF,25V,10%,X7R,CH4104K1B00',
 VOLTAGE='25V',
 PART_NUMBER='CH4104K1B00',
 VALUE='0.1UF',
 PRIM_FILE='./archive_libs/logical/q_cap/chips/chips.prt';

PART_NAME
 PC149_6 'Q_CAP_C0805-22UF,4V,20%,X6S,CH622KMEA03':;

SECTION_NUMBER 1
 '@T6G_MB_LIB.T6G(SCH_1):PAGE195_I67@PURE_QUANTA.Q_CAP(CHIPS)':
 C_PATH='@t6g_mb_lib.t6g(sch_1):page195_i67@pure_quanta.q_cap(chips)',
 P_PATH='@t6g_mb_lib.t6g(sch_1):page220_i67@pure_quanta.q_cap(chips)',
 PATH='I67',
 DRAWING='@T6G_MB_LIB.T6G(SCH_1):PAGE195',
 TOLERANCE='20%',
 MATERIAL='X6S',
 PHYS_PAGE='220',
 XY='(8575,2025)',
 ROT='0',
 VER='1',
 PACK_TYPE='C0805',
 LOCATION='PC149_6',
 CDS_LIB='pure_quanta',
 CDS_PART_NAME='Q_CAP_C0805-22UF,4V,20%,X6S,CH622KMEA03',
 VOLTAGE='4V',
 PART_NUMBER='CH622KMEA03',
 VALUE='22UF',
 PRIM_FILE='./archive_libs/logical/q_cap/chips/chips.prt';

PART_NAME
 PC150 'Q_CAP_C0805-22UF,16V,20%,X6S,CH6223MEA01':;

SECTION_NUMBER 1
 '@T6G_MB_LIB.T6G(SCH_1):PAGE201_I22@PURE_QUANTA.Q_CAP(CHIPS)':
 C_PATH='@t6g_mb_lib.t6g(sch_1):page201_i22@pure_quanta.q_cap(chips)',
 P_PATH='@t6g_mb_lib.t6g(sch_1):page226_i22@pure_quanta.q_cap(chips)',
 PATH='I22',
 DRAWING='@T6G_MB_LIB.T6G(SCH_1):PAGE201',
 TOLERANCE='20%',
 MATERIAL='X6S',
 PHYS_PAGE='226',
 XY='(-6825,4550)',
 ROT='0',
 VER='1',
 PACK_TYPE='C0805',
 LOCATION='PC150',
 CDS_LIB='pure_quanta',
 CDS_PART_NAME='Q_CAP_C0805-22UF,16V,20%,X6S,CH6223MEA01',
 VOLTAGE='16V',
 PART_NUMBER='CH6223MEA01',
 VALUE='22UF',
 PRIM_FILE='./archive_libs/logical/q_cap/chips/chips.prt';

PART_NAME
 PC150_1 'Q_CAP_C0402-1UF,25V,10%,X6S,CH5104KEB02':;

SECTION_NUMBER 1
 '@T6G_MB_LIB.T6G(SCH_1):PAGE180_I82@PURE_QUANTA.Q_CAP(CHIPS)':
 C_PATH='@t6g_mb_lib.t6g(sch_1):page180_i82@pure_quanta.q_cap(chips)',
 P_PATH='@t6g_mb_lib.t6g(sch_1):page205_i82@pure_quanta.q_cap(chips)',
 PATH='I82',
 DRAWING='@T6G_MB_LIB.T6G(SCH_1):PAGE180',
 TOLERANCE='10%',
 MATERIAL='X6S',
 PHYS_PAGE='205',
 XY='(4025,5875)',
 ROT='0',
 VER='1',
 PACK_TYPE='C0402',
 LOCATION='PC150_1',
 CDS_LIB='pure_quanta',
 CDS_PART_NAME='Q_CAP_C0402-1UF,25V,10%,X6S,CH5104KEB02',
 VOLTAGE='25V',
 PART_NUMBER='CH5104KEB02',
 VALUE='1UF',
 PRIM_FILE='./archive_libs/logical/q_cap/chips/chips.prt';

PART_NAME
 PC150_6 'Q_CAP_0402-0.1UF,25V,10%,X7R,CH4104K1B00':;

SECTION_NUMBER 1
 '@T6G_MB_LIB.T6G(SCH_1):PAGE171_I4@PURE_QUANTA.Q_CAP(CHIPS)':
 C_PATH='@t6g_mb_lib.t6g(sch_1):page171_i4@pure_quanta.q_cap(chips)',
 P_PATH='@t6g_mb_lib.t6g(sch_1):page196_i4@pure_quanta.q_cap(chips)',
 PATH='I4',
 DRAWING='@T6G_MB_LIB.T6G(SCH_1):PAGE171',
 TOLERANCE='10%',
 MATERIAL='X7R',
 PHYS_PAGE='196',
 XY='(-7525,1575)',
 ROT='0',
 VER='1',
 PACK_TYPE='0402',
 LOCATION='PC150_6',
 CDS_LIB='pure_quanta',
 CDS_PART_NAME='Q_CAP_0402-0.1UF,25V,10%,X7R,CH4104K1B00',
 VOLTAGE='25V',
 PART_NUMBER='CH4104K1B00',
 VALUE='0.1UF',
 PRIM_FILE='./archive_libs/logical/q_cap/chips/chips.prt';

PART_NAME
 PC151 'Q_CAP_C0402-2.2UF,10V,10%,X6S,CH5222KEB01':;

SECTION_NUMBER 1
 '@T6G_MB_LIB.T6G(SCH_1):PAGE171_I11@PURE_QUANTA.Q_CAP(CHIPS)':
 C_PATH='@t6g_mb_lib.t6g(sch_1):page171_i11@pure_quanta.q_cap(chips)',
 P_PATH='@t6g_mb_lib.t6g(sch_1):page196_i11@pure_quanta.q_cap(chips)',
 PATH='I11',
 DRAWING='@T6G_MB_LIB.T6G(SCH_1):PAGE171',
 TOLERANCE='10%',
 MATERIAL='X6S',
 PHYS_PAGE='196',
 XY='(-7200,2200)',
 ROT='0',
 VER='1',
 PACK_TYPE='C0402',
 LOCATION='PC151',
 CDS_LIB='pure_quanta',
 CDS_PART_NAME='Q_CAP_C0402-2.2UF,10V,10%,X6S,CH5222KEB01',
 VOLTAGE='10V',
 PART_NUMBER='CH5222KEB01',
 VALUE='2.2UF',
 PRIM_FILE='./archive_libs/logical/q_cap/chips/chips.prt';

PART_NAME
 PC151_2 'Q_CAP_C0402-1UF,25V,10%,X6S,CH5104KEB02':;

SECTION_NUMBER 1
 '@T6G_MB_LIB.T6G(SCH_1):PAGE180_I42@PURE_QUANTA.Q_CAP(CHIPS)':
 C_PATH='@t6g_mb_lib.t6g(sch_1):page180_i42@pure_quanta.q_cap(chips)',
 P_PATH='@t6g_mb_lib.t6g(sch_1):page205_i42@pure_quanta.q_cap(chips)',
 PATH='I42',
 DRAWING='@T6G_MB_LIB.T6G(SCH_1):PAGE180',
 TOLERANCE='10%',
 MATERIAL='X6S',
 PHYS_PAGE='205',
 XY='(4175,3100)',
 ROT='0',
 VER='1',
 PACK_TYPE='C0402',
 LOCATION='PC151_2',
 CDS_LIB='pure_quanta',
 CDS_PART_NAME='Q_CAP_C0402-1UF,25V,10%,X6S,CH5104KEB02',
 VOLTAGE='25V',
 PART_NUMBER='CH5104KEB02',
 VALUE='1UF',
 PRIM_FILE='./archive_libs/logical/q_cap/chips/chips.prt';

PART_NAME
 PC152 'Q_CAP_C0805-22UF,16V,20%,X6S,CH6223MEA01':;

SECTION_NUMBER 1
 '@T6G_MB_LIB.T6G(SCH_1):PAGE201_I23@PURE_QUANTA.Q_CAP(CHIPS)':
 C_PATH='@t6g_mb_lib.t6g(sch_1):page201_i23@pure_quanta.q_cap(chips)',
 P_PATH='@t6g_mb_lib.t6g(sch_1):page226_i23@pure_quanta.q_cap(chips)',
 PATH='I23',
 DRAWING='@T6G_MB_LIB.T6G(SCH_1):PAGE201',
 TOLERANCE='20%',
 MATERIAL='X6S',
 PHYS_PAGE='226',
 XY='(-6575,4550)',
 ROT='0',
 VER='1',
 PACK_TYPE='C0805',
 LOCATION='PC152',
 CDS_LIB='pure_quanta',
 CDS_PART_NAME='Q_CAP_C0805-22UF,16V,20%,X6S,CH6223MEA01',
 VOLTAGE='16V',
 PART_NUMBER='CH6223MEA01',
 VALUE='22UF',
 PRIM_FILE='./archive_libs/logical/q_cap/chips/chips.prt';

PART_NAME
 PC152_1 'Q_CAP_C0805-22UF,16V,20%,X6S,CH6223MEA01':;

SECTION_NUMBER 1
 '@T6G_MB_LIB.T6G(SCH_1):PAGE180_I81@PURE_QUANTA.Q_CAP(CHIPS)':
 C_PATH='@t6g_mb_lib.t6g(sch_1):page180_i81@pure_quanta.q_cap(chips)',
 P_PATH='@t6g_mb_lib.t6g(sch_1):page205_i81@pure_quanta.q_cap(chips)',
 PATH='I81',
 DRAWING='@T6G_MB_LIB.T6G(SCH_1):PAGE180',
 TOLERANCE='20%',
 MATERIAL='X6S',
 PHYS_PAGE='205',
 XY='(4425,5875)',
 ROT='0',
 VER='1',
 PACK_TYPE='C0805',
 LOCATION='PC152_1',
 CDS_LIB='pure_quanta',
 CDS_PART_NAME='Q_CAP_C0805-22UF,16V,20%,X6S,CH6223MEA01',
 VOLTAGE='16V',
 PART_NUMBER='CH6223MEA01',
 VALUE='22UF',
 PRIM_FILE='./archive_libs/logical/q_cap/chips/chips.prt';

PART_NAME
 PC152_C0P0_6 'Q_CAP_C0402-2.2UF,10V,10%,X6S,CH5222KEB01':;

SECTION_NUMBER 1
 '@T6G_MB_LIB.T6G(SCH_1):PAGE171_I14@PURE_QUANTA.Q_CAP(CHIPS)':
 C_PATH='@t6g_mb_lib.t6g(sch_1):page171_i14@pure_quanta.q_cap(chips)',
 P_PATH='@t6g_mb_lib.t6g(sch_1):page196_i14@pure_quanta.q_cap(chips)',
 PATH='I14',
 DRAWING='@T6G_MB_LIB.T6G(SCH_1):PAGE171',
 TOLERANCE='10%',
 MATERIAL='X6S',
 PHYS_PAGE='196',
 XY='(-6850,2725)',
 ROT='0',
 VER='1',
 PACK_TYPE='C0402',
 LOCATION='PC152_C0P0_6',
 CDS_LIB='pure_quanta',
 CDS_PART_NAME='Q_CAP_C0402-2.2UF,10V,10%,X6S,CH5222KEB01',
 VOLTAGE='10V',
 PART_NUMBER='CH5222KEB01',
 VALUE='2.2UF',
 PRIM_FILE='./archive_libs/logical/q_cap/chips/chips.prt';

PART_NAME
 PC153 'Q_CAP_0402-0.022UF,25V,10%,X7R,CH3224K1B01':;

SECTION_NUMBER 1
 '@T6G_MB_LIB.T6G(SCH_1):PAGE201_I18@PURE_QUANTA.Q_CAP(CHIPS)':
 C_PATH='@t6g_mb_lib.t6g(sch_1):page201_i18@pure_quanta.q_cap(chips)',
 P_PATH='@t6g_mb_lib.t6g(sch_1):page226_i18@pure_quanta.q_cap(chips)',
 PATH='I18',
 DRAWING='@T6G_MB_LIB.T6G(SCH_1):PAGE201',
 TOLERANCE='10%',
 MATERIAL='X7R',
 PHYS_PAGE='226',
 XY='(-4700,3125)',
 ROT='0',
 VER='1',
 PACK_TYPE='0402',
 LOCATION='PC153',
 CDS_LIB='pure_quanta',
 CDS_PART_NAME='Q_CAP_0402-0.022UF,25V,10%,X7R,CH3224K1B01',
 VOLTAGE='25V',
 PART_NUMBER='CH3224K1B01',
 VALUE='0.022UF',
 PRIM_FILE='./archive_libs/logical/q_cap/chips/chips.prt';

PART_NAME
 PC153_2 'Q_CAP_C0805-22UF,16V,20%,X6S,CH6223MEA01':;

SECTION_NUMBER 1
 '@T6G_MB_LIB.T6G(SCH_1):PAGE180_I43@PURE_QUANTA.Q_CAP(CHIPS)':
 C_PATH='@t6g_mb_lib.t6g(sch_1):page180_i43@pure_quanta.q_cap(chips)',
 P_PATH='@t6g_mb_lib.t6g(sch_1):page205_i43@pure_quanta.q_cap(chips)',
 PATH='I43',
 DRAWING='@T6G_MB_LIB.T6G(SCH_1):PAGE180',
 TOLERANCE='20%',
 MATERIAL='X6S',
 PHYS_PAGE='205',
 XY='(4575,3100)',
 ROT='0',
 VER='1',
 PACK_TYPE='C0805',
 LOCATION='PC153_2',
 CDS_LIB='pure_quanta',
 CDS_PART_NAME='Q_CAP_C0805-22UF,16V,20%,X6S,CH6223MEA01',
 VOLTAGE='16V',
 PART_NUMBER='CH6223MEA01',
 VALUE='22UF',
 PRIM_FILE='./archive_libs/logical/q_cap/chips/chips.prt';

PART_NAME
 PC153_6 'Q_CAP_0402-0.1UF,25V,10%,X7R,CH4104K1B00':;

SECTION_NUMBER 1
 '@T6G_MB_LIB.T6G(SCH_1):PAGE171_I24@PURE_QUANTA.Q_CAP(CHIPS)':
 C_PATH='@t6g_mb_lib.t6g(sch_1):page171_i24@pure_quanta.q_cap(chips)',
 P_PATH='@t6g_mb_lib.t6g(sch_1):page196_i24@pure_quanta.q_cap(chips)',
 PATH='I24',
 DRAWING='@T6G_MB_LIB.T6G(SCH_1):PAGE171',
 TOLERANCE='10%',
 MATERIAL='X7R',
 PHYS_PAGE='196',
 XY='(-4950,2725)',
 ROT='0',
 VER='1',
 PACK_TYPE='0402',
 LOCATION='PC153_6',
 CDS_LIB='pure_quanta',
 CDS_PART_NAME='Q_CAP_0402-0.1UF,25V,10%,X7R,CH4104K1B00',
 VOLTAGE='25V',
 PART_NUMBER='CH4104K1B00',
 VALUE='0.1UF',
 PRIM_FILE='./archive_libs/logical/q_cap/chips/chips.prt';

PART_NAME
 PC154 'Q_CAP_C0402-560PF,50V,10%,EMPTY,CH1566K1B09':;

SECTION_NUMBER 1
 '@T6G_MB_LIB.T6G(SCH_1):PAGE178_I72@PURE_QUANTA.Q_CAP(CHIPS)':
 C_PATH='@t6g_mb_lib.t6g(sch_1):page178_i72@pure_quanta.q_cap(chips)',
 P_PATH='@t6g_mb_lib.t6g(sch_1):page203_i72@pure_quanta.q_cap(chips)',
 PATH='I72',
 DRAWING='@T6G_MB_LIB.T6G(SCH_1):PAGE178',
 TOLERANCE='10%',
 MATERIAL='EMPTY',
 PHYS_PAGE='203',
 XY='(4800,2025)',
 ROT='0',
 VER='1',
 PACK_TYPE='C0402',
 LOCATION='PC154',
 CDS_LIB='pure_quanta',
 CDS_PART_NAME='Q_CAP_C0402-560PF,50V,10%,EMPTY,CH1566K1B09',
 VOLTAGE='50V',
 PART_NUMBER='CH1566K1B09',
 VALUE='560PF',
 PRIM_FILE='./archive_libs/logical/q_cap/chips/chips.prt';

PART_NAME
 PC154_1 'Q_CAP_C0805-22UF,16V,20%,X6S,CH6223MEA01':;

SECTION_NUMBER 1
 '@T6G_MB_LIB.T6G(SCH_1):PAGE180_I80@PURE_QUANTA.Q_CAP(CHIPS)':
 C_PATH='@t6g_mb_lib.t6g(sch_1):page180_i80@pure_quanta.q_cap(chips)',
 P_PATH='@t6g_mb_lib.t6g(sch_1):page205_i80@pure_quanta.q_cap(chips)',
 PATH='I80',
 DRAWING='@T6G_MB_LIB.T6G(SCH_1):PAGE180',
 TOLERANCE='20%',
 MATERIAL='X6S',
 PHYS_PAGE='205',
 XY='(4750,5875)',
 ROT='0',
 VER='1',
 PACK_TYPE='C0805',
 LOCATION='PC154_1',
 CDS_LIB='pure_quanta',
 CDS_PART_NAME='Q_CAP_C0805-22UF,16V,20%,X6S,CH6223MEA01',
 VOLTAGE='16V',
 PART_NUMBER='CH6223MEA01',
 VALUE='22UF',
 PRIM_FILE='./archive_libs/logical/q_cap/chips/chips.prt';

PART_NAME
 PC154_6 'Q_CAP_C0402-1UF,25V,10%,X6S,CH5104KEB02':;

SECTION_NUMBER 1
 '@T6G_MB_LIB.T6G(SCH_1):PAGE171_I27@PURE_QUANTA.Q_CAP(CHIPS)':
 C_PATH='@t6g_mb_lib.t6g(sch_1):page171_i27@pure_quanta.q_cap(chips)',
 P_PATH='@t6g_mb_lib.t6g(sch_1):page196_i27@pure_quanta.q_cap(chips)',
 PATH='I27',
 DRAWING='@T6G_MB_LIB.T6G(SCH_1):PAGE171',
 TOLERANCE='10%',
 MATERIAL='X6S',
 PHYS_PAGE='196',
 XY='(-4575,2725)',
 ROT='0',
 VER='1',
 PACK_TYPE='C0402',
 LOCATION='PC154_6',
 CDS_LIB='pure_quanta',
 CDS_PART_NAME='Q_CAP_C0402-1UF,25V,10%,X6S,CH5104KEB02',
 VOLTAGE='25V',
 PART_NUMBER='CH5104KEB02',
 VALUE='1UF',
 PRIM_FILE='./archive_libs/logical/q_cap/chips/chips.prt';

PART_NAME
 PC155 'Q_CAP_0402-0.22UF,16V,10%,X7R,CH4223K1B00':;

SECTION_NUMBER 1
 '@T6G_MB_LIB.T6G(SCH_1):PAGE180_I63@PURE_QUANTA.Q_CAP(CHIPS)':
 C_PATH='@t6g_mb_lib.t6g(sch_1):page180_i63@pure_quanta.q_cap(chips)',
 P_PATH='@t6g_mb_lib.t6g(sch_1):page205_i63@pure_quanta.q_cap(chips)',
 PATH='I63',
 DRAWING='@T6G_MB_LIB.T6G(SCH_1):PAGE180',
 TOLERANCE='10%',
 MATERIAL='X7R',
 PHYS_PAGE='205',
 XY='(4850,5200)',
 ROT='0',
 VER='1',
 PACK_TYPE='0402',
 LOCATION='PC155',
 CDS_LIB='pure_quanta',
 CDS_PART_NAME='Q_CAP_0402-0.22UF,16V,10%,X7R,CH4223K1B00',
 VOLTAGE='16V',
 PART_NUMBER='CH4223K1B00',
 VALUE='0.22UF',
 PRIM_FILE='./archive_libs/logical/q_cap/chips/chips.prt';

PART_NAME
 PC156 'Q_CAP_0402-0.22UF,16V,10%,X7R,CH4223K1B00':;

SECTION_NUMBER 1
 '@T6G_MB_LIB.T6G(SCH_1):PAGE180_I41@PURE_QUANTA.Q_CAP(CHIPS)':
 C_PATH='@t6g_mb_lib.t6g(sch_1):page180_i41@pure_quanta.q_cap(chips)',
 P_PATH='@t6g_mb_lib.t6g(sch_1):page205_i41@pure_quanta.q_cap(chips)',
 PATH='I41',
 DRAWING='@T6G_MB_LIB.T6G(SCH_1):PAGE180',
 TOLERANCE='10%',
 MATERIAL='X7R',
 PHYS_PAGE='205',
 XY='(4850,2400)',
 ROT='0',
 VER='1',
 PACK_TYPE='0402',
 LOCATION='PC156',
 CDS_LIB='pure_quanta',
 CDS_PART_NAME='Q_CAP_0402-0.22UF,16V,10%,X7R,CH4223K1B00',
 VOLTAGE='16V',
 PART_NUMBER='CH4223K1B00',
 VALUE='0.22UF',
 PRIM_FILE='./archive_libs/logical/q_cap/chips/chips.prt';

PART_NAME
 PC157 'Q_CAP_C0402-560PF,50V,10%,EMPTY,CH1566K1B09':;

SECTION_NUMBER 1
 '@T6G_MB_LIB.T6G(SCH_1):PAGE178_I57@PURE_QUANTA.Q_CAP(CHIPS)':
 C_PATH='@t6g_mb_lib.t6g(sch_1):page178_i57@pure_quanta.q_cap(chips)',
 P_PATH='@t6g_mb_lib.t6g(sch_1):page203_i57@pure_quanta.q_cap(chips)',
 PATH='I57',
 DRAWING='@T6G_MB_LIB.T6G(SCH_1):PAGE178',
 TOLERANCE='10%',
 MATERIAL='EMPTY',
 PHYS_PAGE='203',
 XY='(4900,4675)',
 ROT='0',
 VER='1',
 PACK_TYPE='C0402',
 LOCATION='PC157',
 CDS_LIB='pure_quanta',
 CDS_PART_NAME='Q_CAP_C0402-560PF,50V,10%,EMPTY,CH1566K1B09',
 VOLTAGE='50V',
 PART_NUMBER='CH1566K1B09',
 VALUE='560PF',
 PRIM_FILE='./archive_libs/logical/q_cap/chips/chips.prt';

PART_NAME
 PC157_2 'Q_CAP_C0805-22UF,16V,20%,X6S,CH6223MEA01':;

SECTION_NUMBER 1
 '@T6G_MB_LIB.T6G(SCH_1):PAGE180_I45@PURE_QUANTA.Q_CAP(CHIPS)':
 C_PATH='@t6g_mb_lib.t6g(sch_1):page180_i45@pure_quanta.q_cap(chips)',
 P_PATH='@t6g_mb_lib.t6g(sch_1):page205_i45@pure_quanta.q_cap(chips)',
 PATH='I45',
 DRAWING='@T6G_MB_LIB.T6G(SCH_1):PAGE180',
 TOLERANCE='20%',
 MATERIAL='X6S',
 PHYS_PAGE='205',
 XY='(4975,3100)',
 ROT='0',
 VER='1',
 PACK_TYPE='C0805',
 LOCATION='PC157_2',
 CDS_LIB='pure_quanta',
 CDS_PART_NAME='Q_CAP_C0805-22UF,16V,20%,X6S,CH6223MEA01',
 VOLTAGE='16V',
 PART_NUMBER='CH6223MEA01',
 VALUE='22UF',
 PRIM_FILE='./archive_libs/logical/q_cap/chips/chips.prt';

PART_NAME
 PC157_6 'Q_CAP_C0805-22UF,16V,20%,X6S,CH6223MEA01':;

SECTION_NUMBER 1
 '@T6G_MB_LIB.T6G(SCH_1):PAGE171_I28@PURE_QUANTA.Q_CAP(CHIPS)':
 C_PATH='@t6g_mb_lib.t6g(sch_1):page171_i28@pure_quanta.q_cap(chips)',
 P_PATH='@t6g_mb_lib.t6g(sch_1):page196_i28@pure_quanta.q_cap(chips)',
 PATH='I28',
 DRAWING='@T6G_MB_LIB.T6G(SCH_1):PAGE171',
 TOLERANCE='20%',
 MATERIAL='X6S',
 PHYS_PAGE='196',
 XY='(-4250,2725)',
 ROT='0',
 VER='1',
 PACK_TYPE='C0805',
 LOCATION='PC157_6',
 CDS_LIB='pure_quanta',
 CDS_PART_NAME='Q_CAP_C0805-22UF,16V,20%,X6S,CH6223MEA01',
 VOLTAGE='16V',
 PART_NUMBER='CH6223MEA01',
 VALUE='22UF',
 PRIM_FILE='./archive_libs/logical/q_cap/chips/chips.prt';

PART_NAME
 PC158 'Q_CAP_C0402-560PF,50V,10%,EMPTY,CH1566K1B09':;

SECTION_NUMBER 1
 '@T6G_MB_LIB.T6G(SCH_1):PAGE180_I61@PURE_QUANTA.Q_CAP(CHIPS)':
 C_PATH='@t6g_mb_lib.t6g(sch_1):page180_i61@pure_quanta.q_cap(chips)',
 P_PATH='@t6g_mb_lib.t6g(sch_1):page205_i61@pure_quanta.q_cap(chips)',
 PATH='I61',
 DRAWING='@T6G_MB_LIB.T6G(SCH_1):PAGE180',
 TOLERANCE='10%',
 MATERIAL='EMPTY',
 PHYS_PAGE='205',
 XY='(4325,4775)',
 ROT='0',
 VER='1',
 PACK_TYPE='C0402',
 LOCATION='PC158',
 CDS_LIB='pure_quanta',
 CDS_PART_NAME='Q_CAP_C0402-560PF,50V,10%,EMPTY,CH1566K1B09',
 VOLTAGE='50V',
 PART_NUMBER='CH1566K1B09',
 VALUE='560PF',
 PRIM_FILE='./archive_libs/logical/q_cap/chips/chips.prt';

PART_NAME
 PC158_1 'Q_CAP_C0805-22UF,16V,20%,X6S,CH6223MEA01':;

SECTION_NUMBER 1
 '@T6G_MB_LIB.T6G(SCH_1):PAGE180_I66@PURE_QUANTA.Q_CAP(CHIPS)':
 C_PATH='@t6g_mb_lib.t6g(sch_1):page180_i66@pure_quanta.q_cap(chips)',
 P_PATH='@t6g_mb_lib.t6g(sch_1):page205_i66@pure_quanta.q_cap(chips)',
 PATH='I66',
 DRAWING='@T6G_MB_LIB.T6G(SCH_1):PAGE180',
 TOLERANCE='20%',
 MATERIAL='X6S',
 PHYS_PAGE='205',
 XY='(5075,5900)',
 ROT='0',
 VER='1',
 PACK_TYPE='C0805',
 LOCATION='PC158_1',
 CDS_LIB='pure_quanta',
 CDS_PART_NAME='Q_CAP_C0805-22UF,16V,20%,X6S,CH6223MEA01',
 VOLTAGE='16V',
 PART_NUMBER='CH6223MEA01',
 VALUE='22UF',
 PRIM_FILE='./archive_libs/logical/q_cap/chips/chips.prt';

PART_NAME
 PC158_6 'Q_CAP_C0805-22UF,16V,20%,X6S,CH6223MEA01':;

SECTION_NUMBER 1
 '@T6G_MB_LIB.T6G(SCH_1):PAGE171_I29@PURE_QUANTA.Q_CAP(CHIPS)':
 C_PATH='@t6g_mb_lib.t6g(sch_1):page171_i29@pure_quanta.q_cap(chips)',
 P_PATH='@t6g_mb_lib.t6g(sch_1):page196_i29@pure_quanta.q_cap(chips)',
 PATH='I29',
 DRAWING='@T6G_MB_LIB.T6G(SCH_1):PAGE171',
 TOLERANCE='20%',
 MATERIAL='X6S',
 PHYS_PAGE='196',
 XY='(-3925,2725)',
 ROT='0',
 VER='1',
 PACK_TYPE='C0805',
 LOCATION='PC158_6',
 CDS_LIB='pure_quanta',
 CDS_PART_NAME='Q_CAP_C0805-22UF,16V,20%,X6S,CH6223MEA01',
 VOLTAGE='16V',
 PART_NUMBER='CH6223MEA01',
 VALUE='22UF',
 PRIM_FILE='./archive_libs/logical/q_cap/chips/chips.prt';

PART_NAME
 PC159 'Q_CAP_C0402-560PF,50V,10%,EMPTY,CH1566K1B09':;

SECTION_NUMBER 1
 '@T6G_MB_LIB.T6G(SCH_1):PAGE180_I37@PURE_QUANTA.Q_CAP(CHIPS)':
 C_PATH='@t6g_mb_lib.t6g(sch_1):page180_i37@pure_quanta.q_cap(chips)',
 P_PATH='@t6g_mb_lib.t6g(sch_1):page205_i37@pure_quanta.q_cap(chips)',
 PATH='I37',
 DRAWING='@T6G_MB_LIB.T6G(SCH_1):PAGE180',
 TOLERANCE='10%',
 MATERIAL='EMPTY',
 PHYS_PAGE='205',
 XY='(4325,1975)',
 ROT='0',
 VER='1',
 PACK_TYPE='C0402',
 LOCATION='PC159',
 CDS_LIB='pure_quanta',
 CDS_PART_NAME='Q_CAP_C0402-560PF,50V,10%,EMPTY,CH1566K1B09',
 VOLTAGE='50V',
 PART_NUMBER='CH1566K1B09',
 VALUE='560PF',
 PRIM_FILE='./archive_libs/logical/q_cap/chips/chips.prt';

PART_NAME
 PC159_2 'Q_CAP_C0805-22UF,16V,20%,X6S,CH6223MEA01':;

SECTION_NUMBER 1
 '@T6G_MB_LIB.T6G(SCH_1):PAGE180_I47@PURE_QUANTA.Q_CAP(CHIPS)':
 C_PATH='@t6g_mb_lib.t6g(sch_1):page180_i47@pure_quanta.q_cap(chips)',
 P_PATH='@t6g_mb_lib.t6g(sch_1):page205_i47@pure_quanta.q_cap(chips)',
 PATH='I47',
 DRAWING='@T6G_MB_LIB.T6G(SCH_1):PAGE180',
 TOLERANCE='20%',
 MATERIAL='X6S',
 PHYS_PAGE='205',
 XY='(5450,3100)',
 ROT='0',
 VER='1',
 PACK_TYPE='C0805',
 LOCATION='PC159_2',
 CDS_LIB='pure_quanta',
 CDS_PART_NAME='Q_CAP_C0805-22UF,16V,20%,X6S,CH6223MEA01',
 VOLTAGE='16V',
 PART_NUMBER='CH6223MEA01',
 VALUE='22UF',
 PRIM_FILE='./archive_libs/logical/q_cap/chips/chips.prt';

PART_NAME
 PC159_6 'Q_CAP_C0805-22UF,16V,20%,X6S,CH6223MEA01':;

SECTION_NUMBER 1
 '@T6G_MB_LIB.T6G(SCH_1):PAGE171_I55@PURE_QUANTA.Q_CAP(CHIPS)':
 C_PATH='@t6g_mb_lib.t6g(sch_1):page171_i55@pure_quanta.q_cap(chips)',
 P_PATH='@t6g_mb_lib.t6g(sch_1):page196_i55@pure_quanta.q_cap(chips)',
 PATH='I55',
 DRAWING='@T6G_MB_LIB.T6G(SCH_1):PAGE171',
 TOLERANCE='20%',
 MATERIAL='X6S',
 PHYS_PAGE='196',
 XY='(-3625,2725)',
 ROT='0',
 VER='1',
 PACK_TYPE='C0805',
 LOCATION='PC159_6',
 CDS_LIB='pure_quanta',
 CDS_PART_NAME='Q_CAP_C0805-22UF,16V,20%,X6S,CH6223MEA01',
 VOLTAGE='16V',
 PART_NUMBER='CH6223MEA01',
 VALUE='22UF',
 PRIM_FILE='./archive_libs/logical/q_cap/chips/chips.prt';

PART_NAME
 PC160 'Q_CAPP_SMLF-470UF,2.5V,20%,EMPTY,CH747LM8825':;

SECTION_NUMBER 1
 '@T6G_MB_LIB.T6G(SCH_1):PAGE180_I54@PURE_QUANTA.Q_CAPP(CHIPS)':
 C_PATH='@t6g_mb_lib.t6g(sch_1):page180_i54@pure_quanta.q_capp(chips)',
 P_PATH='@t6g_mb_lib.t6g(sch_1):page205_i54@pure_quanta.q_capp(chips)',
 PATH='I54',
 DRAWING='@T6G_MB_LIB.T6G(SCH_1):PAGE180',
 TOLERANCE='20%',
 MATERIAL='EMPTY',
 PHYS_PAGE='205',
 XY='(7150,3175)',
 ROT='0',
 VER='1',
 PACK_TYPE='SMLF',
 LOCATION='PC160',
 CDS_LIB='pure_quanta',
 CDS_PART_NAME='Q_CAPP_SMLF-470UF,2.5V,20%,EMPTY,CH747LM8825',
 VOLTAGE='2.5V',
 PART_NUMBER='CH747LM8825',
 VALUE='470UF',
 PRIM_FILE='./archive_libs/logical/q_capp/chips/chips.prt';

PART_NAME
 PC161 'Q_CAP_0402-0.22UF,16V,10%,X7R,CH4223K1B00':;

SECTION_NUMBER 1
 '@T6G_MB_LIB.T6G(SCH_1):PAGE171_I54@PURE_QUANTA.Q_CAP(CHIPS)':
 C_PATH='@t6g_mb_lib.t6g(sch_1):page171_i54@pure_quanta.q_cap(chips)',
 P_PATH='@t6g_mb_lib.t6g(sch_1):page196_i54@pure_quanta.q_cap(chips)',
 PATH='I54',
 DRAWING='@T6G_MB_LIB.T6G(SCH_1):PAGE171',
 TOLERANCE='10%',
 MATERIAL='X7R',
 PHYS_PAGE='196',
 XY='(-3275,2075)',
 ROT='0',
 VER='1',
 PACK_TYPE='0402',
 LOCATION='PC161',
 CDS_LIB='pure_quanta',
 CDS_PART_NAME='Q_CAP_0402-0.22UF,16V,10%,X7R,CH4223K1B00',
 VOLTAGE='16V',
 PART_NUMBER='CH4223K1B00',
 VALUE='0.22UF',
 PRIM_FILE='./archive_libs/logical/q_cap/chips/chips.prt';

PART_NAME
 PC162 'Q_CAPP_SMLF-470UF,2.5V,20%,SPCAP,CH747LM8825':;

SECTION_NUMBER 1
 '@T6G_MB_LIB.T6G(SCH_1):PAGE180_I57@PURE_QUANTA.Q_CAPP(CHIPS)':
 C_PATH='@t6g_mb_lib.t6g(sch_1):page180_i57@pure_quanta.q_capp(chips)',
 P_PATH='@t6g_mb_lib.t6g(sch_1):page205_i57@pure_quanta.q_capp(chips)',
 PATH='I57',
 DRAWING='@T6G_MB_LIB.T6G(SCH_1):PAGE180',
 TOLERANCE='20%',
 MATERIAL='SPCAP',
 PHYS_PAGE='205',
 XY='(7550,3175)',
 ROT='0',
 VER='1',
 PACK_TYPE='SMLF',
 LOCATION='PC162',
 CDS_LIB='pure_quanta',
 CDS_PART_NAME='Q_CAPP_SMLF-470UF,2.5V,20%,SPCAP,CH747LM8825',
 VOLTAGE='2.5V',
 PART_NUMBER='CH747LM8825',
 VALUE='470UF',
 PRIM_FILE='./archive_libs/logical/q_capp/chips/chips.prt';

PART_NAME
 PC163 'Q_CAP_C0402-560PF,50V,10%,EMPTY,CH1566K1B09':;

SECTION_NUMBER 1
 '@T6G_MB_LIB.T6G(SCH_1):PAGE181_I39@PURE_QUANTA.Q_CAP(CHIPS)':
 C_PATH='@t6g_mb_lib.t6g(sch_1):page181_i39@pure_quanta.q_cap(chips)',
 P_PATH='@t6g_mb_lib.t6g(sch_1):page206_i39@pure_quanta.q_cap(chips)',
 PATH='I39',
 DRAWING='@T6G_MB_LIB.T6G(SCH_1):PAGE181',
 TOLERANCE='10%',
 MATERIAL='EMPTY',
 PHYS_PAGE='206',
 XY='(-7950,2425)',
 ROT='0',
 VER='1',
 PACK_TYPE='C0402',
 LOCATION='PC163',
 CDS_LIB='pure_quanta',
 CDS_PART_NAME='Q_CAP_C0402-560PF,50V,10%,EMPTY,CH1566K1B09',
 VOLTAGE='50V',
 PART_NUMBER='CH1566K1B09',
 VALUE='560PF',
 PRIM_FILE='./archive_libs/logical/q_cap/chips/chips.prt';

PART_NAME
 PC163_6 'Q_CAP_C0805-22UF,4V,20%,X6S,CH622KMEA03':;

SECTION_NUMBER 1
 '@T6G_MB_LIB.T6G(SCH_1):PAGE171_I59@PURE_QUANTA.Q_CAP(CHIPS)':
 C_PATH='@t6g_mb_lib.t6g(sch_1):page171_i59@pure_quanta.q_cap(chips)',
 P_PATH='@t6g_mb_lib.t6g(sch_1):page196_i59@pure_quanta.q_cap(chips)',
 PATH='I59',
 DRAWING='@T6G_MB_LIB.T6G(SCH_1):PAGE171',
 TOLERANCE='20%',
 MATERIAL='X6S',
 PHYS_PAGE='196',
 XY='(-1075,1675)',
 ROT='0',
 VER='1',
 PACK_TYPE='C0805',
 LOCATION='PC163_6',
 CDS_LIB='pure_quanta',
 CDS_PART_NAME='Q_CAP_C0805-22UF,4V,20%,X6S,CH622KMEA03',
 VOLTAGE='4V',
 PART_NUMBER='CH622KMEA03',
 VALUE='22UF',
 PRIM_FILE='./archive_libs/logical/q_cap/chips/chips.prt';

PART_NAME
 PC164 'Q_CAPP_THLF-270UF,16V,20%,OSCON,CC72703MD38':;

SECTION_NUMBER 1
 '@T6G_MB_LIB.T6G(SCH_1):PAGE180_I67@PURE_QUANTA.Q_CAPP(CHIPS)':
 C_PATH='@t6g_mb_lib.t6g(sch_1):page180_i67@pure_quanta.q_capp(chips)',
 P_PATH='@t6g_mb_lib.t6g(sch_1):page205_i67@pure_quanta.q_capp(chips)',
 PATH='I67',
 DRAWING='@T6G_MB_LIB.T6G(SCH_1):PAGE180',
 TOLERANCE='20%',
 MATERIAL='OSCON',
 PHYS_PAGE='205',
 XY='(5725,5900)',
 ROT='0',
 VER='1',
 PACK_TYPE='THLF',
 LOCATION='PC164',
 CDS_LIB='pure_quanta',
 CDS_PART_NAME='Q_CAPP_THLF-270UF,16V,20%,OSCON,CC72703MD38',
 VOLTAGE='16V',
 PART_NUMBER='CC72703MD38',
 VALUE='270UF',
 PRIM_FILE='./archive_libs/logical/q_capp/chips/chips.prt';

PART_NAME
 PC165 'Q_CAPP_SMLF-470UF,2.5V,20%,SPCAP,CH747LM8825':;

SECTION_NUMBER 1
 '@T6G_MB_LIB.T6G(SCH_1):PAGE180_I58@PURE_QUANTA.Q_CAPP(CHIPS)':
 C_PATH='@t6g_mb_lib.t6g(sch_1):page180_i58@pure_quanta.q_capp(chips)',
 P_PATH='@t6g_mb_lib.t6g(sch_1):page205_i58@pure_quanta.q_capp(chips)',
 PATH='I58',
 DRAWING='@T6G_MB_LIB.T6G(SCH_1):PAGE180',
 TOLERANCE='20%',
 MATERIAL='SPCAP',
 PHYS_PAGE='205',
 XY='(7950,3175)',
 ROT='0',
 VER='1',
 PACK_TYPE='SMLF',
 LOCATION='PC165',
 CDS_LIB='pure_quanta',
 CDS_PART_NAME='Q_CAPP_SMLF-470UF,2.5V,20%,SPCAP,CH747LM8825',
 VOLTAGE='2.5V',
 PART_NUMBER='CH747LM8825',
 VALUE='470UF',
 PRIM_FILE='./archive_libs/logical/q_capp/chips/chips.prt';

PART_NAME
 PC166 'Q_CAP_C0402-560PF,50V,10%,EMPTY,CH1566K1B09':;

SECTION_NUMBER 1
 '@T6G_MB_LIB.T6G(SCH_1):PAGE181_I56@PURE_QUANTA.Q_CAP(CHIPS)':
 C_PATH='@t6g_mb_lib.t6g(sch_1):page181_i56@pure_quanta.q_cap(chips)',
 P_PATH='@t6g_mb_lib.t6g(sch_1):page206_i56@pure_quanta.q_cap(chips)',
 PATH='I56',
 DRAWING='@T6G_MB_LIB.T6G(SCH_1):PAGE181',
 TOLERANCE='10%',
 MATERIAL='EMPTY',
 PHYS_PAGE='206',
 XY='(-7950,5225)',
 ROT='0',
 VER='1',
 PACK_TYPE='C0402',
 LOCATION='PC166',
 CDS_LIB='pure_quanta',
 CDS_PART_NAME='Q_CAP_C0402-560PF,50V,10%,EMPTY,CH1566K1B09',
 VOLTAGE='50V',
 PART_NUMBER='CH1566K1B09',
 VALUE='560PF',
 PRIM_FILE='./archive_libs/logical/q_cap/chips/chips.prt';

PART_NAME
 PC166_1 'Q_CAP_C0805-22UF,4V,20%,X6S,CH622KMEA03':;

SECTION_NUMBER 1
 '@T6G_MB_LIB.T6G(SCH_1):PAGE180_I74@PURE_QUANTA.Q_CAP(CHIPS)':
 C_PATH='@t6g_mb_lib.t6g(sch_1):page180_i74@pure_quanta.q_cap(chips)',
 P_PATH='@t6g_mb_lib.t6g(sch_1):page205_i74@pure_quanta.q_cap(chips)',
 PATH='I74',
 DRAWING='@T6G_MB_LIB.T6G(SCH_1):PAGE180',
 TOLERANCE='20%',
 MATERIAL='X6S',
 PHYS_PAGE='205',
 XY='(7700,4775)',
 ROT='0',
 VER='1',
 PACK_TYPE='C0805',
 LOCATION='PC166_1',
 CDS_LIB='pure_quanta',
 CDS_PART_NAME='Q_CAP_C0805-22UF,4V,20%,X6S,CH622KMEA03',
 VOLTAGE='4V',
 PART_NUMBER='CH622KMEA03',
 VALUE='22UF',
 PRIM_FILE='./archive_libs/logical/q_cap/chips/chips.prt';

PART_NAME
 PC166_6 'Q_CAP_C0805-22UF,4V,20%,X6S,CH622KMEA03':;

SECTION_NUMBER 1
 '@T6G_MB_LIB.T6G(SCH_1):PAGE171_I60@PURE_QUANTA.Q_CAP(CHIPS)':
 C_PATH='@t6g_mb_lib.t6g(sch_1):page171_i60@pure_quanta.q_cap(chips)',
 P_PATH='@t6g_mb_lib.t6g(sch_1):page196_i60@pure_quanta.q_cap(chips)',
 PATH='I60',
 DRAWING='@T6G_MB_LIB.T6G(SCH_1):PAGE171',
 TOLERANCE='20%',
 MATERIAL='X6S',
 PHYS_PAGE='196',
 XY='(-650,1675)',
 ROT='0',
 VER='1',
 PACK_TYPE='C0805',
 LOCATION='PC166_6',
 CDS_LIB='pure_quanta',
 CDS_PART_NAME='Q_CAP_C0805-22UF,4V,20%,X6S,CH622KMEA03',
 VOLTAGE='4V',
 PART_NUMBER='CH622KMEA03',
 VALUE='22UF',
 PRIM_FILE='./archive_libs/logical/q_cap/chips/chips.prt';

PART_NAME
 PC168 'Q_CAP_C0402-560PF,50V,10%,EMPTY,CH1566K1B09':;

SECTION_NUMBER 1
 '@T6G_MB_LIB.T6G(SCH_1):PAGE183_I26@PURE_QUANTA.Q_CAP(CHIPS)':
 C_PATH='@t6g_mb_lib.t6g(sch_1):page183_i26@pure_quanta.q_cap(chips)',
 P_PATH='@t6g_mb_lib.t6g(sch_1):page208_i26@pure_quanta.q_cap(chips)',
 PATH='I26',
 DRAWING='@T6G_MB_LIB.T6G(SCH_1):PAGE183',
 TOLERANCE='10%',
 MATERIAL='EMPTY',
 PHYS_PAGE='208',
 XY='(-4550,1300)',
 ROT='0',
 VER='1',
 PACK_TYPE='C0402',
 LOCATION='PC168',
 CDS_LIB='pure_quanta',
 CDS_PART_NAME='Q_CAP_C0402-560PF,50V,10%,EMPTY,CH1566K1B09',
 VOLTAGE='50V',
 PART_NUMBER='CH1566K1B09',
 VALUE='560PF',
 PRIM_FILE='./archive_libs/logical/q_cap/chips/chips.prt';

PART_NAME
 PC168_2 'Q_CAP_C0805-22UF,4V,20%,X6S,CH622KMEA03':;

SECTION_NUMBER 1
 '@T6G_MB_LIB.T6G(SCH_1):PAGE180_I51@PURE_QUANTA.Q_CAP(CHIPS)':
 C_PATH='@t6g_mb_lib.t6g(sch_1):page180_i51@pure_quanta.q_cap(chips)',
 P_PATH='@t6g_mb_lib.t6g(sch_1):page205_i51@pure_quanta.q_cap(chips)',
 PATH='I51',
 DRAWING='@T6G_MB_LIB.T6G(SCH_1):PAGE180',
 TOLERANCE='20%',
 MATERIAL='X6S',
 PHYS_PAGE='205',
 XY='(7650,1975)',
 ROT='0',
 VER='1',
 PACK_TYPE='C0805',
 LOCATION='PC168_2',
 CDS_LIB='pure_quanta',
 CDS_PART_NAME='Q_CAP_C0805-22UF,4V,20%,X6S,CH622KMEA03',
 VOLTAGE='4V',
 PART_NUMBER='CH622KMEA03',
 VALUE='22UF',
 PRIM_FILE='./archive_libs/logical/q_cap/chips/chips.prt';

PART_NAME
 PC169 'Q_CAP_C0402-560PF,50V,10%,EMPTY,CH1566K1B09':;

SECTION_NUMBER 1
 '@T6G_MB_LIB.T6G(SCH_1):PAGE183_I45@PURE_QUANTA.Q_CAP(CHIPS)':
 C_PATH='@t6g_mb_lib.t6g(sch_1):page183_i45@pure_quanta.q_cap(chips)',
 P_PATH='@t6g_mb_lib.t6g(sch_1):page208_i45@pure_quanta.q_cap(chips)',
 PATH='I45',
 DRAWING='@T6G_MB_LIB.T6G(SCH_1):PAGE183',
 TOLERANCE='10%',
 MATERIAL='EMPTY',
 PHYS_PAGE='208',
 XY='(-4650,4225)',
 ROT='0',
 VER='1',
 PACK_TYPE='C0402',
 LOCATION='PC169',
 CDS_LIB='pure_quanta',
 CDS_PART_NAME='Q_CAP_C0402-560PF,50V,10%,EMPTY,CH1566K1B09',
 VOLTAGE='50V',
 PART_NUMBER='CH1566K1B09',
 VALUE='560PF',
 PRIM_FILE='./archive_libs/logical/q_cap/chips/chips.prt';

PART_NAME
 PC169_1 'Q_CAP_C0805-22UF,4V,20%,X6S,CH622KMEA03':;

SECTION_NUMBER 1
 '@T6G_MB_LIB.T6G(SCH_1):PAGE180_I75@PURE_QUANTA.Q_CAP(CHIPS)':
 C_PATH='@t6g_mb_lib.t6g(sch_1):page180_i75@pure_quanta.q_cap(chips)',
 P_PATH='@t6g_mb_lib.t6g(sch_1):page205_i75@pure_quanta.q_cap(chips)',
 PATH='I75',
 DRAWING='@T6G_MB_LIB.T6G(SCH_1):PAGE180',
 TOLERANCE='20%',
 MATERIAL='X6S',
 PHYS_PAGE='205',
 XY='(8125,4775)',
 ROT='0',
 VER='1',
 PACK_TYPE='C0805',
 LOCATION='PC169_1',
 CDS_LIB='pure_quanta',
 CDS_PART_NAME='Q_CAP_C0805-22UF,4V,20%,X6S,CH622KMEA03',
 VOLTAGE='4V',
 PART_NUMBER='CH622KMEA03',
 VALUE='22UF',
 PRIM_FILE='./archive_libs/logical/q_cap/chips/chips.prt';

PART_NAME
 PC170 'Q_CAP_C0402-560PF,50V,10%,EMPTY,CH1566K1B09':;

SECTION_NUMBER 1
 '@T6G_MB_LIB.T6G(SCH_1):PAGE186_I48@PURE_QUANTA.Q_CAP(CHIPS)':
 C_PATH='@t6g_mb_lib.t6g(sch_1):page186_i48@pure_quanta.q_cap(chips)',
 P_PATH='@t6g_mb_lib.t6g(sch_1):page211_i48@pure_quanta.q_cap(chips)',
 PATH='I48',
 DRAWING='@T6G_MB_LIB.T6G(SCH_1):PAGE186',
 TOLERANCE='10%',
 MATERIAL='EMPTY',
 PHYS_PAGE='211',
 XY='(-4800,4250)',
 ROT='0',
 VER='1',
 PACK_TYPE='C0402',
 LOCATION='PC170',
 CDS_LIB='pure_quanta',
 CDS_PART_NAME='Q_CAP_C0402-560PF,50V,10%,EMPTY,CH1566K1B09',
 VOLTAGE='50V',
 PART_NUMBER='CH1566K1B09',
 VALUE='560PF',
 PRIM_FILE='./archive_libs/logical/q_cap/chips/chips.prt';

PART_NAME
 PC170_2 'Q_CAP_C0805-22UF,4V,20%,X6S,CH622KMEA03':;

SECTION_NUMBER 1
 '@T6G_MB_LIB.T6G(SCH_1):PAGE180_I53@PURE_QUANTA.Q_CAP(CHIPS)':
 C_PATH='@t6g_mb_lib.t6g(sch_1):page180_i53@pure_quanta.q_cap(chips)',
 P_PATH='@t6g_mb_lib.t6g(sch_1):page205_i53@pure_quanta.q_cap(chips)',
 PATH='I53',
 DRAWING='@T6G_MB_LIB.T6G(SCH_1):PAGE180',
 TOLERANCE='20%',
 MATERIAL='X6S',
 PHYS_PAGE='205',
 XY='(8075,1975)',
 ROT='0',
 VER='1',
 PACK_TYPE='C0805',
 LOCATION='PC170_2',
 CDS_LIB='pure_quanta',
 CDS_PART_NAME='Q_CAP_C0805-22UF,4V,20%,X6S,CH622KMEA03',
 VOLTAGE='4V',
 PART_NUMBER='CH622KMEA03',
 VALUE='22UF',
 PRIM_FILE='./archive_libs/logical/q_cap/chips/chips.prt';

PART_NAME
 PC171 'Q_CAP_C0402-2.2UF,10V,10%,X6S,CH5222KEB01':;

SECTION_NUMBER 1
 '@T6G_MB_LIB.T6G(SCH_1):PAGE181_I10@PURE_QUANTA.Q_CAP(CHIPS)':
 C_PATH='@t6g_mb_lib.t6g(sch_1):page181_i10@pure_quanta.q_cap(chips)',
 P_PATH='@t6g_mb_lib.t6g(sch_1):page206_i10@pure_quanta.q_cap(chips)',
 PATH='I10',
 DRAWING='@T6G_MB_LIB.T6G(SCH_1):PAGE181',
 TOLERANCE='10%',
 MATERIAL='X6S',
 PHYS_PAGE='206',
 XY='(-11050,3025)',
 ROT='0',
 VER='1',
 PACK_TYPE='C0402',
 LOCATION='PC171',
 CDS_LIB='pure_quanta',
 CDS_PART_NAME='Q_CAP_C0402-2.2UF,10V,10%,X6S,CH5222KEB01',
 VOLTAGE='10V',
 PART_NUMBER='CH5222KEB01',
 VALUE='2.2UF',
 PRIM_FILE='./archive_libs/logical/q_cap/chips/chips.prt';

PART_NAME
 PC172 'Q_CAP_C0402-2.2UF,10V,10%,X6S,CH5222KEB01':;

SECTION_NUMBER 1
 '@T6G_MB_LIB.T6G(SCH_1):PAGE181_I27@PURE_QUANTA.Q_CAP(CHIPS)':
 C_PATH='@t6g_mb_lib.t6g(sch_1):page181_i27@pure_quanta.q_cap(chips)',
 P_PATH='@t6g_mb_lib.t6g(sch_1):page206_i27@pure_quanta.q_cap(chips)',
 PATH='I27',
 DRAWING='@T6G_MB_LIB.T6G(SCH_1):PAGE181',
 TOLERANCE='10%',
 MATERIAL='X6S',
 PHYS_PAGE='206',
 XY='(-11025,5725)',
 ROT='0',
 VER='1',
 PACK_TYPE='C0402',
 LOCATION='PC172',
 CDS_LIB='pure_quanta',
 CDS_PART_NAME='Q_CAP_C0402-2.2UF,10V,10%,X6S,CH5222KEB01',
 VOLTAGE='10V',
 PART_NUMBER='CH5222KEB01',
 VALUE='2.2UF',
 PRIM_FILE='./archive_libs/logical/q_cap/chips/chips.prt';

PART_NAME
 PC173 'Q_CAP_C0402-560PF,50V,10%,EMPTY,CH1566K1B09':;

SECTION_NUMBER 1
 '@T6G_MB_LIB.T6G(SCH_1):PAGE186_I24@PURE_QUANTA.Q_CAP(CHIPS)':
 C_PATH='@t6g_mb_lib.t6g(sch_1):page186_i24@pure_quanta.q_cap(chips)',
 P_PATH='@t6g_mb_lib.t6g(sch_1):page211_i24@pure_quanta.q_cap(chips)',
 PATH='I24',
 DRAWING='@T6G_MB_LIB.T6G(SCH_1):PAGE186',
 TOLERANCE='10%',
 MATERIAL='EMPTY',
 PHYS_PAGE='211',
 XY='(-4650,1500)',
 ROT='0',
 VER='1',
 PACK_TYPE='C0402',
 LOCATION='PC173',
 CDS_LIB='pure_quanta',
 CDS_PART_NAME='Q_CAP_C0402-560PF,50V,10%,EMPTY,CH1566K1B09',
 VOLTAGE='50V',
 PART_NUMBER='CH1566K1B09',
 VALUE='560PF',
 PRIM_FILE='./archive_libs/logical/q_cap/chips/chips.prt';

PART_NAME
 PC173_IOP0_4 'Q_CAP_C0402-2.2UF,10V,10%,X6S,CH5222KEB01':;

SECTION_NUMBER 1
 '@T6G_MB_LIB.T6G(SCH_1):PAGE181_I13@PURE_QUANTA.Q_CAP(CHIPS)':
 C_PATH='@t6g_mb_lib.t6g(sch_1):page181_i13@pure_quanta.q_cap(chips)',
 P_PATH='@t6g_mb_lib.t6g(sch_1):page206_i13@pure_quanta.q_cap(chips)',
 PATH='I13',
 DRAWING='@T6G_MB_LIB.T6G(SCH_1):PAGE181',
 TOLERANCE='10%',
 MATERIAL='X6S',
 PHYS_PAGE='206',
 XY='(-10700,3600)',
 ROT='0',
 VER='1',
 PACK_TYPE='C0402',
 LOCATION='PC173_IOP0_4',
 CDS_LIB='pure_quanta',
 CDS_PART_NAME='Q_CAP_C0402-2.2UF,10V,10%,X6S,CH5222KEB01',
 VOLTAGE='10V',
 PART_NUMBER='CH5222KEB01',
 VALUE='2.2UF',
 PRIM_FILE='./archive_libs/logical/q_cap/chips/chips.prt';

PART_NAME
 PC174 'Q_CAP_C0402-560PF,50V,10%,EMPTY,CH1566K1B09':;

SECTION_NUMBER 1
 '@T6G_MB_LIB.T6G(SCH_1):PAGE197_I40@PURE_QUANTA.Q_CAP(CHIPS)':
 C_PATH='@t6g_mb_lib.t6g(sch_1):page197_i40@pure_quanta.q_cap(chips)',
 P_PATH='@t6g_mb_lib.t6g(sch_1):page222_i40@pure_quanta.q_cap(chips)',
 PATH='I40',
 DRAWING='@T6G_MB_LIB.T6G(SCH_1):PAGE197',
 TOLERANCE='10%',
 MATERIAL='EMPTY',
 PHYS_PAGE='222',
 XY='(4125,4800)',
 ROT='0',
 VER='1',
 PACK_TYPE='C0402',
 LOCATION='PC174',
 CDS_LIB='pure_quanta',
 CDS_PART_NAME='Q_CAP_C0402-560PF,50V,10%,EMPTY,CH1566K1B09',
 VOLTAGE='50V',
 PART_NUMBER='CH1566K1B09',
 VALUE='560PF',
 PRIM_FILE='./archive_libs/logical/q_cap/chips/chips.prt';

PART_NAME
 PC174_IOP0_3 'Q_CAP_C0402-2.2UF,10V,10%,X6S,CH5222KEB01':;

SECTION_NUMBER 1
 '@T6G_MB_LIB.T6G(SCH_1):PAGE181_I30@PURE_QUANTA.Q_CAP(CHIPS)':
 C_PATH='@t6g_mb_lib.t6g(sch_1):page181_i30@pure_quanta.q_cap(chips)',
 P_PATH='@t6g_mb_lib.t6g(sch_1):page206_i30@pure_quanta.q_cap(chips)',
 PATH='I30',
 DRAWING='@T6G_MB_LIB.T6G(SCH_1):PAGE181',
 TOLERANCE='10%',
 MATERIAL='X6S',
 PHYS_PAGE='206',
 XY='(-10675,6300)',
 ROT='0',
 VER='1',
 PACK_TYPE='C0402',
 LOCATION='PC174_IOP0_3',
 CDS_LIB='pure_quanta',
 CDS_PART_NAME='Q_CAP_C0402-2.2UF,10V,10%,X6S,CH5222KEB01',
 VOLTAGE='10V',
 PART_NUMBER='CH5222KEB01',
 VALUE='2.2UF',
 PRIM_FILE='./archive_libs/logical/q_cap/chips/chips.prt';

PART_NAME
 PC175 'Q_CAP_C0402-560PF,50V,10%,EMPTY,CH1566K1B09':;

SECTION_NUMBER 1
 '@T6G_MB_LIB.T6G(SCH_1):PAGE197_I20@PURE_QUANTA.Q_CAP(CHIPS)':
 C_PATH='@t6g_mb_lib.t6g(sch_1):page197_i20@pure_quanta.q_cap(chips)',
 P_PATH='@t6g_mb_lib.t6g(sch_1):page222_i20@pure_quanta.q_cap(chips)',
 PATH='I20',
 DRAWING='@T6G_MB_LIB.T6G(SCH_1):PAGE197',
 TOLERANCE='10%',
 MATERIAL='EMPTY',
 PHYS_PAGE='222',
 XY='(4025,2050)',
 ROT='0',
 VER='1',
 PACK_TYPE='C0402',
 LOCATION='PC175',
 CDS_LIB='pure_quanta',
 CDS_PART_NAME='Q_CAP_C0402-560PF,50V,10%,EMPTY,CH1566K1B09',
 VOLTAGE='50V',
 PART_NUMBER='CH1566K1B09',
 VALUE='560PF',
 PRIM_FILE='./archive_libs/logical/q_cap/chips/chips.prt';

PART_NAME
 PC175_9 'Q_CAP_0402-0.1UF,25V,10%,X7R,CH4104K1B00':;

SECTION_NUMBER 1
 '@T6G_MB_LIB.T6G(SCH_1):PAGE181_I19@PURE_QUANTA.Q_CAP(CHIPS)':
 C_PATH='@t6g_mb_lib.t6g(sch_1):page181_i19@pure_quanta.q_cap(chips)',
 P_PATH='@t6g_mb_lib.t6g(sch_1):page206_i19@pure_quanta.q_cap(chips)',
 PATH='I19',
 DRAWING='@T6G_MB_LIB.T6G(SCH_1):PAGE181',
 TOLERANCE='10%',
 MATERIAL='X7R',
 PHYS_PAGE='206',
 XY='(-11925,5050)',
 ROT='0',
 VER='1',
 PACK_TYPE='0402',
 LOCATION='PC175_9',
 CDS_LIB='pure_quanta',
 CDS_PART_NAME='Q_CAP_0402-0.1UF,25V,10%,X7R,CH4104K1B00',
 VOLTAGE='25V',
 PART_NUMBER='CH4104K1B00',
 VALUE='0.1UF',
 PRIM_FILE='./archive_libs/logical/q_cap/chips/chips.prt';

PART_NAME
 PC176 'Q_CAP_C0402-560PF,50V,10%,EMPTY,CH1566K1B09':;

SECTION_NUMBER 1
 '@T6G_MB_LIB.T6G(SCH_1):PAGE198_I37@PURE_QUANTA.Q_CAP(CHIPS)':
 C_PATH='@t6g_mb_lib.t6g(sch_1):page198_i37@pure_quanta.q_cap(chips)',
 P_PATH='@t6g_mb_lib.t6g(sch_1):page223_i37@pure_quanta.q_cap(chips)',
 PATH='I37',
 DRAWING='@T6G_MB_LIB.T6G(SCH_1):PAGE198',
 TOLERANCE='10%',
 MATERIAL='EMPTY',
 PHYS_PAGE='223',
 XY='(-8025,2100)',
 ROT='0',
 VER='1',
 PACK_TYPE='C0402',
 LOCATION='PC176',
 CDS_LIB='pure_quanta',
 CDS_PART_NAME='Q_CAP_C0402-560PF,50V,10%,EMPTY,CH1566K1B09',
 VOLTAGE='50V',
 PART_NUMBER='CH1566K1B09',
 VALUE='560PF',
 PRIM_FILE='./archive_libs/logical/q_cap/chips/chips.prt';

PART_NAME
 PC176_10 'Q_CAP_0402-0.1UF,25V,10%,X7R,CH4104K1B00':;

SECTION_NUMBER 1
 '@T6G_MB_LIB.T6G(SCH_1):PAGE181_I1@PURE_QUANTA.Q_CAP(CHIPS)':
 C_PATH='@t6g_mb_lib.t6g(sch_1):page181_i1@pure_quanta.q_cap(chips)',
 P_PATH='@t6g_mb_lib.t6g(sch_1):page206_i1@pure_quanta.q_cap(chips)',
 PATH='I1',
 DRAWING='@T6G_MB_LIB.T6G(SCH_1):PAGE181',
 TOLERANCE='10%',
 MATERIAL='X7R',
 PHYS_PAGE='206',
 XY='(-11900,2250)',
 ROT='0',
 VER='1',
 PACK_TYPE='0402',
 LOCATION='PC176_10',
 CDS_LIB='pure_quanta',
 CDS_PART_NAME='Q_CAP_0402-0.1UF,25V,10%,X7R,CH4104K1B00',
 VOLTAGE='25V',
 PART_NUMBER='CH4104K1B00',
 VALUE='0.1UF',
 PRIM_FILE='./archive_libs/logical/q_cap/chips/chips.prt';

PART_NAME
 PC177 'Q_CAP_C0402-560PF,50V,10%,EMPTY,CH1566K1B09':;

SECTION_NUMBER 1
 '@T6G_MB_LIB.T6G(SCH_1):PAGE198_I58@PURE_QUANTA.Q_CAP(CHIPS)':
 C_PATH='@t6g_mb_lib.t6g(sch_1):page198_i58@pure_quanta.q_cap(chips)',
 P_PATH='@t6g_mb_lib.t6g(sch_1):page223_i58@pure_quanta.q_cap(chips)',
 PATH='I58',
 DRAWING='@T6G_MB_LIB.T6G(SCH_1):PAGE198',
 TOLERANCE='10%',
 MATERIAL='EMPTY',
 PHYS_PAGE='223',
 XY='(-7925,4900)',
 ROT='0',
 VER='1',
 PACK_TYPE='C0402',
 LOCATION='PC177',
 CDS_LIB='pure_quanta',
 CDS_PART_NAME='Q_CAP_C0402-560PF,50V,10%,EMPTY,CH1566K1B09',
 VOLTAGE='50V',
 PART_NUMBER='CH1566K1B09',
 VALUE='560PF',
 PRIM_FILE='./archive_libs/logical/q_cap/chips/chips.prt';

PART_NAME
 PC177_3 'Q_CAP_0402-0.1UF,25V,10%,X7R,CH4104K1B00':;

SECTION_NUMBER 1
 '@T6G_MB_LIB.T6G(SCH_1):PAGE181_I35@PURE_QUANTA.Q_CAP(CHIPS)':
 C_PATH='@t6g_mb_lib.t6g(sch_1):page181_i35@pure_quanta.q_cap(chips)',
 P_PATH='@t6g_mb_lib.t6g(sch_1):page206_i35@pure_quanta.q_cap(chips)',
 PATH='I35',
 DRAWING='@T6G_MB_LIB.T6G(SCH_1):PAGE181',
 TOLERANCE='10%',
 MATERIAL='X7R',
 PHYS_PAGE='206',
 XY='(-8500,6375)',
 ROT='0',
 VER='1',
 PACK_TYPE='0402',
 LOCATION='PC177_3',
 CDS_LIB='pure_quanta',
 CDS_PART_NAME='Q_CAP_0402-0.1UF,25V,10%,X7R,CH4104K1B00',
 VOLTAGE='25V',
 PART_NUMBER='CH4104K1B00',
 VALUE='0.1UF',
 PRIM_FILE='./archive_libs/logical/q_cap/chips/chips.prt';

PART_NAME
 PC178 'Q_CAP_C0402-560PF,50V,10%,EMPTY,CH1566K1B09':;

SECTION_NUMBER 1
 '@T6G_MB_LIB.T6G(SCH_1):PAGE169_I54@PURE_QUANTA.Q_CAP(CHIPS)':
 C_PATH='@t6g_mb_lib.t6g(sch_1):page169_i54@pure_quanta.q_cap(chips)',
 P_PATH='@t6g_mb_lib.t6g(sch_1):page194_i54@pure_quanta.q_cap(chips)',
 PATH='I54',
 DRAWING='@T6G_MB_LIB.T6G(SCH_1):PAGE169',
 TOLERANCE='10%',
 MATERIAL='EMPTY',
 PHYS_PAGE='194',
 XY='(-4825,4175)',
 ROT='0',
 VER='1',
 PACK_TYPE='C0402',
 LOCATION='PC178',
 CDS_LIB='pure_quanta',
 CDS_PART_NAME='Q_CAP_C0402-560PF,50V,10%,EMPTY,CH1566K1B09',
 VOLTAGE='50V',
 PART_NUMBER='CH1566K1B09',
 VALUE='560PF',
 PRIM_FILE='./archive_libs/logical/q_cap/chips/chips.prt';

PART_NAME
 PC178_4 'Q_CAP_0402-0.1UF,25V,10%,X7R,CH4104K1B00':;

SECTION_NUMBER 1
 '@T6G_MB_LIB.T6G(SCH_1):PAGE181_I17@PURE_QUANTA.Q_CAP(CHIPS)':
 C_PATH='@t6g_mb_lib.t6g(sch_1):page181_i17@pure_quanta.q_cap(chips)',
 P_PATH='@t6g_mb_lib.t6g(sch_1):page206_i17@pure_quanta.q_cap(chips)',
 PATH='I17',
 DRAWING='@T6G_MB_LIB.T6G(SCH_1):PAGE181',
 TOLERANCE='10%',
 MATERIAL='X7R',
 PHYS_PAGE='206',
 XY='(-8475,3600)',
 ROT='0',
 VER='1',
 PACK_TYPE='0402',
 LOCATION='PC178_4',
 CDS_LIB='pure_quanta',
 CDS_PART_NAME='Q_CAP_0402-0.1UF,25V,10%,X7R,CH4104K1B00',
 VOLTAGE='25V',
 PART_NUMBER='CH4104K1B00',
 VALUE='0.1UF',
 PRIM_FILE='./archive_libs/logical/q_cap/chips/chips.prt';

PART_NAME
 PC179 'Q_CAP_C0402-560PF,50V,10%,EMPTY,CH1566K1B09':;

SECTION_NUMBER 1
 '@T6G_MB_LIB.T6G(SCH_1):PAGE169_I31@PURE_QUANTA.Q_CAP(CHIPS)':
 C_PATH='@t6g_mb_lib.t6g(sch_1):page169_i31@pure_quanta.q_cap(chips)',
 P_PATH='@t6g_mb_lib.t6g(sch_1):page194_i31@pure_quanta.q_cap(chips)',
 PATH='I31',
 DRAWING='@T6G_MB_LIB.T6G(SCH_1):PAGE169',
 TOLERANCE='10%',
 MATERIAL='EMPTY',
 PHYS_PAGE='194',
 XY='(-4650,1425)',
 ROT='0',
 VER='1',
 PACK_TYPE='C0402',
 LOCATION='PC179',
 CDS_LIB='pure_quanta',
 CDS_PART_NAME='Q_CAP_C0402-560PF,50V,10%,EMPTY,CH1566K1B09',
 VOLTAGE='50V',
 PART_NUMBER='CH1566K1B09',
 VALUE='560PF',
 PRIM_FILE='./archive_libs/logical/q_cap/chips/chips.prt';

PART_NAME
 PC179_3 'Q_CAP_C0402-1UF,25V,10%,X6S,CH5104KEB02':;

SECTION_NUMBER 1
 '@T6G_MB_LIB.T6G(SCH_1):PAGE181_I36@PURE_QUANTA.Q_CAP(CHIPS)':
 C_PATH='@t6g_mb_lib.t6g(sch_1):page181_i36@pure_quanta.q_cap(chips)',
 P_PATH='@t6g_mb_lib.t6g(sch_1):page206_i36@pure_quanta.q_cap(chips)',
 PATH='I36',
 DRAWING='@T6G_MB_LIB.T6G(SCH_1):PAGE181',
 TOLERANCE='10%',
 MATERIAL='X6S',
 PHYS_PAGE='206',
 XY='(-8075,6375)',
 ROT='0',
 VER='1',
 PACK_TYPE='C0402',
 LOCATION='PC179_3',
 CDS_LIB='pure_quanta',
 CDS_PART_NAME='Q_CAP_C0402-1UF,25V,10%,X6S,CH5104KEB02',
 VOLTAGE='25V',
 PART_NUMBER='CH5104KEB02',
 VALUE='1UF',
 PRIM_FILE='./archive_libs/logical/q_cap/chips/chips.prt';

PART_NAME
 PC180 'Q_CAP_C0402-560PF,50V,10%,EMPTY,CH1566K1B09':;

SECTION_NUMBER 1
 '@T6G_MB_LIB.T6G(SCH_1):PAGE170_I45@PURE_QUANTA.Q_CAP(CHIPS)':
 C_PATH='@t6g_mb_lib.t6g(sch_1):page170_i45@pure_quanta.q_cap(chips)',
 P_PATH='@t6g_mb_lib.t6g(sch_1):page195_i45@pure_quanta.q_cap(chips)',
 PATH='I45',
 DRAWING='@T6G_MB_LIB.T6G(SCH_1):PAGE170',
 TOLERANCE='10%',
 MATERIAL='EMPTY',
 PHYS_PAGE='195',
 XY='(-4375,4625)',
 ROT='0',
 VER='1',
 PACK_TYPE='C0402',
 LOCATION='PC180',
 CDS_LIB='pure_quanta',
 CDS_PART_NAME='Q_CAP_C0402-560PF,50V,10%,EMPTY,CH1566K1B09',
 VOLTAGE='50V',
 PART_NUMBER='CH1566K1B09',
 VALUE='560PF',
 PRIM_FILE='./archive_libs/logical/q_cap/chips/chips.prt';

PART_NAME
 PC180_4 'Q_CAP_C0402-1UF,25V,10%,X6S,CH5104KEB02':;

SECTION_NUMBER 1
 '@T6G_MB_LIB.T6G(SCH_1):PAGE181_I45@PURE_QUANTA.Q_CAP(CHIPS)':
 C_PATH='@t6g_mb_lib.t6g(sch_1):page181_i45@pure_quanta.q_cap(chips)',
 P_PATH='@t6g_mb_lib.t6g(sch_1):page206_i45@pure_quanta.q_cap(chips)',
 PATH='I45',
 DRAWING='@T6G_MB_LIB.T6G(SCH_1):PAGE181',
 TOLERANCE='10%',
 MATERIAL='X6S',
 PHYS_PAGE='206',
 XY='(-8000,3575)',
 ROT='0',
 VER='1',
 PACK_TYPE='C0402',
 LOCATION='PC180_4',
 CDS_LIB='pure_quanta',
 CDS_PART_NAME='Q_CAP_C0402-1UF,25V,10%,X6S,CH5104KEB02',
 VOLTAGE='25V',
 PART_NUMBER='CH5104KEB02',
 VALUE='1UF',
 PRIM_FILE='./archive_libs/logical/q_cap/chips/chips.prt';

PART_NAME
 PC181 'Q_CAP_C0402-560PF,50V,10%,EMPTY,CH1566K1B09':;

SECTION_NUMBER 1
 '@T6G_MB_LIB.T6G(SCH_1):PAGE170_I19@PURE_QUANTA.Q_CAP(CHIPS)':
 C_PATH='@t6g_mb_lib.t6g(sch_1):page170_i19@pure_quanta.q_cap(chips)',
 P_PATH='@t6g_mb_lib.t6g(sch_1):page195_i19@pure_quanta.q_cap(chips)',
 PATH='I19',
 DRAWING='@T6G_MB_LIB.T6G(SCH_1):PAGE170',
 TOLERANCE='10%',
 MATERIAL='EMPTY',
 PHYS_PAGE='195',
 XY='(-4300,1325)',
 ROT='0',
 VER='1',
 PACK_TYPE='C0402',
 LOCATION='PC181',
 CDS_LIB='pure_quanta',
 CDS_PART_NAME='Q_CAP_C0402-560PF,50V,10%,EMPTY,CH1566K1B09',
 VOLTAGE='50V',
 PART_NUMBER='CH1566K1B09',
 VALUE='560PF',
 PRIM_FILE='./archive_libs/logical/q_cap/chips/chips.prt';

PART_NAME
 PC181_3 'Q_CAP_C0805-22UF,16V,20%,X6S,CH6223MEA01':;

SECTION_NUMBER 1
 '@T6G_MB_LIB.T6G(SCH_1):PAGE181_I58@PURE_QUANTA.Q_CAP(CHIPS)':
 C_PATH='@t6g_mb_lib.t6g(sch_1):page181_i58@pure_quanta.q_cap(chips)',
 P_PATH='@t6g_mb_lib.t6g(sch_1):page206_i58@pure_quanta.q_cap(chips)',
 PATH='I58',
 DRAWING='@T6G_MB_LIB.T6G(SCH_1):PAGE181',
 TOLERANCE='20%',
 MATERIAL='X6S',
 PHYS_PAGE='206',
 XY='(-7675,6375)',
 ROT='0',
 VER='1',
 PACK_TYPE='C0805',
 LOCATION='PC181_3',
 CDS_LIB='pure_quanta',
 CDS_PART_NAME='Q_CAP_C0805-22UF,16V,20%,X6S,CH6223MEA01',
 VOLTAGE='16V',
 PART_NUMBER='CH6223MEA01',
 VALUE='22UF',
 PRIM_FILE='./archive_libs/logical/q_cap/chips/chips.prt';

PART_NAME
 PC182 'Q_CAP_C0402-560PF,50V,10%,EMPTY,CH1566K1B09':;

SECTION_NUMBER 1
 '@T6G_MB_LIB.T6G(SCH_1):PAGE171_I23@PURE_QUANTA.Q_CAP(CHIPS)':
 C_PATH='@t6g_mb_lib.t6g(sch_1):page171_i23@pure_quanta.q_cap(chips)',
 P_PATH='@t6g_mb_lib.t6g(sch_1):page196_i23@pure_quanta.q_cap(chips)',
 PATH='I23',
 DRAWING='@T6G_MB_LIB.T6G(SCH_1):PAGE171',
 TOLERANCE='10%',
 MATERIAL='EMPTY',
 PHYS_PAGE='196',
 XY='(-4225,1675)',
 ROT='0',
 VER='1',
 PACK_TYPE='C0402',
 LOCATION='PC182',
 CDS_LIB='pure_quanta',
 CDS_PART_NAME='Q_CAP_C0402-560PF,50V,10%,EMPTY,CH1566K1B09',
 VOLTAGE='50V',
 PART_NUMBER='CH1566K1B09',
 VALUE='560PF',
 PRIM_FILE='./archive_libs/logical/q_cap/chips/chips.prt';

PART_NAME
 PC182_4 'Q_CAP_C0805-22UF,16V,20%,X6S,CH6223MEA01':;

SECTION_NUMBER 1
 '@T6G_MB_LIB.T6G(SCH_1):PAGE181_I46@PURE_QUANTA.Q_CAP(CHIPS)':
 C_PATH='@t6g_mb_lib.t6g(sch_1):page181_i46@pure_quanta.q_cap(chips)',
 P_PATH='@t6g_mb_lib.t6g(sch_1):page206_i46@pure_quanta.q_cap(chips)',
 PATH='I46',
 DRAWING='@T6G_MB_LIB.T6G(SCH_1):PAGE181',
 TOLERANCE='20%',
 MATERIAL='X6S',
 PHYS_PAGE='206',
 XY='(-7600,3575)',
 ROT='0',
 VER='1',
 PACK_TYPE='C0805',
 LOCATION='PC182_4',
 CDS_LIB='pure_quanta',
 CDS_PART_NAME='Q_CAP_C0805-22UF,16V,20%,X6S,CH6223MEA01',
 VOLTAGE='16V',
 PART_NUMBER='CH6223MEA01',
 VALUE='22UF',
 PRIM_FILE='./archive_libs/logical/q_cap/chips/chips.prt';

PART_NAME
 PC183 'Q_CAP_0402-0.22UF,16V,10%,X7R,CH4223K1B00':;

SECTION_NUMBER 1
 '@T6G_MB_LIB.T6G(SCH_1):PAGE181_I44@PURE_QUANTA.Q_CAP(CHIPS)':
 C_PATH='@t6g_mb_lib.t6g(sch_1):page181_i44@pure_quanta.q_cap(chips)',
 P_PATH='@t6g_mb_lib.t6g(sch_1):page206_i44@pure_quanta.q_cap(chips)',
 PATH='I44',
 DRAWING='@T6G_MB_LIB.T6G(SCH_1):PAGE181',
 TOLERANCE='10%',
 MATERIAL='X7R',
 PHYS_PAGE='206',
 XY='(-7350,2850)',
 ROT='0',
 VER='1',
 PACK_TYPE='0402',
 LOCATION='PC183',
 CDS_LIB='pure_quanta',
 CDS_PART_NAME='Q_CAP_0402-0.22UF,16V,10%,X7R,CH4223K1B00',
 VOLTAGE='16V',
 PART_NUMBER='CH4223K1B00',
 VALUE='0.22UF',
 PRIM_FILE='./archive_libs/logical/q_cap/chips/chips.prt';

PART_NAME
 PC184 'Q_CAP_C0402-560PF,50V,10%,EMPTY,CH1566K1B09':;

SECTION_NUMBER 1
 '@T6G_MB_LIB.T6G(SCH_1):PAGE171_I46@PURE_QUANTA.Q_CAP(CHIPS)':
 C_PATH='@t6g_mb_lib.t6g(sch_1):page171_i46@pure_quanta.q_cap(chips)',
 P_PATH='@t6g_mb_lib.t6g(sch_1):page196_i46@pure_quanta.q_cap(chips)',
 PATH='I46',
 DRAWING='@T6G_MB_LIB.T6G(SCH_1):PAGE171',
 TOLERANCE='10%',
 MATERIAL='EMPTY',
 PHYS_PAGE='196',
 XY='(-4200,4400)',
 ROT='0',
 VER='1',
 PACK_TYPE='C0402',
 LOCATION='PC184',
 CDS_LIB='pure_quanta',
 CDS_PART_NAME='Q_CAP_C0402-560PF,50V,10%,EMPTY,CH1566K1B09',
 VOLTAGE='50V',
 PART_NUMBER='CH1566K1B09',
 VALUE='560PF',
 PRIM_FILE='./archive_libs/logical/q_cap/chips/chips.prt';

PART_NAME
 PC184_3 'Q_CAP_C0805-22UF,16V,20%,X6S,CH6223MEA01':;

SECTION_NUMBER 1
 '@T6G_MB_LIB.T6G(SCH_1):PAGE181_I60@PURE_QUANTA.Q_CAP(CHIPS)':
 C_PATH='@t6g_mb_lib.t6g(sch_1):page181_i60@pure_quanta.q_cap(chips)',
 P_PATH='@t6g_mb_lib.t6g(sch_1):page206_i60@pure_quanta.q_cap(chips)',
 PATH='I60',
 DRAWING='@T6G_MB_LIB.T6G(SCH_1):PAGE181',
 TOLERANCE='20%',
 MATERIAL='X6S',
 PHYS_PAGE='206',
 XY='(-7275,6375)',
 ROT='0',
 VER='1',
 PACK_TYPE='C0805',
 LOCATION='PC184_3',
 CDS_LIB='pure_quanta',
 CDS_PART_NAME='Q_CAP_C0805-22UF,16V,20%,X6S,CH6223MEA01',
 VOLTAGE='16V',
 PART_NUMBER='CH6223MEA01',
 VALUE='22UF',
 PRIM_FILE='./archive_libs/logical/q_cap/chips/chips.prt';

PART_NAME
 PC185 'Q_CAP_C0402-560PF,50V,10%,EMPTY,CH1566K1B09':;

SECTION_NUMBER 1
 '@T6G_MB_LIB.T6G(SCH_1):PAGE173_I46@PURE_QUANTA.Q_CAP(CHIPS)':
 C_PATH='@t6g_mb_lib.t6g(sch_1):page173_i46@pure_quanta.q_cap(chips)',
 P_PATH='@t6g_mb_lib.t6g(sch_1):page198_i46@pure_quanta.q_cap(chips)',
 PATH='I46',
 DRAWING='@T6G_MB_LIB.T6G(SCH_1):PAGE173',
 TOLERANCE='10%',
 MATERIAL='EMPTY',
 PHYS_PAGE='198',
 XY='(-4475,4825)',
 ROT='0',
 VER='1',
 PACK_TYPE='C0402',
 LOCATION='PC185',
 CDS_LIB='pure_quanta',
 CDS_PART_NAME='Q_CAP_C0402-560PF,50V,10%,EMPTY,CH1566K1B09',
 VOLTAGE='50V',
 PART_NUMBER='CH1566K1B09',
 VALUE='560PF',
 PRIM_FILE='./archive_libs/logical/q_cap/chips/chips.prt';

PART_NAME
 PC185_4 'Q_CAP_C0805-22UF,16V,20%,X6S,CH6223MEA01':;

SECTION_NUMBER 1
 '@T6G_MB_LIB.T6G(SCH_1):PAGE181_I47@PURE_QUANTA.Q_CAP(CHIPS)':
 C_PATH='@t6g_mb_lib.t6g(sch_1):page181_i47@pure_quanta.q_cap(chips)',
 P_PATH='@t6g_mb_lib.t6g(sch_1):page206_i47@pure_quanta.q_cap(chips)',
 PATH='I47',
 DRAWING='@T6G_MB_LIB.T6G(SCH_1):PAGE181',
 TOLERANCE='20%',
 MATERIAL='X6S',
 PHYS_PAGE='206',
 XY='(-7200,3575)',
 ROT='0',
 VER='1',
 PACK_TYPE='C0805',
 LOCATION='PC185_4',
 CDS_LIB='pure_quanta',
 CDS_PART_NAME='Q_CAP_C0805-22UF,16V,20%,X6S,CH6223MEA01',
 VOLTAGE='16V',
 PART_NUMBER='CH6223MEA01',
 VALUE='22UF',
 PRIM_FILE='./archive_libs/logical/q_cap/chips/chips.prt';

PART_NAME
 PC186 'Q_CAP_0402-0.22UF,16V,10%,X7R,CH4223K1B00':;

SECTION_NUMBER 1
 '@T6G_MB_LIB.T6G(SCH_1):PAGE181_I59@PURE_QUANTA.Q_CAP(CHIPS)':
 C_PATH='@t6g_mb_lib.t6g(sch_1):page181_i59@pure_quanta.q_cap(chips)',
 P_PATH='@t6g_mb_lib.t6g(sch_1):page206_i59@pure_quanta.q_cap(chips)',
 PATH='I59',
 DRAWING='@T6G_MB_LIB.T6G(SCH_1):PAGE181',
 TOLERANCE='10%',
 MATERIAL='X7R',
 PHYS_PAGE='206',
 XY='(-7050,5650)',
 ROT='0',
 VER='1',
 PACK_TYPE='0402',
 LOCATION='PC186',
 CDS_LIB='pure_quanta',
 CDS_PART_NAME='Q_CAP_0402-0.22UF,16V,10%,X7R,CH4223K1B00',
 VOLTAGE='16V',
 PART_NUMBER='CH4223K1B00',
 VALUE='0.22UF',
 PRIM_FILE='./archive_libs/logical/q_cap/chips/chips.prt';

PART_NAME
 PC187 'Q_CAP_C0402-560PF,50V,10%,EMPTY,CH1566K1B09':;

SECTION_NUMBER 1
 '@T6G_MB_LIB.T6G(SCH_1):PAGE173_I85@PURE_QUANTA.Q_CAP(CHIPS)':
 C_PATH='@t6g_mb_lib.t6g(sch_1):page173_i85@pure_quanta.q_cap(chips)',
 P_PATH='@t6g_mb_lib.t6g(sch_1):page198_i85@pure_quanta.q_cap(chips)',
 PATH='I85',
 DRAWING='@T6G_MB_LIB.T6G(SCH_1):PAGE173',
 TOLERANCE='10%',
 MATERIAL='EMPTY',
 PHYS_PAGE='198',
 XY='(-4500,1800)',
 ROT='0',
 VER='1',
 PACK_TYPE='C0402',
 LOCATION='PC187',
 CDS_LIB='pure_quanta',
 CDS_PART_NAME='Q_CAP_C0402-560PF,50V,10%,EMPTY,CH1566K1B09',
 VOLTAGE='50V',
 PART_NUMBER='CH1566K1B09',
 VALUE='560PF',
 PRIM_FILE='./archive_libs/logical/q_cap/chips/chips.prt';

PART_NAME
 PC187_3 'Q_CAP_C0805-22UF,16V,20%,X6S,CH6223MEA01':;

SECTION_NUMBER 1
 '@T6G_MB_LIB.T6G(SCH_1):PAGE181_I63@PURE_QUANTA.Q_CAP(CHIPS)':
 C_PATH='@t6g_mb_lib.t6g(sch_1):page181_i63@pure_quanta.q_cap(chips)',
 P_PATH='@t6g_mb_lib.t6g(sch_1):page206_i63@pure_quanta.q_cap(chips)',
 PATH='I63',
 DRAWING='@T6G_MB_LIB.T6G(SCH_1):PAGE181',
 TOLERANCE='20%',
 MATERIAL='X6S',
 PHYS_PAGE='206',
 XY='(-6850,6400)',
 ROT='0',
 VER='1',
 PACK_TYPE='C0805',
 LOCATION='PC187_3',
 CDS_LIB='pure_quanta',
 CDS_PART_NAME='Q_CAP_C0805-22UF,16V,20%,X6S,CH6223MEA01',
 VOLTAGE='16V',
 PART_NUMBER='CH6223MEA01',
 VALUE='22UF',
 PRIM_FILE='./archive_libs/logical/q_cap/chips/chips.prt';

PART_NAME
 PC188 'Q_CAP_C0402-560PF,50V,10%,EMPTY,CH1566K1B09':;

SECTION_NUMBER 1
 '@T6G_MB_LIB.T6G(SCH_1):PAGE174_I12@PURE_QUANTA.Q_CAP(CHIPS)':
 C_PATH='@t6g_mb_lib.t6g(sch_1):page174_i12@pure_quanta.q_cap(chips)',
 P_PATH='@t6g_mb_lib.t6g(sch_1):page199_i12@pure_quanta.q_cap(chips)',
 PATH='I12',
 DRAWING='@T6G_MB_LIB.T6G(SCH_1):PAGE174',
 TOLERANCE='10%',
 MATERIAL='EMPTY',
 PHYS_PAGE='199',
 XY='(-4375,4050)',
 ROT='0',
 VER='1',
 PACK_TYPE='C0402',
 LOCATION='PC188',
 CDS_LIB='pure_quanta',
 CDS_PART_NAME='Q_CAP_C0402-560PF,50V,10%,EMPTY,CH1566K1B09',
 VOLTAGE='50V',
 PART_NUMBER='CH1566K1B09',
 VALUE='560PF',
 PRIM_FILE='./archive_libs/logical/q_cap/chips/chips.prt';

PART_NAME
 PC188_4 'Q_CAP_C0805-22UF,16V,20%,X6S,CH6223MEA01':;

SECTION_NUMBER 1
 '@T6G_MB_LIB.T6G(SCH_1):PAGE181_I49@PURE_QUANTA.Q_CAP(CHIPS)':
 C_PATH='@t6g_mb_lib.t6g(sch_1):page181_i49@pure_quanta.q_cap(chips)',
 P_PATH='@t6g_mb_lib.t6g(sch_1):page206_i49@pure_quanta.q_cap(chips)',
 PATH='I49',
 DRAWING='@T6G_MB_LIB.T6G(SCH_1):PAGE181',
 TOLERANCE='20%',
 MATERIAL='X6S',
 PHYS_PAGE='206',
 XY='(-6725,3575)',
 ROT='0',
 VER='1',
 PACK_TYPE='C0805',
 LOCATION='PC188_4',
 CDS_LIB='pure_quanta',
 CDS_PART_NAME='Q_CAP_C0805-22UF,16V,20%,X6S,CH6223MEA01',
 VOLTAGE='16V',
 PART_NUMBER='CH6223MEA01',
 VALUE='22UF',
 PRIM_FILE='./archive_libs/logical/q_cap/chips/chips.prt';

PART_NAME
 PC189 'Q_CAP_C0402-560PF,50V,10%,EMPTY,CH1566K1B09':;

SECTION_NUMBER 1
 '@T6G_MB_LIB.T6G(SCH_1):PAGE176_I57@PURE_QUANTA.Q_CAP(CHIPS)':
 C_PATH='@t6g_mb_lib.t6g(sch_1):page176_i57@pure_quanta.q_cap(chips)',
 P_PATH='@t6g_mb_lib.t6g(sch_1):page201_i57@pure_quanta.q_cap(chips)',
 PATH='I57',
 DRAWING='@T6G_MB_LIB.T6G(SCH_1):PAGE176',
 TOLERANCE='10%',
 MATERIAL='EMPTY',
 PHYS_PAGE='201',
 XY='(-5875,3950)',
 ROT='0',
 VER='1',
 PACK_TYPE='C0402',
 LOCATION='PC189',
 CDS_LIB='pure_quanta',
 CDS_PART_NAME='Q_CAP_C0402-560PF,50V,10%,EMPTY,CH1566K1B09',
 VOLTAGE='50V',
 PART_NUMBER='CH1566K1B09',
 VALUE='560PF',
 PRIM_FILE='./archive_libs/logical/q_cap/chips/chips.prt';

PART_NAME
 PC189_4 'Q_CAP_C0805-22UF,4V,20%,X6S,CH622KMEA03':;

SECTION_NUMBER 1
 '@T6G_MB_LIB.T6G(SCH_1):PAGE181_I53@PURE_QUANTA.Q_CAP(CHIPS)':
 C_PATH='@t6g_mb_lib.t6g(sch_1):page181_i53@pure_quanta.q_cap(chips)',
 P_PATH='@t6g_mb_lib.t6g(sch_1):page206_i53@pure_quanta.q_cap(chips)',
 PATH='I53',
 DRAWING='@T6G_MB_LIB.T6G(SCH_1):PAGE181',
 TOLERANCE='20%',
 MATERIAL='X6S',
 PHYS_PAGE='206',
 XY='(-4200,2425)',
 ROT='0',
 VER='1',
 PACK_TYPE='C0805',
 LOCATION='PC189_4',
 CDS_LIB='pure_quanta',
 CDS_PART_NAME='Q_CAP_C0805-22UF,4V,20%,X6S,CH622KMEA03',
 VOLTAGE='4V',
 PART_NUMBER='CH622KMEA03',
 VALUE='22UF',
 PRIM_FILE='./archive_libs/logical/q_cap/chips/chips.prt';

PART_NAME
 PC190 'Q_CAP_C0402-560PF,50V,10%,EMPTY,CH1566K1B09':;

SECTION_NUMBER 1
 '@T6G_MB_LIB.T6G(SCH_1):PAGE176_I41@PURE_QUANTA.Q_CAP(CHIPS)':
 C_PATH='@t6g_mb_lib.t6g(sch_1):page176_i41@pure_quanta.q_cap(chips)',
 P_PATH='@t6g_mb_lib.t6g(sch_1):page201_i41@pure_quanta.q_cap(chips)',
 PATH='I41',
 DRAWING='@T6G_MB_LIB.T6G(SCH_1):PAGE176',
 TOLERANCE='10%',
 MATERIAL='EMPTY',
 PHYS_PAGE='201',
 XY='(-5875,1000)',
 ROT='0',
 VER='1',
 PACK_TYPE='C0402',
 LOCATION='PC190',
 CDS_LIB='pure_quanta',
 CDS_PART_NAME='Q_CAP_C0402-560PF,50V,10%,EMPTY,CH1566K1B09',
 VOLTAGE='50V',
 PART_NUMBER='CH1566K1B09',
 VALUE='560PF',
 PRIM_FILE='./archive_libs/logical/q_cap/chips/chips.prt';

PART_NAME
 PC190_3 'Q_CAP_C0805-22UF,4V,20%,X6S,CH622KMEA03':;

SECTION_NUMBER 1
 '@T6G_MB_LIB.T6G(SCH_1):PAGE181_I66@PURE_QUANTA.Q_CAP(CHIPS)':
 C_PATH='@t6g_mb_lib.t6g(sch_1):page181_i66@pure_quanta.q_cap(chips)',
 P_PATH='@t6g_mb_lib.t6g(sch_1):page206_i66@pure_quanta.q_cap(chips)',
 PATH='I66',
 DRAWING='@T6G_MB_LIB.T6G(SCH_1):PAGE181',
 TOLERANCE='20%',
 MATERIAL='X6S',
 PHYS_PAGE='206',
 XY='(-4150,5225)',
 ROT='0',
 VER='1',
 PACK_TYPE='C0805',
 LOCATION='PC190_3',
 CDS_LIB='pure_quanta',
 CDS_PART_NAME='Q_CAP_C0805-22UF,4V,20%,X6S,CH622KMEA03',
 VOLTAGE='4V',
 PART_NUMBER='CH622KMEA03',
 VALUE='22UF',
 PRIM_FILE='./archive_libs/logical/q_cap/chips/chips.prt';

PART_NAME
 PC191 'Q_CAP_C0402-560PF,50V,10%,EMPTY,CH1566K1B09':;

SECTION_NUMBER 1
 '@T6G_MB_LIB.T6G(SCH_1):PAGE177_I38@PURE_QUANTA.Q_CAP(CHIPS)':
 C_PATH='@t6g_mb_lib.t6g(sch_1):page177_i38@pure_quanta.q_cap(chips)',
 P_PATH='@t6g_mb_lib.t6g(sch_1):page202_i38@pure_quanta.q_cap(chips)',
 PATH='I38',
 DRAWING='@T6G_MB_LIB.T6G(SCH_1):PAGE177',
 TOLERANCE='10%',
 MATERIAL='EMPTY',
 PHYS_PAGE='202',
 XY='(4650,1350)',
 ROT='0',
 VER='1',
 PACK_TYPE='C0402',
 LOCATION='PC191',
 CDS_LIB='pure_quanta',
 CDS_PART_NAME='Q_CAP_C0402-560PF,50V,10%,EMPTY,CH1566K1B09',
 VOLTAGE='50V',
 PART_NUMBER='CH1566K1B09',
 VALUE='560PF',
 PRIM_FILE='./archive_libs/logical/q_cap/chips/chips.prt';

PART_NAME
 PC191_4 'Q_CAP_C0805-22UF,4V,20%,X6S,CH622KMEA03':;

SECTION_NUMBER 1
 '@T6G_MB_LIB.T6G(SCH_1):PAGE181_I68@PURE_QUANTA.Q_CAP(CHIPS)':
 C_PATH='@t6g_mb_lib.t6g(sch_1):page181_i68@pure_quanta.q_cap(chips)',
 P_PATH='@t6g_mb_lib.t6g(sch_1):page206_i68@pure_quanta.q_cap(chips)',
 PATH='I68',
 DRAWING='@T6G_MB_LIB.T6G(SCH_1):PAGE181',
 TOLERANCE='20%',
 MATERIAL='X6S',
 PHYS_PAGE='206',
 XY='(-3775,2425)',
 ROT='0',
 VER='1',
 PACK_TYPE='C0805',
 LOCATION='PC191_4',
 CDS_LIB='pure_quanta',
 CDS_PART_NAME='Q_CAP_C0805-22UF,4V,20%,X6S,CH622KMEA03',
 VOLTAGE='4V',
 PART_NUMBER='CH622KMEA03',
 VALUE='22UF',
 PRIM_FILE='./archive_libs/logical/q_cap/chips/chips.prt';

PART_NAME
 PC192 'Q_CAP_C0402-560PF,50V,10%,EMPTY,CH1566K1B09':;

SECTION_NUMBER 1
 '@T6G_MB_LIB.T6G(SCH_1):PAGE177_I58@PURE_QUANTA.Q_CAP(CHIPS)':
 C_PATH='@t6g_mb_lib.t6g(sch_1):page177_i58@pure_quanta.q_cap(chips)',
 P_PATH='@t6g_mb_lib.t6g(sch_1):page202_i58@pure_quanta.q_cap(chips)',
 PATH='I58',
 DRAWING='@T6G_MB_LIB.T6G(SCH_1):PAGE177',
 TOLERANCE='10%',
 MATERIAL='EMPTY',
 PHYS_PAGE='202',
 XY='(4700,4150)',
 ROT='0',
 VER='1',
 PACK_TYPE='C0402',
 LOCATION='PC192',
 CDS_LIB='pure_quanta',
 CDS_PART_NAME='Q_CAP_C0402-560PF,50V,10%,EMPTY,CH1566K1B09',
 VOLTAGE='50V',
 PART_NUMBER='CH1566K1B09',
 VALUE='560PF',
 PRIM_FILE='./archive_libs/logical/q_cap/chips/chips.prt';

PART_NAME
 PC192_3 'Q_CAP_C0805-22UF,4V,20%,X6S,CH622KMEA03':;

SECTION_NUMBER 1
 '@T6G_MB_LIB.T6G(SCH_1):PAGE181_I71@PURE_QUANTA.Q_CAP(CHIPS)':
 C_PATH='@t6g_mb_lib.t6g(sch_1):page181_i71@pure_quanta.q_cap(chips)',
 P_PATH='@t6g_mb_lib.t6g(sch_1):page206_i71@pure_quanta.q_cap(chips)',
 PATH='I71',
 DRAWING='@T6G_MB_LIB.T6G(SCH_1):PAGE181',
 TOLERANCE='20%',
 MATERIAL='X6S',
 PHYS_PAGE='206',
 XY='(-3725,5225)',
 ROT='0',
 VER='1',
 PACK_TYPE='C0805',
 LOCATION='PC192_3',
 CDS_LIB='pure_quanta',
 CDS_PART_NAME='Q_CAP_C0805-22UF,4V,20%,X6S,CH622KMEA03',
 VOLTAGE='4V',
 PART_NUMBER='CH622KMEA03',
 VALUE='22UF',
 PRIM_FILE='./archive_libs/logical/q_cap/chips/chips.prt';

PART_NAME
 PC193 'Q_CAP_0402-0.1UF,25V,10%,X7R,CH4104K1B00':;

SECTION_NUMBER 1
 '@T6G_MB_LIB.T6G(SCH_1):PAGE182_I4@PURE_QUANTA.Q_CAP(CHIPS)':
 C_PATH='@t6g_mb_lib.t6g(sch_1):page182_i4@pure_quanta.q_cap(chips)',
 P_PATH='@t6g_mb_lib.t6g(sch_1):page207_i4@pure_quanta.q_cap(chips)',
 PATH='I4',
 DRAWING='@T6G_MB_LIB.T6G(SCH_1):PAGE182',
 TOLERANCE='10%',
 MATERIAL='X7R',
 PHYS_PAGE='207',
 XY='(-6975,675)',
 ROT='0',
 VER='1',
 PACK_TYPE='0402',
 LOCATION='PC193',
 CDS_LIB='pure_quanta',
 CDS_PART_NAME='Q_CAP_0402-0.1UF,25V,10%,X7R,CH4104K1B00',
 VOLTAGE='25V',
 PART_NUMBER='CH4104K1B00',
 VALUE='0.1UF',
 PRIM_FILE='./archive_libs/logical/q_cap/chips/chips.prt';

PART_NAME
 PC194 'Q_CAP_0402-3300PF,50V,10%,X7R,TMP_QCH2336K1B12':;

SECTION_NUMBER 1
 '@T6G_MB_LIB.T6G(SCH_1):PAGE182_I29@PURE_QUANTA.Q_CAP(CHIPS)':
 C_PATH='@t6g_mb_lib.t6g(sch_1):page182_i29@pure_quanta.q_cap(chips)',
 P_PATH='@t6g_mb_lib.t6g(sch_1):page207_i29@pure_quanta.q_cap(chips)',
 PATH='I29',
 DRAWING='@T6G_MB_LIB.T6G(SCH_1):PAGE182',
 TOLERANCE='10%',
 MATERIAL='X7R',
 PHYS_PAGE='207',
 XY='(-5775,3950)',
 ROT='0',
 VER='1',
 PACK_TYPE='0402',
 LOCATION='PC194',
 CDS_LIB='pure_quanta',
 CDS_PART_NAME='Q_CAP_0402-3300PF,50V,10%,X7R,TMP_QCH2336K1B12',
 VOLTAGE='50V',
 PART_NUMBER='TMP_QCH2336K1B12',
 VALUE='3300PF',
 PRIM_FILE='./archive_libs/logical/q_cap/chips/chips.prt';

PART_NAME
 PC195 'Q_CAP_C0402-560PF,50V,10%,EMPTY,CH1566K1B09':;

SECTION_NUMBER 1
 '@T6G_MB_LIB.T6G(SCH_1):PAGE191_I11@PURE_QUANTA.Q_CAP(CHIPS)':
 C_PATH='@t6g_mb_lib.t6g(sch_1):page191_i11@pure_quanta.q_cap(chips)',
 P_PATH='@t6g_mb_lib.t6g(sch_1):page216_i11@pure_quanta.q_cap(chips)',
 PATH='I11',
 DRAWING='@T6G_MB_LIB.T6G(SCH_1):PAGE191',
 TOLERANCE='10%',
 MATERIAL='EMPTY',
 PHYS_PAGE='216',
 XY='(-4450,4300)',
 ROT='0',
 VER='1',
 PACK_TYPE='C0402',
 LOCATION='PC195',
 CDS_LIB='pure_quanta',
 CDS_PART_NAME='Q_CAP_C0402-560PF,50V,10%,EMPTY,CH1566K1B09',
 VOLTAGE='50V',
 PART_NUMBER='CH1566K1B09',
 VALUE='560PF',
 PRIM_FILE='./archive_libs/logical/q_cap/chips/chips.prt';

PART_NAME
 PC198 'Q_CAP_0402-470PF,50V,10%,X7R,TMP_QCH14706KB18':;

SECTION_NUMBER 1
 '@T6G_MB_LIB.T6G(SCH_1):PAGE182_I50@PURE_QUANTA.Q_CAP(CHIPS)':
 C_PATH='@t6g_mb_lib.t6g(sch_1):page182_i50@pure_quanta.q_cap(chips)',
 P_PATH='@t6g_mb_lib.t6g(sch_1):page207_i50@pure_quanta.q_cap(chips)',
 PATH='I50',
 DRAWING='@T6G_MB_LIB.T6G(SCH_1):PAGE182',
 TOLERANCE='10%',
 MATERIAL='X7R',
 PHYS_PAGE='207',
 XY='(-3475,725)',
 ROT='0',
 VER='1',
 PACK_TYPE='0402',
 LOCATION='PC198',
 CDS_LIB='pure_quanta',
 CDS_PART_NAME='Q_CAP_0402-470PF,50V,10%,X7R,TMP_QCH14706KB18',
 VOLTAGE='50V',
 PART_NUMBER='TMP_QCH14706KB18',
 VALUE='470PF',
 PRIM_FILE='./archive_libs/logical/q_cap/chips/chips.prt';

PART_NAME
 PC199 'Q_CAP_C0402-10UF,6.3V,20%,X6S,CH6101MEB03':;

SECTION_NUMBER 1
 '@T6G_MB_LIB.T6G(SCH_1):PAGE182_I80@PURE_QUANTA.Q_CAP(CHIPS)':
 C_PATH='@t6g_mb_lib.t6g(sch_1):page182_i80@pure_quanta.q_cap(chips)',
 P_PATH='@t6g_mb_lib.t6g(sch_1):page207_i80@pure_quanta.q_cap(chips)',
 PATH='I80',
 DRAWING='@T6G_MB_LIB.T6G(SCH_1):PAGE182',
 TOLERANCE='20%',
 MATERIAL='X6S',
 PHYS_PAGE='207',
 XY='(-3025,5675)',
 ROT='0',
 VER='1',
 PACK_TYPE='C0402',
 LOCATION='PC199',
 CDS_LIB='pure_quanta',
 CDS_PART_NAME='Q_CAP_C0402-10UF,6.3V,20%,X6S,CH6101MEB03',
 VOLTAGE='6.3V',
 PART_NUMBER='CH6101MEB03',
 VALUE='10UF',
 PRIM_FILE='./archive_libs/logical/q_cap/chips/chips.prt';

PART_NAME
 PC200 'Q_CAP_C0402-1UF,16V,10%,X6S,CH5103KEB01':;

SECTION_NUMBER 1
 '@T6G_MB_LIB.T6G(SCH_1):PAGE182_I82@PURE_QUANTA.Q_CAP(CHIPS)':
 C_PATH='@t6g_mb_lib.t6g(sch_1):page182_i82@pure_quanta.q_cap(chips)',
 P_PATH='@t6g_mb_lib.t6g(sch_1):page207_i82@pure_quanta.q_cap(chips)',
 PATH='I82',
 DRAWING='@T6G_MB_LIB.T6G(SCH_1):PAGE182',
 TOLERANCE='10%',
 MATERIAL='X6S',
 PHYS_PAGE='207',
 XY='(-3025,6150)',
 ROT='0',
 VER='1',
 PACK_TYPE='C0402',
 LOCATION='PC200',
 CDS_LIB='pure_quanta',
 CDS_PART_NAME='Q_CAP_C0402-1UF,16V,10%,X6S,CH5103KEB01',
 VOLTAGE='16V',
 PART_NUMBER='CH5103KEB01',
 VALUE='1UF',
 PRIM_FILE='./archive_libs/logical/q_cap/chips/chips.prt';

PART_NAME
 PC201 'Q_CAP_C0402-560PF,50V,10%,EMPTY,CH1566K1B09':;

SECTION_NUMBER 1
 '@T6G_MB_LIB.T6G(SCH_1):PAGE193_I52@PURE_QUANTA.Q_CAP(CHIPS)':
 C_PATH='@t6g_mb_lib.t6g(sch_1):page193_i52@pure_quanta.q_cap(chips)',
 P_PATH='@t6g_mb_lib.t6g(sch_1):page218_i52@pure_quanta.q_cap(chips)',
 PATH='I52',
 DRAWING='@T6G_MB_LIB.T6G(SCH_1):PAGE193',
 TOLERANCE='10%',
 MATERIAL='EMPTY',
 PHYS_PAGE='218',
 XY='(-5325,4400)',
 ROT='0',
 VER='1',
 PACK_TYPE='C0402',
 LOCATION='PC201',
 CDS_LIB='pure_quanta',
 CDS_PART_NAME='Q_CAP_C0402-560PF,50V,10%,EMPTY,CH1566K1B09',
 VOLTAGE='50V',
 PART_NUMBER='CH1566K1B09',
 VALUE='560PF',
 PRIM_FILE='./archive_libs/logical/q_cap/chips/chips.prt';

PART_NAME
 PC201_1 'Q_CAP_0402-0.1UF,25V,10%,X7R,CH4104K1B00':;

SECTION_NUMBER 1
 '@T6G_MB_LIB.T6G(SCH_1):PAGE183_I34@PURE_QUANTA.Q_CAP(CHIPS)':
 C_PATH='@t6g_mb_lib.t6g(sch_1):page183_i34@pure_quanta.q_cap(chips)',
 P_PATH='@t6g_mb_lib.t6g(sch_1):page208_i34@pure_quanta.q_cap(chips)',
 PATH='I34',
 DRAWING='@T6G_MB_LIB.T6G(SCH_1):PAGE183',
 TOLERANCE='10%',
 MATERIAL='X7R',
 PHYS_PAGE='208',
 XY='(-7875,4150)',
 ROT='0',
 VER='1',
 PACK_TYPE='0402',
 LOCATION='PC201_1',
 CDS_LIB='pure_quanta',
 CDS_PART_NAME='Q_CAP_0402-0.1UF,25V,10%,X7R,CH4104K1B00',
 VOLTAGE='25V',
 PART_NUMBER='CH4104K1B00',
 VALUE='0.1UF',
 PRIM_FILE='./archive_libs/logical/q_cap/chips/chips.prt';

PART_NAME
 PC202 'Q_CAP_C0402-560PF,50V,10%,EMPTY,CH1566K1B09':;

SECTION_NUMBER 1
 '@T6G_MB_LIB.T6G(SCH_1):PAGE193_I37@PURE_QUANTA.Q_CAP(CHIPS)':
 C_PATH='@t6g_mb_lib.t6g(sch_1):page193_i37@pure_quanta.q_cap(chips)',
 P_PATH='@t6g_mb_lib.t6g(sch_1):page218_i37@pure_quanta.q_cap(chips)',
 PATH='I37',
 DRAWING='@T6G_MB_LIB.T6G(SCH_1):PAGE193',
 TOLERANCE='10%',
 MATERIAL='EMPTY',
 PHYS_PAGE='218',
 XY='(-5375,1800)',
 ROT='0',
 VER='1',
 PACK_TYPE='C0402',
 LOCATION='PC202',
 CDS_LIB='pure_quanta',
 CDS_PART_NAME='Q_CAP_C0402-560PF,50V,10%,EMPTY,CH1566K1B09',
 VOLTAGE='50V',
 PART_NUMBER='CH1566K1B09',
 VALUE='560PF',
 PRIM_FILE='./archive_libs/logical/q_cap/chips/chips.prt';

PART_NAME
 PC202_2 'Q_CAP_0402-0.1UF,25V,10%,X7R,CH4104K1B00':;

SECTION_NUMBER 1
 '@T6G_MB_LIB.T6G(SCH_1):PAGE183_I7@PURE_QUANTA.Q_CAP(CHIPS)':
 C_PATH='@t6g_mb_lib.t6g(sch_1):page183_i7@pure_quanta.q_cap(chips)',
 P_PATH='@t6g_mb_lib.t6g(sch_1):page208_i7@pure_quanta.q_cap(chips)',
 PATH='I7',
 DRAWING='@T6G_MB_LIB.T6G(SCH_1):PAGE183',
 TOLERANCE='10%',
 MATERIAL='X7R',
 PHYS_PAGE='208',
 XY='(-7825,1225)',
 ROT='0',
 VER='1',
 PACK_TYPE='0402',
 LOCATION='PC202_2',
 CDS_LIB='pure_quanta',
 CDS_PART_NAME='Q_CAP_0402-0.1UF,25V,10%,X7R,CH4104K1B00',
 VOLTAGE='25V',
 PART_NUMBER='CH4104K1B00',
 VALUE='0.1UF',
 PRIM_FILE='./archive_libs/logical/q_cap/chips/chips.prt';

PART_NAME
 PC203 'Q_CAP_C0402-2.2UF,10V,10%,X6S,CH5222KEB01':;

SECTION_NUMBER 1
 '@T6G_MB_LIB.T6G(SCH_1):PAGE183_I36@PURE_QUANTA.Q_CAP(CHIPS)':
 C_PATH='@t6g_mb_lib.t6g(sch_1):page183_i36@pure_quanta.q_cap(chips)',
 P_PATH='@t6g_mb_lib.t6g(sch_1):page208_i36@pure_quanta.q_cap(chips)',
 PATH='I36',
 DRAWING='@T6G_MB_LIB.T6G(SCH_1):PAGE183',
 TOLERANCE='10%',
 MATERIAL='X6S',
 PHYS_PAGE='208',
 XY='(-7775,4750)',
 ROT='0',
 VER='1',
 PACK_TYPE='C0402',
 LOCATION='PC203',
 CDS_LIB='pure_quanta',
 CDS_PART_NAME='Q_CAP_C0402-2.2UF,10V,10%,X6S,CH5222KEB01',
 VOLTAGE='10V',
 PART_NUMBER='CH5222KEB01',
 VALUE='2.2UF',
 PRIM_FILE='./archive_libs/logical/q_cap/chips/chips.prt';

PART_NAME
 PC204 'Q_CAP_C0402-2.2UF,10V,10%,X6S,CH5222KEB01':;

SECTION_NUMBER 1
 '@T6G_MB_LIB.T6G(SCH_1):PAGE183_I9@PURE_QUANTA.Q_CAP(CHIPS)':
 C_PATH='@t6g_mb_lib.t6g(sch_1):page183_i9@pure_quanta.q_cap(chips)',
 P_PATH='@t6g_mb_lib.t6g(sch_1):page208_i9@pure_quanta.q_cap(chips)',
 PATH='I9',
 DRAWING='@T6G_MB_LIB.T6G(SCH_1):PAGE183',
 TOLERANCE='10%',
 MATERIAL='X6S',
 PHYS_PAGE='208',
 XY='(-7775,1825)',
 ROT='0',
 VER='1',
 PACK_TYPE='C0402',
 LOCATION='PC204',
 CDS_LIB='pure_quanta',
 CDS_PART_NAME='Q_CAP_C0402-2.2UF,10V,10%,X6S,CH5222KEB01',
 VOLTAGE='10V',
 PART_NUMBER='CH5222KEB01',
 VALUE='2.2UF',
 PRIM_FILE='./archive_libs/logical/q_cap/chips/chips.prt';

PART_NAME
 PC205 'Q_CAP_C0402-560PF,50V,10%,EMPTY,CH1566K1B09':;

SECTION_NUMBER 1
 '@T6G_MB_LIB.T6G(SCH_1):PAGE194_I37@PURE_QUANTA.Q_CAP(CHIPS)':
 C_PATH='@t6g_mb_lib.t6g(sch_1):page194_i37@pure_quanta.q_cap(chips)',
 P_PATH='@t6g_mb_lib.t6g(sch_1):page219_i37@pure_quanta.q_cap(chips)',
 PATH='I37',
 DRAWING='@T6G_MB_LIB.T6G(SCH_1):PAGE194',
 TOLERANCE='10%',
 MATERIAL='EMPTY',
 PHYS_PAGE='219',
 XY='(4675,1275)',
 ROT='0',
 VER='1',
 PACK_TYPE='C0402',
 LOCATION='PC205',
 CDS_LIB='pure_quanta',
 CDS_PART_NAME='Q_CAP_C0402-560PF,50V,10%,EMPTY,CH1566K1B09',
 VOLTAGE='50V',
 PART_NUMBER='CH1566K1B09',
 VALUE='560PF',
 PRIM_FILE='./archive_libs/logical/q_cap/chips/chips.prt';

PART_NAME
 PC205_11P0_1 'Q_CAP_C0402-2.2UF,10V,10%,X6S,CH5222KEB01':;

SECTION_NUMBER 1
 '@T6G_MB_LIB.T6G(SCH_1):PAGE183_I42@PURE_QUANTA.Q_CAP(CHIPS)':
 C_PATH='@t6g_mb_lib.t6g(sch_1):page183_i42@pure_quanta.q_cap(chips)',
 P_PATH='@t6g_mb_lib.t6g(sch_1):page208_i42@pure_quanta.q_cap(chips)',
 PATH='I42',
 DRAWING='@T6G_MB_LIB.T6G(SCH_1):PAGE183',
 TOLERANCE='10%',
 MATERIAL='X6S',
 PHYS_PAGE='208',
 XY='(-7425,5325)',
 ROT='0',
 VER='1',
 PACK_TYPE='C0402',
 LOCATION='PC205_11P0_1',
 CDS_LIB='pure_quanta',
 CDS_PART_NAME='Q_CAP_C0402-2.2UF,10V,10%,X6S,CH5222KEB01',
 VOLTAGE='10V',
 PART_NUMBER='CH5222KEB01',
 VALUE='2.2UF',
 PRIM_FILE='./archive_libs/logical/q_cap/chips/chips.prt';

PART_NAME
 PC206 'Q_CAP_C0402-560PF,50V,10%,EMPTY,CH1566K1B09':;

SECTION_NUMBER 1
 '@T6G_MB_LIB.T6G(SCH_1):PAGE194_I53@PURE_QUANTA.Q_CAP(CHIPS)':
 C_PATH='@t6g_mb_lib.t6g(sch_1):page194_i53@pure_quanta.q_cap(chips)',
 P_PATH='@t6g_mb_lib.t6g(sch_1):page219_i53@pure_quanta.q_cap(chips)',
 PATH='I53',
 DRAWING='@T6G_MB_LIB.T6G(SCH_1):PAGE194',
 TOLERANCE='10%',
 MATERIAL='EMPTY',
 PHYS_PAGE='219',
 XY='(4775,4100)',
 ROT='0',
 VER='1',
 PACK_TYPE='C0402',
 LOCATION='PC206',
 CDS_LIB='pure_quanta',
 CDS_PART_NAME='Q_CAP_C0402-560PF,50V,10%,EMPTY,CH1566K1B09',
 VOLTAGE='50V',
 PART_NUMBER='CH1566K1B09',
 VALUE='560PF',
 PRIM_FILE='./archive_libs/logical/q_cap/chips/chips.prt';

PART_NAME
 PC206_11P0_2 'Q_CAP_C0402-2.2UF,10V,10%,X6S,CH5222KEB01':;

SECTION_NUMBER 1
 '@T6G_MB_LIB.T6G(SCH_1):PAGE183_I17@PURE_QUANTA.Q_CAP(CHIPS)':
 C_PATH='@t6g_mb_lib.t6g(sch_1):page183_i17@pure_quanta.q_cap(chips)',
 P_PATH='@t6g_mb_lib.t6g(sch_1):page208_i17@pure_quanta.q_cap(chips)',
 PATH='I17',
 DRAWING='@T6G_MB_LIB.T6G(SCH_1):PAGE183',
 TOLERANCE='10%',
 MATERIAL='X6S',
 PHYS_PAGE='208',
 XY='(-7425,2400)',
 ROT='0',
 VER='1',
 PACK_TYPE='C0402',
 LOCATION='PC206_11P0_2',
 CDS_LIB='pure_quanta',
 CDS_PART_NAME='Q_CAP_C0402-2.2UF,10V,10%,X6S,CH5222KEB01',
 VOLTAGE='10V',
 PART_NUMBER='CH5222KEB01',
 VALUE='2.2UF',
 PRIM_FILE='./archive_libs/logical/q_cap/chips/chips.prt';

PART_NAME
 PC207 'Q_CAP_C0402-560PF,50V,10%,EMPTY,CH1566K1B09':;

SECTION_NUMBER 1
 '@T6G_MB_LIB.T6G(SCH_1):PAGE195_I53@PURE_QUANTA.Q_CAP(CHIPS)':
 C_PATH='@t6g_mb_lib.t6g(sch_1):page195_i53@pure_quanta.q_cap(chips)',
 P_PATH='@t6g_mb_lib.t6g(sch_1):page220_i53@pure_quanta.q_cap(chips)',
 PATH='I53',
 DRAWING='@T6G_MB_LIB.T6G(SCH_1):PAGE195',
 TOLERANCE='10%',
 MATERIAL='EMPTY',
 PHYS_PAGE='220',
 XY='(4650,4650)',
 ROT='0',
 VER='1',
 PACK_TYPE='C0402',
 LOCATION='PC207',
 CDS_LIB='pure_quanta',
 CDS_PART_NAME='Q_CAP_C0402-560PF,50V,10%,EMPTY,CH1566K1B09',
 VOLTAGE='50V',
 PART_NUMBER='CH1566K1B09',
 VALUE='560PF',
 PRIM_FILE='./archive_libs/logical/q_cap/chips/chips.prt';

PART_NAME
 PC207_1 'Q_CAP_0402-0.1UF,25V,10%,X7R,CH4104K1B00':;

SECTION_NUMBER 1
 '@T6G_MB_LIB.T6G(SCH_1):PAGE183_I47@PURE_QUANTA.Q_CAP(CHIPS)':
 C_PATH='@t6g_mb_lib.t6g(sch_1):page183_i47@pure_quanta.q_cap(chips)',
 P_PATH='@t6g_mb_lib.t6g(sch_1):page208_i47@pure_quanta.q_cap(chips)',
 PATH='I47',
 DRAWING='@T6G_MB_LIB.T6G(SCH_1):PAGE183',
 TOLERANCE='10%',
 MATERIAL='X7R',
 PHYS_PAGE='208',
 XY='(-5050,5325)',
 ROT='0',
 VER='1',
 PACK_TYPE='0402',
 LOCATION='PC207_1',
 CDS_LIB='pure_quanta',
 CDS_PART_NAME='Q_CAP_0402-0.1UF,25V,10%,X7R,CH4104K1B00',
 VOLTAGE='25V',
 PART_NUMBER='CH4104K1B00',
 VALUE='0.1UF',
 PRIM_FILE='./archive_libs/logical/q_cap/chips/chips.prt';

PART_NAME
 PC208 'Q_CAP_C0402-560PF,50V,10%,EMPTY,CH1566K1B09':;

SECTION_NUMBER 1
 '@T6G_MB_LIB.T6G(SCH_1):PAGE195_I34@PURE_QUANTA.Q_CAP(CHIPS)':
 C_PATH='@t6g_mb_lib.t6g(sch_1):page195_i34@pure_quanta.q_cap(chips)',
 P_PATH='@t6g_mb_lib.t6g(sch_1):page220_i34@pure_quanta.q_cap(chips)',
 PATH='I34',
 DRAWING='@T6G_MB_LIB.T6G(SCH_1):PAGE195',
 TOLERANCE='10%',
 MATERIAL='EMPTY',
 PHYS_PAGE='220',
 XY='(4725,2025)',
 ROT='0',
 VER='1',
 PACK_TYPE='C0402',
 LOCATION='PC208',
 CDS_LIB='pure_quanta',
 CDS_PART_NAME='Q_CAP_C0402-560PF,50V,10%,EMPTY,CH1566K1B09',
 VOLTAGE='50V',
 PART_NUMBER='CH1566K1B09',
 VALUE='560PF',
 PRIM_FILE='./archive_libs/logical/q_cap/chips/chips.prt';

PART_NAME
 PC208_2 'Q_CAP_0402-0.1UF,25V,10%,X7R,CH4104K1B00':;

SECTION_NUMBER 1
 '@T6G_MB_LIB.T6G(SCH_1):PAGE183_I29@PURE_QUANTA.Q_CAP(CHIPS)':
 C_PATH='@t6g_mb_lib.t6g(sch_1):page183_i29@pure_quanta.q_cap(chips)',
 P_PATH='@t6g_mb_lib.t6g(sch_1):page208_i29@pure_quanta.q_cap(chips)',
 PATH='I29',
 DRAWING='@T6G_MB_LIB.T6G(SCH_1):PAGE183',
 TOLERANCE='10%',
 MATERIAL='X7R',
 PHYS_PAGE='208',
 XY='(-5000,2400)',
 ROT='0',
 VER='1',
 PACK_TYPE='0402',
 LOCATION='PC208_2',
 CDS_LIB='pure_quanta',
 CDS_PART_NAME='Q_CAP_0402-0.1UF,25V,10%,X7R,CH4104K1B00',
 VOLTAGE='25V',
 PART_NUMBER='CH4104K1B00',
 VALUE='0.1UF',
 PRIM_FILE='./archive_libs/logical/q_cap/chips/chips.prt';

PART_NAME
 PC209 'Q_CAP_0402-0.22UF,16V,10%,X7R,CH4223K1B00':;

SECTION_NUMBER 1
 '@T6G_MB_LIB.T6G(SCH_1):PAGE184_I24@PURE_QUANTA.Q_CAP(CHIPS)':
 C_PATH='@t6g_mb_lib.t6g(sch_1):page184_i24@pure_quanta.q_cap(chips)',
 P_PATH='@t6g_mb_lib.t6g(sch_1):page209_i24@pure_quanta.q_cap(chips)',
 PATH='I24',
 DRAWING='@T6G_MB_LIB.T6G(SCH_1):PAGE184',
 SEC_TYPE='0402',
 TOLERANCE='10%',
 MATERIAL='X7R',
 PHYS_PAGE='209',
 XY='(-4100,3725)',
 ROT='0',
 VER='1',
 PACK_TYPE='0402',
 LOCATION='PC209',
 SEC='1',
 CDS_LIB='pure_quanta',
 CDS_PART_NAME='Q_CAP_0402-0.22UF,16V,10%,X7R,CH4223K1B00',
 VOLTAGE='16V',
 PART_NUMBER='CH4223K1B00',
 VALUE='0.22UF',
 PRIM_FILE='./archive_libs/logical/q_cap/chips/chips.prt';

PART_NAME
 PC209_1 'Q_CAP_C0402-1UF,25V,10%,X6S,CH5104KEB02':;

SECTION_NUMBER 1
 '@T6G_MB_LIB.T6G(SCH_1):PAGE183_I44@PURE_QUANTA.Q_CAP(CHIPS)':
 C_PATH='@t6g_mb_lib.t6g(sch_1):page183_i44@pure_quanta.q_cap(chips)',
 P_PATH='@t6g_mb_lib.t6g(sch_1):page208_i44@pure_quanta.q_cap(chips)',
 PATH='I44',
 DRAWING='@T6G_MB_LIB.T6G(SCH_1):PAGE183',
 TOLERANCE='10%',
 MATERIAL='X6S',
 PHYS_PAGE='208',
 XY='(-5375,5325)',
 ROT='0',
 VER='1',
 PACK_TYPE='C0402',
 LOCATION='PC209_1',
 CDS_LIB='pure_quanta',
 CDS_PART_NAME='Q_CAP_C0402-1UF,25V,10%,X6S,CH5104KEB02',
 VOLTAGE='25V',
 PART_NUMBER='CH5104KEB02',
 VALUE='1UF',
 PRIM_FILE='./archive_libs/logical/q_cap/chips/chips.prt';

PART_NAME
 PC210_2 'Q_CAP_C0402-1UF,25V,10%,X6S,CH5104KEB02':;

SECTION_NUMBER 1
 '@T6G_MB_LIB.T6G(SCH_1):PAGE183_I27@PURE_QUANTA.Q_CAP(CHIPS)':
 C_PATH='@t6g_mb_lib.t6g(sch_1):page183_i27@pure_quanta.q_cap(chips)',
 P_PATH='@t6g_mb_lib.t6g(sch_1):page208_i27@pure_quanta.q_cap(chips)',
 PATH='I27',
 DRAWING='@T6G_MB_LIB.T6G(SCH_1):PAGE183',
 TOLERANCE='10%',
 MATERIAL='X6S',
 PHYS_PAGE='208',
 XY='(-5325,2400)',
 ROT='0',
 VER='1',
 PACK_TYPE='C0402',
 LOCATION='PC210_2',
 CDS_LIB='pure_quanta',
 CDS_PART_NAME='Q_CAP_C0402-1UF,25V,10%,X6S,CH5104KEB02',
 VOLTAGE='25V',
 PART_NUMBER='CH5104KEB02',
 VALUE='1UF',
 PRIM_FILE='./archive_libs/logical/q_cap/chips/chips.prt';

PART_NAME
 PC211_1 'Q_CAP_C0805-22UF,16V,20%,X6S,CH6223MEA01':;

SECTION_NUMBER 1
 '@T6G_MB_LIB.T6G(SCH_1):PAGE183_I48@PURE_QUANTA.Q_CAP(CHIPS)':
 C_PATH='@t6g_mb_lib.t6g(sch_1):page183_i48@pure_quanta.q_cap(chips)',
 P_PATH='@t6g_mb_lib.t6g(sch_1):page208_i48@pure_quanta.q_cap(chips)',
 PATH='I48',
 DRAWING='@T6G_MB_LIB.T6G(SCH_1):PAGE183',
 TOLERANCE='20%',
 MATERIAL='X6S',
 PHYS_PAGE='208',
 XY='(-4750,5325)',
 ROT='0',
 VER='1',
 PACK_TYPE='C0805',
 LOCATION='PC211_1',
 CDS_LIB='pure_quanta',
 CDS_PART_NAME='Q_CAP_C0805-22UF,16V,20%,X6S,CH6223MEA01',
 VOLTAGE='16V',
 PART_NUMBER='CH6223MEA01',
 VALUE='22UF',
 PRIM_FILE='./archive_libs/logical/q_cap/chips/chips.prt';

PART_NAME
 PC212 'Q_CAP_C0402-1UF,25V,10%,X6S,CH5104KEB02':
 SIGNAL_MODEL='DEFAULT_CAPACITOR_100000PF_2_1';

SECTION_NUMBER 1
 '@T6G_MB_LIB.T6G(SCH_1):PAGE184_I11@PURE_QUANTA.Q_CAP(CHIPS)':
 C_PATH='@t6g_mb_lib.t6g(sch_1):page184_i11@pure_quanta.q_cap(chips)',
 P_PATH='@t6g_mb_lib.t6g(sch_1):page209_i11@pure_quanta.q_cap(chips)',
 PATH='I11',
 DRAWING='@T6G_MB_LIB.T6G(SCH_1):PAGE184',
 SEC_TYPE='C0402',
 TOLERANCE='10%',
 MATERIAL='X6S',
 PHYS_PAGE='209',
 XY='(-7575,2550)',
 ROT='2',
 VER='1',
 PACK_TYPE='C0402',
 LOCATION='PC212',
 SEC='1',
 CDS_LIB='pure_quanta',
 CDS_PART_NAME='Q_CAP_C0402-1UF,25V,10%,X6S,CH5104KEB02',
 SIGNAL_MODEL='DEFAULT_CAPACITOR_100000PF_2_1',
 VOLTAGE='25V',
 PART_NUMBER='CH5104KEB02',
 VALUE='1UF',
 PRIM_FILE='./archive_libs/logical/q_cap/chips/chips.prt';

PART_NAME
 PC212_2 'Q_CAP_C0805-22UF,16V,20%,X6S,CH6223MEA01':;

SECTION_NUMBER 1
 '@T6G_MB_LIB.T6G(SCH_1):PAGE183_I30@PURE_QUANTA.Q_CAP(CHIPS)':
 C_PATH='@t6g_mb_lib.t6g(sch_1):page183_i30@pure_quanta.q_cap(chips)',
 P_PATH='@t6g_mb_lib.t6g(sch_1):page208_i30@pure_quanta.q_cap(chips)',
 PATH='I30',
 DRAWING='@T6G_MB_LIB.T6G(SCH_1):PAGE183',
 TOLERANCE='20%',
 MATERIAL='X6S',
 PHYS_PAGE='208',
 XY='(-4675,2400)',
 ROT='0',
 VER='1',
 PACK_TYPE='C0805',
 LOCATION='PC212_2',
 CDS_LIB='pure_quanta',
 CDS_PART_NAME='Q_CAP_C0805-22UF,16V,20%,X6S,CH6223MEA01',
 VOLTAGE='16V',
 PART_NUMBER='CH6223MEA01',
 VALUE='22UF',
 PRIM_FILE='./archive_libs/logical/q_cap/chips/chips.prt';

PART_NAME
 PC213_1 'Q_CAP_C0805-22UF,16V,20%,X6S,CH6223MEA01':;

SECTION_NUMBER 1
 '@T6G_MB_LIB.T6G(SCH_1):PAGE183_I49@PURE_QUANTA.Q_CAP(CHIPS)':
 C_PATH='@t6g_mb_lib.t6g(sch_1):page183_i49@pure_quanta.q_cap(chips)',
 P_PATH='@t6g_mb_lib.t6g(sch_1):page208_i49@pure_quanta.q_cap(chips)',
 PATH='I49',
 DRAWING='@T6G_MB_LIB.T6G(SCH_1):PAGE183',
 TOLERANCE='20%',
 MATERIAL='X6S',
 PHYS_PAGE='208',
 XY='(-4425,5325)',
 ROT='0',
 VER='1',
 PACK_TYPE='C0805',
 LOCATION='PC213_1',
 CDS_LIB='pure_quanta',
 CDS_PART_NAME='Q_CAP_C0805-22UF,16V,20%,X6S,CH6223MEA01',
 VOLTAGE='16V',
 PART_NUMBER='CH6223MEA01',
 VALUE='22UF',
 PRIM_FILE='./archive_libs/logical/q_cap/chips/chips.prt';

PART_NAME
 PC214_2 'Q_CAP_C0805-22UF,16V,20%,X6S,CH6223MEA01':;

SECTION_NUMBER 1
 '@T6G_MB_LIB.T6G(SCH_1):PAGE183_I31@PURE_QUANTA.Q_CAP(CHIPS)':
 C_PATH='@t6g_mb_lib.t6g(sch_1):page183_i31@pure_quanta.q_cap(chips)',
 P_PATH='@t6g_mb_lib.t6g(sch_1):page208_i31@pure_quanta.q_cap(chips)',
 PATH='I31',
 DRAWING='@T6G_MB_LIB.T6G(SCH_1):PAGE183',
 TOLERANCE='20%',
 MATERIAL='X6S',
 PHYS_PAGE='208',
 XY='(-4375,2400)',
 ROT='0',
 VER='1',
 PACK_TYPE='C0805',
 LOCATION='PC214_2',
 CDS_LIB='pure_quanta',
 CDS_PART_NAME='Q_CAP_C0805-22UF,16V,20%,X6S,CH6223MEA01',
 VOLTAGE='16V',
 PART_NUMBER='CH6223MEA01',
 VALUE='22UF',
 PRIM_FILE='./archive_libs/logical/q_cap/chips/chips.prt';

PART_NAME
 PC215 'Q_CAP_0402-0.1UF,25V,10%,X7R,CH4104K1B00':;

SECTION_NUMBER 1
 '@T6G_MB_LIB.T6G(SCH_1):PAGE184_I48@PURE_QUANTA.Q_CAP(CHIPS)':
 C_PATH='@t6g_mb_lib.t6g(sch_1):page184_i48@pure_quanta.q_cap(chips)',
 P_PATH='@t6g_mb_lib.t6g(sch_1):page209_i48@pure_quanta.q_cap(chips)',
 PATH='I48',
 DRAWING='@T6G_MB_LIB.T6G(SCH_1):PAGE184',
 SEC_TYPE='0402',
 TOLERANCE='10%',
 MATERIAL='X7R',
 PHYS_PAGE='209',
 XY='(-1100,3325)',
 ROT='0',
 VER='1',
 PACK_TYPE='0402',
 LOCATION='PC215',
 SEC='1',
 CDS_LIB='pure_quanta',
 CDS_PART_NAME='Q_CAP_0402-0.1UF,25V,10%,X7R,CH4104K1B00',
 VOLTAGE='25V',
 PART_NUMBER='CH4104K1B00',
 VALUE='0.1UF',
 PRIM_FILE='./archive_libs/logical/q_cap/chips/chips.prt';

PART_NAME
 PC215_1 'Q_CAP_C0805-22UF,16V,20%,X6S,CH6223MEA01':;

SECTION_NUMBER 1
 '@T6G_MB_LIB.T6G(SCH_1):PAGE183_I87@PURE_QUANTA.Q_CAP(CHIPS)':
 C_PATH='@t6g_mb_lib.t6g(sch_1):page183_i87@pure_quanta.q_cap(chips)',
 P_PATH='@t6g_mb_lib.t6g(sch_1):page208_i87@pure_quanta.q_cap(chips)',
 PATH='I87',
 DRAWING='@T6G_MB_LIB.T6G(SCH_1):PAGE183',
 TOLERANCE='20%',
 MATERIAL='X6S',
 PHYS_PAGE='208',
 XY='(-4200,5325)',
 ROT='0',
 VER='1',
 PACK_TYPE='C0805',
 LOCATION='PC215_1',
 CDS_LIB='pure_quanta',
 CDS_PART_NAME='Q_CAP_C0805-22UF,16V,20%,X6S,CH6223MEA01',
 VOLTAGE='16V',
 PART_NUMBER='CH6223MEA01',
 VALUE='22UF',
 PRIM_FILE='./archive_libs/logical/q_cap/chips/chips.prt';

PART_NAME
 PC216_2 'Q_CAP_C0805-22UF,16V,20%,X6S,CH6223MEA01':;

SECTION_NUMBER 1
 '@T6G_MB_LIB.T6G(SCH_1):PAGE183_I50@PURE_QUANTA.Q_CAP(CHIPS)':
 C_PATH='@t6g_mb_lib.t6g(sch_1):page183_i50@pure_quanta.q_cap(chips)',
 P_PATH='@t6g_mb_lib.t6g(sch_1):page208_i50@pure_quanta.q_cap(chips)',
 PATH='I50',
 DRAWING='@T6G_MB_LIB.T6G(SCH_1):PAGE183',
 TOLERANCE='20%',
 MATERIAL='X6S',
 PHYS_PAGE='208',
 XY='(-4050,2400)',
 ROT='0',
 VER='1',
 PACK_TYPE='C0805',
 LOCATION='PC216_2',
 CDS_LIB='pure_quanta',
 CDS_PART_NAME='Q_CAP_C0805-22UF,16V,20%,X6S,CH6223MEA01',
 VOLTAGE='16V',
 PART_NUMBER='CH6223MEA01',
 VALUE='22UF',
 PRIM_FILE='./archive_libs/logical/q_cap/chips/chips.prt';

PART_NAME
 PC217 'Q_CAP_0402-0.22UF,16V,10%,X7R,CH4223K1B00':;

SECTION_NUMBER 1
 '@T6G_MB_LIB.T6G(SCH_1):PAGE183_I71@PURE_QUANTA.Q_CAP(CHIPS)':
 C_PATH='@t6g_mb_lib.t6g(sch_1):page183_i71@pure_quanta.q_cap(chips)',
 P_PATH='@t6g_mb_lib.t6g(sch_1):page208_i71@pure_quanta.q_cap(chips)',
 PATH='I71',
 DRAWING='@T6G_MB_LIB.T6G(SCH_1):PAGE183',
 TOLERANCE='10%',
 MATERIAL='X7R',
 PHYS_PAGE='208',
 XY='(-3925,4650)',
 ROT='0',
 VER='1',
 PACK_TYPE='0402',
 LOCATION='PC217',
 CDS_LIB='pure_quanta',
 CDS_PART_NAME='Q_CAP_0402-0.22UF,16V,10%,X7R,CH4223K1B00',
 VOLTAGE='16V',
 PART_NUMBER='CH4223K1B00',
 VALUE='0.22UF',
 PRIM_FILE='./archive_libs/logical/q_cap/chips/chips.prt';

PART_NAME
 PC218 'Q_CAP_0402-0.22UF,16V,10%,X7R,CH4223K1B00':;

SECTION_NUMBER 1
 '@T6G_MB_LIB.T6G(SCH_1):PAGE183_I51@PURE_QUANTA.Q_CAP(CHIPS)':
 C_PATH='@t6g_mb_lib.t6g(sch_1):page183_i51@pure_quanta.q_cap(chips)',
 P_PATH='@t6g_mb_lib.t6g(sch_1):page208_i51@pure_quanta.q_cap(chips)',
 PATH='I51',
 DRAWING='@T6G_MB_LIB.T6G(SCH_1):PAGE183',
 TOLERANCE='10%',
 MATERIAL='X7R',
 PHYS_PAGE='208',
 XY='(-3850,1725)',
 ROT='0',
 VER='1',
 PACK_TYPE='0402',
 LOCATION='PC218',
 CDS_LIB='pure_quanta',
 CDS_PART_NAME='Q_CAP_0402-0.22UF,16V,10%,X7R,CH4223K1B00',
 VOLTAGE='16V',
 PART_NUMBER='CH4223K1B00',
 VALUE='0.22UF',
 PRIM_FILE='./archive_libs/logical/q_cap/chips/chips.prt';

PART_NAME
 PC218_2 'Q_CAP_C0805-22UF,16V,20%,X6S,CH6223MEA01':;

SECTION_NUMBER 1
 '@T6G_MB_LIB.T6G(SCH_1):PAGE183_I54@PURE_QUANTA.Q_CAP(CHIPS)':
 C_PATH='@t6g_mb_lib.t6g(sch_1):page183_i54@pure_quanta.q_cap(chips)',
 P_PATH='@t6g_mb_lib.t6g(sch_1):page208_i54@pure_quanta.q_cap(chips)',
 PATH='I54',
 DRAWING='@T6G_MB_LIB.T6G(SCH_1):PAGE183',
 TOLERANCE='20%',
 MATERIAL='X6S',
 PHYS_PAGE='208',
 XY='(-3700,2400)',
 ROT='0',
 VER='1',
 PACK_TYPE='C0805',
 LOCATION='PC218_2',
 CDS_LIB='pure_quanta',
 CDS_PART_NAME='Q_CAP_C0805-22UF,16V,20%,X6S,CH6223MEA01',
 VOLTAGE='16V',
 PART_NUMBER='CH6223MEA01',
 VALUE='22UF',
 PRIM_FILE='./archive_libs/logical/q_cap/chips/chips.prt';

PART_NAME
 PC219_1 'Q_CAP_C0805-22UF,16V,20%,X6S,CH6223MEA01':;

SECTION_NUMBER 1
 '@T6G_MB_LIB.T6G(SCH_1):PAGE183_I88@PURE_QUANTA.Q_CAP(CHIPS)':
 C_PATH='@t6g_mb_lib.t6g(sch_1):page183_i88@pure_quanta.q_cap(chips)',
 P_PATH='@t6g_mb_lib.t6g(sch_1):page208_i88@pure_quanta.q_cap(chips)',
 PATH='I88',
 DRAWING='@T6G_MB_LIB.T6G(SCH_1):PAGE183',
 TOLERANCE='20%',
 MATERIAL='X6S',
 PHYS_PAGE='208',
 XY='(-4000,5325)',
 ROT='0',
 VER='1',
 PACK_TYPE='C0805',
 LOCATION='PC219_1',
 CDS_LIB='pure_quanta',
 CDS_PART_NAME='Q_CAP_C0805-22UF,16V,20%,X6S,CH6223MEA01',
 VOLTAGE='16V',
 PART_NUMBER='CH6223MEA01',
 VALUE='22UF',
 PRIM_FILE='./archive_libs/logical/q_cap/chips/chips.prt';

PART_NAME
 PC220 'Q_CAPP_THLF-270UF,16V,20%,OSCON,CC72703MD38':;

SECTION_NUMBER 1
 '@T6G_MB_LIB.T6G(SCH_1):PAGE183_I75@PURE_QUANTA.Q_CAPP(CHIPS)':
 C_PATH='@t6g_mb_lib.t6g(sch_1):page183_i75@pure_quanta.q_capp(chips)',
 P_PATH='@t6g_mb_lib.t6g(sch_1):page208_i75@pure_quanta.q_capp(chips)',
 PATH='I75',
 DRAWING='@T6G_MB_LIB.T6G(SCH_1):PAGE183',
 TOLERANCE='20%',
 MATERIAL='OSCON',
 PHYS_PAGE='208',
 XY='(-3250,5325)',
 ROT='0',
 VER='1',
 PACK_TYPE='THLF',
 LOCATION='PC220',
 CDS_LIB='pure_quanta',
 CDS_PART_NAME='Q_CAPP_THLF-270UF,16V,20%,OSCON,CC72703MD38',
 VOLTAGE='16V',
 PART_NUMBER='CC72703MD38',
 VALUE='270UF',
 PRIM_FILE='./archive_libs/logical/q_capp/chips/chips.prt';

PART_NAME
 PC221_2 'Q_CAP_C0805-22UF,4V,20%,X6S,CH622KMEA03':;

SECTION_NUMBER 1
 '@T6G_MB_LIB.T6G(SCH_1):PAGE183_I90@PURE_QUANTA.Q_CAP(CHIPS)':
 C_PATH='@t6g_mb_lib.t6g(sch_1):page183_i90@pure_quanta.q_cap(chips)',
 P_PATH='@t6g_mb_lib.t6g(sch_1):page208_i90@pure_quanta.q_cap(chips)',
 PATH='I90',
 DRAWING='@T6G_MB_LIB.T6G(SCH_1):PAGE183',
 TOLERANCE='20%',
 MATERIAL='X6S',
 PHYS_PAGE='208',
 XY='(-2375,1325)',
 ROT='0',
 VER='1',
 PACK_TYPE='C0805',
 LOCATION='PC221_2',
 CDS_LIB='pure_quanta',
 CDS_PART_NAME='Q_CAP_C0805-22UF,4V,20%,X6S,CH622KMEA03',
 VOLTAGE='4V',
 PART_NUMBER='CH622KMEA03',
 VALUE='22UF',
 PRIM_FILE='./archive_libs/logical/q_cap/chips/chips.prt';

PART_NAME
 PC222 'Q_CAP_0402-0.1UF,25V,10%,X7R,CH4104K1B00':;

SECTION_NUMBER 1
 '@T6G_MB_LIB.T6G(SCH_1):PAGE183_I76@PURE_QUANTA.Q_CAP(CHIPS)':
 C_PATH='@t6g_mb_lib.t6g(sch_1):page183_i76@pure_quanta.q_cap(chips)',
 P_PATH='@t6g_mb_lib.t6g(sch_1):page208_i76@pure_quanta.q_cap(chips)',
 PATH='I76',
 DRAWING='@T6G_MB_LIB.T6G(SCH_1):PAGE183',
 TOLERANCE='10%',
 MATERIAL='X7R',
 PHYS_PAGE='208',
 XY='(-2300,4250)',
 ROT='0',
 VER='1',
 PACK_TYPE='0402',
 LOCATION='PC222',
 CDS_LIB='pure_quanta',
 CDS_PART_NAME='Q_CAP_0402-0.1UF,25V,10%,X7R,CH4104K1B00',
 VOLTAGE='25V',
 PART_NUMBER='CH4104K1B00',
 VALUE='0.1UF',
 PRIM_FILE='./archive_libs/logical/q_cap/chips/chips.prt';

PART_NAME
 PC223 'Q_CAPP_SMLF-470UF,2.5V,20%,SPCAP,CH747LM8825':;

SECTION_NUMBER 1
 '@T6G_MB_LIB.T6G(SCH_1):PAGE183_I58@PURE_QUANTA.Q_CAPP(CHIPS)':
 C_PATH='@t6g_mb_lib.t6g(sch_1):page183_i58@pure_quanta.q_capp(chips)',
 P_PATH='@t6g_mb_lib.t6g(sch_1):page208_i58@pure_quanta.q_capp(chips)',
 PATH='I58',
 DRAWING='@T6G_MB_LIB.T6G(SCH_1):PAGE183',
 TOLERANCE='20%',
 MATERIAL='SPCAP',
 PHYS_PAGE='208',
 XY='(-2725,2850)',
 ROT='0',
 VER='1',
 PACK_TYPE='SMLF',
 LOCATION='PC223',
 CDS_LIB='pure_quanta',
 CDS_PART_NAME='Q_CAPP_SMLF-470UF,2.5V,20%,SPCAP,CH747LM8825',
 VOLTAGE='2.5V',
 PART_NUMBER='CH747LM8825',
 VALUE='470UF',
 PRIM_FILE='./archive_libs/logical/q_capp/chips/chips.prt';

PART_NAME
 PC224_1 'Q_CAP_C0805-22UF,4V,20%,X6S,CH622KMEA03':;

SECTION_NUMBER 1
 '@T6G_MB_LIB.T6G(SCH_1):PAGE183_I81@PURE_QUANTA.Q_CAP(CHIPS)':
 C_PATH='@t6g_mb_lib.t6g(sch_1):page183_i81@pure_quanta.q_cap(chips)',
 P_PATH='@t6g_mb_lib.t6g(sch_1):page208_i81@pure_quanta.q_cap(chips)',
 PATH='I81',
 DRAWING='@T6G_MB_LIB.T6G(SCH_1):PAGE183',
 TOLERANCE='20%',
 MATERIAL='X6S',
 PHYS_PAGE='208',
 XY='(-1950,4250)',
 ROT='0',
 VER='1',
 PACK_TYPE='C0805',
 LOCATION='PC224_1',
 CDS_LIB='pure_quanta',
 CDS_PART_NAME='Q_CAP_C0805-22UF,4V,20%,X6S,CH622KMEA03',
 VOLTAGE='4V',
 PART_NUMBER='CH622KMEA03',
 VALUE='22UF',
 PRIM_FILE='./archive_libs/logical/q_cap/chips/chips.prt';

PART_NAME
 PC225_2 'Q_CAP_C0805-22UF,4V,20%,X6S,CH622KMEA03':;

SECTION_NUMBER 1
 '@T6G_MB_LIB.T6G(SCH_1):PAGE183_I62@PURE_QUANTA.Q_CAP(CHIPS)':
 C_PATH='@t6g_mb_lib.t6g(sch_1):page183_i62@pure_quanta.q_cap(chips)',
 P_PATH='@t6g_mb_lib.t6g(sch_1):page208_i62@pure_quanta.q_cap(chips)',
 PATH='I62',
 DRAWING='@T6G_MB_LIB.T6G(SCH_1):PAGE183',
 TOLERANCE='20%',
 MATERIAL='X6S',
 PHYS_PAGE='208',
 XY='(-1950,1325)',
 ROT='0',
 VER='1',
 PACK_TYPE='C0805',
 LOCATION='PC225_2',
 CDS_LIB='pure_quanta',
 CDS_PART_NAME='Q_CAP_C0805-22UF,4V,20%,X6S,CH622KMEA03',
 VOLTAGE='4V',
 PART_NUMBER='CH622KMEA03',
 VALUE='22UF',
 PRIM_FILE='./archive_libs/logical/q_cap/chips/chips.prt';

PART_NAME
 PC226 'Q_CAPP_SMLF-470UF,2.5V,20%,SPCAP,CH747LM8825':;

SECTION_NUMBER 1
 '@T6G_MB_LIB.T6G(SCH_1):PAGE183_I59@PURE_QUANTA.Q_CAPP(CHIPS)':
 C_PATH='@t6g_mb_lib.t6g(sch_1):page183_i59@pure_quanta.q_capp(chips)',
 P_PATH='@t6g_mb_lib.t6g(sch_1):page208_i59@pure_quanta.q_capp(chips)',
 PATH='I59',
 DRAWING='@T6G_MB_LIB.T6G(SCH_1):PAGE183',
 TOLERANCE='20%',
 MATERIAL='SPCAP',
 PHYS_PAGE='208',
 XY='(-2400,2850)',
 ROT='0',
 VER='1',
 PACK_TYPE='SMLF',
 LOCATION='PC226',
 CDS_LIB='pure_quanta',
 CDS_PART_NAME='Q_CAPP_SMLF-470UF,2.5V,20%,SPCAP,CH747LM8825',
 VOLTAGE='2.5V',
 PART_NUMBER='CH747LM8825',
 VALUE='470UF',
 PRIM_FILE='./archive_libs/logical/q_capp/chips/chips.prt';

PART_NAME
 PC227 'Q_CAP_C0805-22UF,16V,20%,X6S,CH6223MEA01':;

SECTION_NUMBER 1
 '@T6G_MB_LIB.T6G(SCH_1):PAGE184_I25@PURE_QUANTA.Q_CAP(CHIPS)':
 C_PATH='@t6g_mb_lib.t6g(sch_1):page184_i25@pure_quanta.q_cap(chips)',
 P_PATH='@t6g_mb_lib.t6g(sch_1):page209_i25@pure_quanta.q_cap(chips)',
 PATH='I25',
 DRAWING='@T6G_MB_LIB.T6G(SCH_1):PAGE184',
 TOLERANCE='20%',
 MATERIAL='X6S',
 PHYS_PAGE='209',
 XY='(-7575,4125)',
 ROT='0',
 VER='1',
 PACK_TYPE='C0805',
 LOCATION='PC227',
 CDS_LIB='pure_quanta',
 CDS_PART_NAME='Q_CAP_C0805-22UF,16V,20%,X6S,CH6223MEA01',
 VOLTAGE='16V',
 PART_NUMBER='CH6223MEA01',
 VALUE='22UF',
 PRIM_FILE='./archive_libs/logical/q_cap/chips/chips.prt';

PART_NAME
 PC227_1 'Q_CAP_C0805-22UF,4V,20%,X6S,CH622KMEA03':;

SECTION_NUMBER 1
 '@T6G_MB_LIB.T6G(SCH_1):PAGE183_I82@PURE_QUANTA.Q_CAP(CHIPS)':
 C_PATH='@t6g_mb_lib.t6g(sch_1):page183_i82@pure_quanta.q_cap(chips)',
 P_PATH='@t6g_mb_lib.t6g(sch_1):page208_i82@pure_quanta.q_cap(chips)',
 PATH='I82',
 DRAWING='@T6G_MB_LIB.T6G(SCH_1):PAGE183',
 TOLERANCE='20%',
 MATERIAL='X6S',
 PHYS_PAGE='208',
 XY='(-1525,4250)',
 ROT='0',
 VER='1',
 PACK_TYPE='C0805',
 LOCATION='PC227_1',
 CDS_LIB='pure_quanta',
 CDS_PART_NAME='Q_CAP_C0805-22UF,4V,20%,X6S,CH622KMEA03',
 VOLTAGE='4V',
 PART_NUMBER='CH622KMEA03',
 VALUE='22UF',
 PRIM_FILE='./archive_libs/logical/q_cap/chips/chips.prt';

PART_NAME
 PC228 'Q_CAPP_SMLF-390UF,2.5V,20%,ALUM,CC7390JMZ13':;

SECTION_NUMBER 1
 '@T6G_MB_LIB.T6G(SCH_1):PAGE183_I65@PURE_QUANTA.Q_CAPP(CHIPS)':
 C_PATH='@t6g_mb_lib.t6g(sch_1):page183_i65@pure_quanta.q_capp(chips)',
 P_PATH='@t6g_mb_lib.t6g(sch_1):page208_i65@pure_quanta.q_capp(chips)',
 PATH='I65',
 DRAWING='@T6G_MB_LIB.T6G(SCH_1):PAGE183',
 TOLERANCE='20%',
 MATERIAL='ALUM',
 PHYS_PAGE='208',
 XY='(-1675,2875)',
 ROT='0',
 VER='1',
 PACK_TYPE='SMLF',
 LOCATION='PC228',
 CDS_LIB='pure_quanta',
 CDS_PART_NAME='Q_CAPP_SMLF-390UF,2.5V,20%,ALUM,CC7390JMZ13',
 VOLTAGE='2.5V',
 PART_NUMBER='CC7390JMZ13',
 VALUE='390UF',
 PRIM_FILE='./archive_libs/logical/q_capp/chips/chips.prt';

PART_NAME
 PC229 'Q_CAPP_SMLF-390UF,2.5V,20%,ALUM,CC7390JMZ13':;

SECTION_NUMBER 1
 '@T6G_MB_LIB.T6G(SCH_1):PAGE183_I66@PURE_QUANTA.Q_CAPP(CHIPS)':
 C_PATH='@t6g_mb_lib.t6g(sch_1):page183_i66@pure_quanta.q_capp(chips)',
 P_PATH='@t6g_mb_lib.t6g(sch_1):page208_i66@pure_quanta.q_capp(chips)',
 PATH='I66',
 DRAWING='@T6G_MB_LIB.T6G(SCH_1):PAGE183',
 TOLERANCE='20%',
 MATERIAL='ALUM',
 PHYS_PAGE='208',
 XY='(-1350,2875)',
 ROT='0',
 VER='1',
 PACK_TYPE='SMLF',
 LOCATION='PC229',
 CDS_LIB='pure_quanta',
 CDS_PART_NAME='Q_CAPP_SMLF-390UF,2.5V,20%,ALUM,CC7390JMZ13',
 VOLTAGE='2.5V',
 PART_NUMBER='CC7390JMZ13',
 VALUE='390UF',
 PRIM_FILE='./archive_libs/logical/q_capp/chips/chips.prt';

PART_NAME
 PC230 'Q_CAPP_SMLF-390UF,2.5V,20%,ALUM,CC7390JMZ13':;

SECTION_NUMBER 1
 '@T6G_MB_LIB.T6G(SCH_1):PAGE183_I67@PURE_QUANTA.Q_CAPP(CHIPS)':
 C_PATH='@t6g_mb_lib.t6g(sch_1):page183_i67@pure_quanta.q_capp(chips)',
 P_PATH='@t6g_mb_lib.t6g(sch_1):page208_i67@pure_quanta.q_capp(chips)',
 PATH='I67',
 DRAWING='@T6G_MB_LIB.T6G(SCH_1):PAGE183',
 TOLERANCE='20%',
 MATERIAL='ALUM',
 PHYS_PAGE='208',
 XY='(-1050,2875)',
 ROT='0',
 VER='1',
 PACK_TYPE='SMLF',
 LOCATION='PC230',
 CDS_LIB='pure_quanta',
 CDS_PART_NAME='Q_CAPP_SMLF-390UF,2.5V,20%,ALUM,CC7390JMZ13',
 VOLTAGE='2.5V',
 PART_NUMBER='CC7390JMZ13',
 VALUE='390UF',
 PRIM_FILE='./archive_libs/logical/q_capp/chips/chips.prt';

PART_NAME
 PC237 'Q_CAP_C0402-1UF,25V,10%,X6S,CH5104KEB02':;

SECTION_NUMBER 1
 '@T6G_MB_LIB.T6G(SCH_1):PAGE184_I28@PURE_QUANTA.Q_CAP(CHIPS)':
 C_PATH='@t6g_mb_lib.t6g(sch_1):page184_i28@pure_quanta.q_cap(chips)',
 P_PATH='@t6g_mb_lib.t6g(sch_1):page209_i28@pure_quanta.q_cap(chips)',
 PATH='I28',
 DRAWING='@T6G_MB_LIB.T6G(SCH_1):PAGE184',
 TOLERANCE='10%',
 MATERIAL='X6S',
 PHYS_PAGE='209',
 XY='(-6725,4125)',
 ROT='0',
 VER='1',
 PACK_TYPE='C0402',
 LOCATION='PC237',
 CDS_LIB='pure_quanta',
 CDS_PART_NAME='Q_CAP_C0402-1UF,25V,10%,X6S,CH5104KEB02',
 VOLTAGE='25V',
 PART_NUMBER='CH5104KEB02',
 VALUE='1UF',
 PRIM_FILE='./archive_libs/logical/q_cap/chips/chips.prt';

PART_NAME
 PC243 'Q_CAP_0402-0.1UF,25V,10%,X7R,CH4104K1B00':;

SECTION_NUMBER 1
 '@T6G_MB_LIB.T6G(SCH_1):PAGE185_I22@PURE_QUANTA.Q_CAP(CHIPS)':
 C_PATH='@t6g_mb_lib.t6g(sch_1):page185_i22@pure_quanta.q_cap(chips)',
 P_PATH='@t6g_mb_lib.t6g(sch_1):page210_i22@pure_quanta.q_cap(chips)',
 PATH='I22',
 DRAWING='@T6G_MB_LIB.T6G(SCH_1):PAGE185',
 TOLERANCE='10%',
 MATERIAL='X7R',
 PHYS_PAGE='210',
 XY='(-3250,2425)',
 ROT='0',
 VER='1',
 PACK_TYPE='0402',
 LOCATION='PC243',
 CDS_LIB='pure_quanta',
 CDS_PART_NAME='Q_CAP_0402-0.1UF,25V,10%,X7R,CH4104K1B00',
 VOLTAGE='25V',
 PART_NUMBER='CH4104K1B00',
 VALUE='0.1UF',
 PRIM_FILE='./archive_libs/logical/q_cap/chips/chips.prt';

PART_NAME
 PC244 'Q_CAP_0402-3300PF,50V,10%,X7R,TMP_QCH2336K1B12':;

SECTION_NUMBER 1
 '@T6G_MB_LIB.T6G(SCH_1):PAGE185_I60@PURE_QUANTA.Q_CAP(CHIPS)':
 C_PATH='@t6g_mb_lib.t6g(sch_1):page185_i60@pure_quanta.q_cap(chips)',
 P_PATH='@t6g_mb_lib.t6g(sch_1):page210_i60@pure_quanta.q_cap(chips)',
 PATH='I60',
 DRAWING='@T6G_MB_LIB.T6G(SCH_1):PAGE185',
 TOLERANCE='10%',
 MATERIAL='X7R',
 PHYS_PAGE='210',
 XY='(-2525,5700)',
 ROT='0',
 VER='1',
 PACK_TYPE='0402',
 LOCATION='PC244',
 CDS_LIB='pure_quanta',
 CDS_PART_NAME='Q_CAP_0402-3300PF,50V,10%,X7R,TMP_QCH2336K1B12',
 VOLTAGE='50V',
 PART_NUMBER='TMP_QCH2336K1B12',
 VALUE='3300PF',
 PRIM_FILE='./archive_libs/logical/q_cap/chips/chips.prt';

PART_NAME
 PC245 'Q_CAP_0402-3300PF,50V,10%,X7R,TMP_QCH2336K1B12':;

SECTION_NUMBER 1
 '@T6G_MB_LIB.T6G(SCH_1):PAGE185_I58@PURE_QUANTA.Q_CAP(CHIPS)':
 C_PATH='@t6g_mb_lib.t6g(sch_1):page185_i58@pure_quanta.q_cap(chips)',
 P_PATH='@t6g_mb_lib.t6g(sch_1):page210_i58@pure_quanta.q_cap(chips)',
 PATH='I58',
 DRAWING='@T6G_MB_LIB.T6G(SCH_1):PAGE185',
 TOLERANCE='10%',
 MATERIAL='X7R',
 PHYS_PAGE='210',
 XY='(-2450,4600)',
 ROT='0',
 VER='1',
 PACK_TYPE='0402',
 LOCATION='PC245',
 CDS_LIB='pure_quanta',
 CDS_PART_NAME='Q_CAP_0402-3300PF,50V,10%,X7R,TMP_QCH2336K1B12',
 VOLTAGE='50V',
 PART_NUMBER='TMP_QCH2336K1B12',
 VALUE='3300PF',
 PRIM_FILE='./archive_libs/logical/q_cap/chips/chips.prt';

PART_NAME
 PC247 'Q_CAP_0402-1UF,6.3V,10%,X7R,CH5101K1B01':;

SECTION_NUMBER 1
 '@T6G_MB_LIB.T6G(SCH_1):PAGE185_I132@PURE_QUANTA.Q_CAP(CHIPS)':
 C_PATH='@t6g_mb_lib.t6g(sch_1):page185_i132@pure_quanta.q_cap(chips)',
 P_PATH='@t6g_mb_lib.t6g(sch_1):page210_i132@pure_quanta.q_cap(chips)',
 PATH='I132',
 DRAWING='@T6G_MB_LIB.T6G(SCH_1):PAGE185',
 TOLERANCE='10%',
 MATERIAL='X7R',
 PHYS_PAGE='210',
 XY='(-2450,3500)',
 ROT='0',
 VER='2',
 PACK_TYPE='0402',
 LOCATION='PC247',
 CDS_LIB='pure_quanta',
 CDS_PART_NAME='Q_CAP_0402-1UF,6.3V,10%,X7R,CH5101K1B01',
 VOLTAGE='6.3V',
 PART_NUMBER='CH5101K1B01',
 VALUE='1UF',
 PRIM_FILE='./archive_libs/logical/q_cap/chips/chips.prt';

PART_NAME
 PC250 'Q_CAP_0402-470PF,50V,10%,X7R,TMP_QCH14706KB18':;

SECTION_NUMBER 1
 '@T6G_MB_LIB.T6G(SCH_1):PAGE185_I91@PURE_QUANTA.Q_CAP(CHIPS)':
 C_PATH='@t6g_mb_lib.t6g(sch_1):page185_i91@pure_quanta.q_cap(chips)',
 P_PATH='@t6g_mb_lib.t6g(sch_1):page210_i91@pure_quanta.q_cap(chips)',
 PATH='I91',
 DRAWING='@T6G_MB_LIB.T6G(SCH_1):PAGE185',
 TOLERANCE='10%',
 MATERIAL='X7R',
 PHYS_PAGE='210',
 XY='(-150,2475)',
 ROT='0',
 VER='1',
 PACK_TYPE='0402',
 LOCATION='PC250',
 CDS_LIB='pure_quanta',
 CDS_PART_NAME='Q_CAP_0402-470PF,50V,10%,X7R,TMP_QCH14706KB18',
 VOLTAGE='50V',
 PART_NUMBER='TMP_QCH14706KB18',
 VALUE='470PF',
 PRIM_FILE='./archive_libs/logical/q_cap/chips/chips.prt';

PART_NAME
 PC251 'Q_CAP_C0402-10UF,6.3V,20%,X6S,CH6101MEB03':;

SECTION_NUMBER 1
 '@T6G_MB_LIB.T6G(SCH_1):PAGE185_I125@PURE_QUANTA.Q_CAP(CHIPS)':
 C_PATH='@t6g_mb_lib.t6g(sch_1):page185_i125@pure_quanta.q_cap(chips)',
 P_PATH='@t6g_mb_lib.t6g(sch_1):page210_i125@pure_quanta.q_cap(chips)',
 PATH='I125',
 DRAWING='@T6G_MB_LIB.T6G(SCH_1):PAGE185',
 TOLERANCE='20%',
 MATERIAL='X6S',
 PHYS_PAGE='210',
 XY='(300,7425)',
 ROT='0',
 VER='1',
 PACK_TYPE='C0402',
 LOCATION='PC251',
 CDS_LIB='pure_quanta',
 CDS_PART_NAME='Q_CAP_C0402-10UF,6.3V,20%,X6S,CH6101MEB03',
 VOLTAGE='6.3V',
 PART_NUMBER='CH6101MEB03',
 VALUE='10UF',
 PRIM_FILE='./archive_libs/logical/q_cap/chips/chips.prt';

PART_NAME
 PC252 'Q_CAP_C0402-1UF,16V,10%,X6S,CH5103KEB01':;

SECTION_NUMBER 1
 '@T6G_MB_LIB.T6G(SCH_1):PAGE185_I127@PURE_QUANTA.Q_CAP(CHIPS)':
 C_PATH='@t6g_mb_lib.t6g(sch_1):page185_i127@pure_quanta.q_cap(chips)',
 P_PATH='@t6g_mb_lib.t6g(sch_1):page210_i127@pure_quanta.q_cap(chips)',
 PATH='I127',
 DRAWING='@T6G_MB_LIB.T6G(SCH_1):PAGE185',
 TOLERANCE='10%',
 MATERIAL='X6S',
 PHYS_PAGE='210',
 XY='(325,7900)',
 ROT='0',
 VER='1',
 PACK_TYPE='C0402',
 LOCATION='PC252',
 CDS_LIB='pure_quanta',
 CDS_PART_NAME='Q_CAP_C0402-1UF,16V,10%,X6S,CH5103KEB01',
 VOLTAGE='16V',
 PART_NUMBER='CH5103KEB01',
 VALUE='1UF',
 PRIM_FILE='./archive_libs/logical/q_cap/chips/chips.prt';

PART_NAME
 PC253 'Q_CAP_0402-470PF,50V,10%,X7R,TMP_QCH14706KB18':;

SECTION_NUMBER 1
 '@T6G_MB_LIB.T6G(SCH_1):PAGE185_I94@PURE_QUANTA.Q_CAP(CHIPS)':
 C_PATH='@t6g_mb_lib.t6g(sch_1):page185_i94@pure_quanta.q_cap(chips)',
 P_PATH='@t6g_mb_lib.t6g(sch_1):page210_i94@pure_quanta.q_cap(chips)',
 PATH='I94',
 DRAWING='@T6G_MB_LIB.T6G(SCH_1):PAGE185',
 TOLERANCE='10%',
 MATERIAL='X7R',
 PHYS_PAGE='210',
 XY='(475,2800)',
 ROT='0',
 VER='1',
 PACK_TYPE='0402',
 LOCATION='PC253',
 CDS_LIB='pure_quanta',
 CDS_PART_NAME='Q_CAP_0402-470PF,50V,10%,X7R,TMP_QCH14706KB18',
 VOLTAGE='50V',
 PART_NUMBER='TMP_QCH14706KB18',
 VALUE='470PF',
 PRIM_FILE='./archive_libs/logical/q_cap/chips/chips.prt';

PART_NAME
 PC254 'Q_CAP_C0805-22UF,16V,20%,X6S,CH6223MEA01':;

SECTION_NUMBER 1
 '@T6G_MB_LIB.T6G(SCH_1):PAGE184_I26@PURE_QUANTA.Q_CAP(CHIPS)':
 C_PATH='@t6g_mb_lib.t6g(sch_1):page184_i26@pure_quanta.q_cap(chips)',
 P_PATH='@t6g_mb_lib.t6g(sch_1):page209_i26@pure_quanta.q_cap(chips)',
 PATH='I26',
 DRAWING='@T6G_MB_LIB.T6G(SCH_1):PAGE184',
 TOLERANCE='20%',
 MATERIAL='X6S',
 PHYS_PAGE='209',
 XY='(-7225,4125)',
 ROT='0',
 VER='1',
 PACK_TYPE='C0805',
 LOCATION='PC254',
 CDS_LIB='pure_quanta',
 CDS_PART_NAME='Q_CAP_C0805-22UF,16V,20%,X6S,CH6223MEA01',
 VOLTAGE='16V',
 PART_NUMBER='CH6223MEA01',
 VALUE='22UF',
 PRIM_FILE='./archive_libs/logical/q_cap/chips/chips.prt';

PART_NAME
 PC254_1 'Q_CAP_0402-0.1UF,25V,10%,X7R,CH4104K1B00':;

SECTION_NUMBER 1
 '@T6G_MB_LIB.T6G(SCH_1):PAGE186_I16@PURE_QUANTA.Q_CAP(CHIPS)':
 C_PATH='@t6g_mb_lib.t6g(sch_1):page186_i16@pure_quanta.q_cap(chips)',
 P_PATH='@t6g_mb_lib.t6g(sch_1):page211_i16@pure_quanta.q_cap(chips)',
 PATH='I16',
 DRAWING='@T6G_MB_LIB.T6G(SCH_1):PAGE186',
 TOLERANCE='10%',
 MATERIAL='X7R',
 PHYS_PAGE='211',
 XY='(-7950,4175)',
 ROT='0',
 VER='1',
 PACK_TYPE='0402',
 LOCATION='PC254_1',
 CDS_LIB='pure_quanta',
 CDS_PART_NAME='Q_CAP_0402-0.1UF,25V,10%,X7R,CH4104K1B00',
 VOLTAGE='25V',
 PART_NUMBER='CH4104K1B00',
 VALUE='0.1UF',
 PRIM_FILE='./archive_libs/logical/q_cap/chips/chips.prt';

PART_NAME
 PC255 'Q_CAP_C0402-560PF,50V,10%,EMPTY,CH1566K1B09':;

SECTION_NUMBER 1
 '@T6G_MB_LIB.T6G(SCH_1):PAGE200_I27@PURE_QUANTA.Q_CAP(CHIPS)':
 C_PATH='@t6g_mb_lib.t6g(sch_1):page200_i27@pure_quanta.q_cap(chips)',
 P_PATH='@t6g_mb_lib.t6g(sch_1):page225_i27@pure_quanta.q_cap(chips)',
 PATH='I27',
 DRAWING='@T6G_MB_LIB.T6G(SCH_1):PAGE200',
 TOLERANCE='10%',
 MATERIAL='EMPTY',
 PHYS_PAGE='225',
 XY='(-4550,1525)',
 ROT='0',
 VER='1',
 PACK_TYPE='C0402',
 LOCATION='PC255',
 CDS_LIB='pure_quanta',
 CDS_PART_NAME='Q_CAP_C0402-560PF,50V,10%,EMPTY,CH1566K1B09',
 VOLTAGE='50V',
 PART_NUMBER='CH1566K1B09',
 VALUE='560PF',
 PRIM_FILE='./archive_libs/logical/q_cap/chips/chips.prt';

PART_NAME
 PC255_2 'Q_CAP_0402-0.1UF,25V,10%,X7R,CH4104K1B00':;

SECTION_NUMBER 1
 '@T6G_MB_LIB.T6G(SCH_1):PAGE186_I5@PURE_QUANTA.Q_CAP(CHIPS)':
 C_PATH='@t6g_mb_lib.t6g(sch_1):page186_i5@pure_quanta.q_cap(chips)',
 P_PATH='@t6g_mb_lib.t6g(sch_1):page211_i5@pure_quanta.q_cap(chips)',
 PATH='I5',
 DRAWING='@T6G_MB_LIB.T6G(SCH_1):PAGE186',
 TOLERANCE='10%',
 MATERIAL='X7R',
 PHYS_PAGE='211',
 XY='(-7925,1425)',
 ROT='0',
 VER='1',
 PACK_TYPE='0402',
 LOCATION='PC255_2',
 CDS_LIB='pure_quanta',
 CDS_PART_NAME='Q_CAP_0402-0.1UF,25V,10%,X7R,CH4104K1B00',
 VOLTAGE='25V',
 PART_NUMBER='CH4104K1B00',
 VALUE='0.1UF',
 PRIM_FILE='./archive_libs/logical/q_cap/chips/chips.prt';

PART_NAME
 PC256 'Q_CAP_C0402-2.2UF,10V,10%,X6S,CH5222KEB01':;

SECTION_NUMBER 1
 '@T6G_MB_LIB.T6G(SCH_1):PAGE186_I36@PURE_QUANTA.Q_CAP(CHIPS)':
 C_PATH='@t6g_mb_lib.t6g(sch_1):page186_i36@pure_quanta.q_cap(chips)',
 P_PATH='@t6g_mb_lib.t6g(sch_1):page211_i36@pure_quanta.q_cap(chips)',
 PATH='I36',
 DRAWING='@T6G_MB_LIB.T6G(SCH_1):PAGE186',
 TOLERANCE='10%',
 MATERIAL='X6S',
 PHYS_PAGE='211',
 XY='(-7600,4800)',
 ROT='0',
 VER='1',
 PACK_TYPE='C0402',
 LOCATION='PC256',
 CDS_LIB='pure_quanta',
 CDS_PART_NAME='Q_CAP_C0402-2.2UF,10V,10%,X6S,CH5222KEB01',
 VOLTAGE='10V',
 PART_NUMBER='CH5222KEB01',
 VALUE='2.2UF',
 PRIM_FILE='./archive_libs/logical/q_cap/chips/chips.prt';

PART_NAME
 PC257 'Q_CAP_C0402-2.2UF,10V,10%,X6S,CH5222KEB01':;

SECTION_NUMBER 1
 '@T6G_MB_LIB.T6G(SCH_1):PAGE186_I9@PURE_QUANTA.Q_CAP(CHIPS)':
 C_PATH='@t6g_mb_lib.t6g(sch_1):page186_i9@pure_quanta.q_cap(chips)',
 P_PATH='@t6g_mb_lib.t6g(sch_1):page211_i9@pure_quanta.q_cap(chips)',
 PATH='I9',
 DRAWING='@T6G_MB_LIB.T6G(SCH_1):PAGE186',
 TOLERANCE='10%',
 MATERIAL='X6S',
 PHYS_PAGE='211',
 XY='(-7575,2050)',
 ROT='0',
 VER='1',
 PACK_TYPE='C0402',
 LOCATION='PC257',
 CDS_LIB='pure_quanta',
 CDS_PART_NAME='Q_CAP_C0402-2.2UF,10V,10%,X6S,CH5222KEB01',
 VOLTAGE='10V',
 PART_NUMBER='CH5222KEB01',
 VALUE='2.2UF',
 PRIM_FILE='./archive_libs/logical/q_cap/chips/chips.prt';

PART_NAME
 PC258 'Q_CAP_0402-0.022UF,25V,10%,X7R,CH3224K1B01':;

SECTION_NUMBER 1
 '@T6G_MB_LIB.T6G(SCH_1):PAGE184_I21@PURE_QUANTA.Q_CAP(CHIPS)':
 C_PATH='@t6g_mb_lib.t6g(sch_1):page184_i21@pure_quanta.q_cap(chips)',
 P_PATH='@t6g_mb_lib.t6g(sch_1):page209_i21@pure_quanta.q_cap(chips)',
 PATH='I21',
 DRAWING='@T6G_MB_LIB.T6G(SCH_1):PAGE184',
 TOLERANCE='10%',
 MATERIAL='X7R',
 PHYS_PAGE='209',
 XY='(-5000,2700)',
 ROT='0',
 VER='1',
 PACK_TYPE='0402',
 LOCATION='PC258',
 CDS_LIB='pure_quanta',
 CDS_PART_NAME='Q_CAP_0402-0.022UF,25V,10%,X7R,CH3224K1B01',
 VOLTAGE='25V',
 PART_NUMBER='CH3224K1B01',
 VALUE='0.022UF',
 PRIM_FILE='./archive_libs/logical/q_cap/chips/chips.prt';

PART_NAME
 PC258_C0P1_1 'Q_CAP_C0402-2.2UF,10V,10%,X6S,CH5222KEB01':;

SECTION_NUMBER 1
 '@T6G_MB_LIB.T6G(SCH_1):PAGE186_I44@PURE_QUANTA.Q_CAP(CHIPS)':
 C_PATH='@t6g_mb_lib.t6g(sch_1):page186_i44@pure_quanta.q_cap(chips)',
 P_PATH='@t6g_mb_lib.t6g(sch_1):page211_i44@pure_quanta.q_cap(chips)',
 PATH='I44',
 DRAWING='@T6G_MB_LIB.T6G(SCH_1):PAGE186',
 TOLERANCE='10%',
 MATERIAL='X6S',
 PHYS_PAGE='211',
 XY='(-7250,5375)',
 ROT='0',
 VER='1',
 PACK_TYPE='C0402',
 LOCATION='PC258_C0P1_1',
 CDS_LIB='pure_quanta',
 CDS_PART_NAME='Q_CAP_C0402-2.2UF,10V,10%,X6S,CH5222KEB01',
 VOLTAGE='10V',
 PART_NUMBER='CH5222KEB01',
 VALUE='2.2UF',
 PRIM_FILE='./archive_libs/logical/q_cap/chips/chips.prt';

PART_NAME
 PC259 'Q_CAP_0402-220PF,50V,10%,X7R,TMP_QCH12206KB14':;

SECTION_NUMBER 1
 '@T6G_MB_LIB.T6G(SCH_1):PAGE184_I33@PURE_QUANTA.Q_CAP(CHIPS)':
 C_PATH='@t6g_mb_lib.t6g(sch_1):page184_i33@pure_quanta.q_cap(chips)',
 P_PATH='@t6g_mb_lib.t6g(sch_1):page209_i33@pure_quanta.q_cap(chips)',
 PATH='I33',
 DRAWING='@T6G_MB_LIB.T6G(SCH_1):PAGE184',
 TOLERANCE='10%',
 MATERIAL='X7R',
 PHYS_PAGE='209',
 XY='(-3575,2800)',
 ROT='0',
 VER='2',
 PACK_TYPE='0402',
 LOCATION='PC259',
 CDS_LIB='pure_quanta',
 CDS_PART_NAME='Q_CAP_0402-220PF,50V,10%,X7R,TMP_QCH12206KB14',
 VOLTAGE='50V',
 PART_NUMBER='TMP_QCH12206KB14',
 VALUE='220PF',
 PRIM_FILE='./archive_libs/logical/q_cap/chips/chips.prt';

PART_NAME
 PC259_C0P1_2 'Q_CAP_C0402-2.2UF,10V,10%,X6S,CH5222KEB01':;

SECTION_NUMBER 1
 '@T6G_MB_LIB.T6G(SCH_1):PAGE186_I13@PURE_QUANTA.Q_CAP(CHIPS)':
 C_PATH='@t6g_mb_lib.t6g(sch_1):page186_i13@pure_quanta.q_cap(chips)',
 P_PATH='@t6g_mb_lib.t6g(sch_1):page211_i13@pure_quanta.q_cap(chips)',
 PATH='I13',
 DRAWING='@T6G_MB_LIB.T6G(SCH_1):PAGE186',
 TOLERANCE='10%',
 MATERIAL='X6S',
 PHYS_PAGE='211',
 XY='(-7225,2625)',
 ROT='0',
 VER='1',
 PACK_TYPE='C0402',
 LOCATION='PC259_C0P1_2',
 CDS_LIB='pure_quanta',
 CDS_PART_NAME='Q_CAP_C0402-2.2UF,10V,10%,X6S,CH5222KEB01',
 VOLTAGE='10V',
 PART_NUMBER='CH5222KEB01',
 VALUE='2.2UF',
 PRIM_FILE='./archive_libs/logical/q_cap/chips/chips.prt';

PART_NAME
 PC260 'Q_CAP_C0805-22UF,4V,20%,EMPTY,CH622KMEA03':;

SECTION_NUMBER 1
 '@T6G_MB_LIB.T6G(SCH_1):PAGE184_I41@PURE_QUANTA.Q_CAP(CHIPS)':
 C_PATH='@t6g_mb_lib.t6g(sch_1):page184_i41@pure_quanta.q_cap(chips)',
 P_PATH='@t6g_mb_lib.t6g(sch_1):page209_i41@pure_quanta.q_cap(chips)',
 PATH='I41',
 DRAWING='@T6G_MB_LIB.T6G(SCH_1):PAGE184',
 TOLERANCE='20%',
 MATERIAL='EMPTY',
 PHYS_PAGE='209',
 XY='(-2025,3325)',
 ROT='0',
 VER='1',
 PACK_TYPE='C0805',
 LOCATION='PC260',
 CDS_LIB='pure_quanta',
 CDS_PART_NAME='Q_CAP_C0805-22UF,4V,20%,EMPTY,CH622KMEA03',
 VOLTAGE='4V',
 PART_NUMBER='CH622KMEA03',
 VALUE='22UF',
 PRIM_FILE='./archive_libs/logical/q_cap/chips/chips.prt';

PART_NAME
 PC260_1 'Q_CAP_0402-0.1UF,25V,10%,X7R,CH4104K1B00':;

SECTION_NUMBER 1
 '@T6G_MB_LIB.T6G(SCH_1):PAGE186_I46@PURE_QUANTA.Q_CAP(CHIPS)':
 C_PATH='@t6g_mb_lib.t6g(sch_1):page186_i46@pure_quanta.q_cap(chips)',
 P_PATH='@t6g_mb_lib.t6g(sch_1):page211_i46@pure_quanta.q_cap(chips)',
 PATH='I46',
 DRAWING='@T6G_MB_LIB.T6G(SCH_1):PAGE186',
 TOLERANCE='10%',
 MATERIAL='X7R',
 PHYS_PAGE='211',
 XY='(-5475,5325)',
 ROT='0',
 VER='1',
 PACK_TYPE='0402',
 LOCATION='PC260_1',
 CDS_LIB='pure_quanta',
 CDS_PART_NAME='Q_CAP_0402-0.1UF,25V,10%,X7R,CH4104K1B00',
 VOLTAGE='25V',
 PART_NUMBER='CH4104K1B00',
 VALUE='0.1UF',
 PRIM_FILE='./archive_libs/logical/q_cap/chips/chips.prt';

PART_NAME
 PC261 'Q_CAP_C0805-22UF,4V,20%,EMPTY,CH622KMEA03':;

SECTION_NUMBER 1
 '@T6G_MB_LIB.T6G(SCH_1):PAGE184_I46@PURE_QUANTA.Q_CAP(CHIPS)':
 C_PATH='@t6g_mb_lib.t6g(sch_1):page184_i46@pure_quanta.q_cap(chips)',
 P_PATH='@t6g_mb_lib.t6g(sch_1):page209_i46@pure_quanta.q_cap(chips)',
 PATH='I46',
 DRAWING='@T6G_MB_LIB.T6G(SCH_1):PAGE184',
 TOLERANCE='20%',
 MATERIAL='EMPTY',
 PHYS_PAGE='209',
 XY='(-1700,3325)',
 ROT='0',
 VER='1',
 PACK_TYPE='C0805',
 LOCATION='PC261',
 CDS_LIB='pure_quanta',
 CDS_PART_NAME='Q_CAP_C0805-22UF,4V,20%,EMPTY,CH622KMEA03',
 VOLTAGE='4V',
 PART_NUMBER='CH622KMEA03',
 VALUE='22UF',
 PRIM_FILE='./archive_libs/logical/q_cap/chips/chips.prt';

PART_NAME
 PC261_2 'Q_CAP_0402-0.1UF,25V,10%,X7R,CH4104K1B00':;

SECTION_NUMBER 1
 '@T6G_MB_LIB.T6G(SCH_1):PAGE186_I25@PURE_QUANTA.Q_CAP(CHIPS)':
 C_PATH='@t6g_mb_lib.t6g(sch_1):page186_i25@pure_quanta.q_cap(chips)',
 P_PATH='@t6g_mb_lib.t6g(sch_1):page211_i25@pure_quanta.q_cap(chips)',
 PATH='I25',
 DRAWING='@T6G_MB_LIB.T6G(SCH_1):PAGE186',
 TOLERANCE='10%',
 MATERIAL='X7R',
 PHYS_PAGE='211',
 XY='(-5475,2575)',
 ROT='0',
 VER='1',
 PACK_TYPE='0402',
 LOCATION='PC261_2',
 CDS_LIB='pure_quanta',
 CDS_PART_NAME='Q_CAP_0402-0.1UF,25V,10%,X7R,CH4104K1B00',
 VOLTAGE='25V',
 PART_NUMBER='CH4104K1B00',
 VALUE='0.1UF',
 PRIM_FILE='./archive_libs/logical/q_cap/chips/chips.prt';

PART_NAME
 PC262_1 'Q_CAP_C0402-1UF,25V,10%,X6S,CH5104KEB02':;

SECTION_NUMBER 1
 '@T6G_MB_LIB.T6G(SCH_1):PAGE186_I47@PURE_QUANTA.Q_CAP(CHIPS)':
 C_PATH='@t6g_mb_lib.t6g(sch_1):page186_i47@pure_quanta.q_cap(chips)',
 P_PATH='@t6g_mb_lib.t6g(sch_1):page211_i47@pure_quanta.q_cap(chips)',
 PATH='I47',
 DRAWING='@T6G_MB_LIB.T6G(SCH_1):PAGE186',
 TOLERANCE='10%',
 MATERIAL='X6S',
 PHYS_PAGE='211',
 XY='(-5150,5325)',
 ROT='0',
 VER='1',
 PACK_TYPE='C0402',
 LOCATION='PC262_1',
 CDS_LIB='pure_quanta',
 CDS_PART_NAME='Q_CAP_C0402-1UF,25V,10%,X6S,CH5104KEB02',
 VOLTAGE='25V',
 PART_NUMBER='CH5104KEB02',
 VALUE='1UF',
 PRIM_FILE='./archive_libs/logical/q_cap/chips/chips.prt';

PART_NAME
 PC263_2 'Q_CAP_C0402-1UF,25V,10%,X6S,CH5104KEB02':;

SECTION_NUMBER 1
 '@T6G_MB_LIB.T6G(SCH_1):PAGE186_I26@PURE_QUANTA.Q_CAP(CHIPS)':
 C_PATH='@t6g_mb_lib.t6g(sch_1):page186_i26@pure_quanta.q_cap(chips)',
 P_PATH='@t6g_mb_lib.t6g(sch_1):page211_i26@pure_quanta.q_cap(chips)',
 PATH='I26',
 DRAWING='@T6G_MB_LIB.T6G(SCH_1):PAGE186',
 TOLERANCE='10%',
 MATERIAL='X6S',
 PHYS_PAGE='211',
 XY='(-5150,2575)',
 ROT='0',
 VER='1',
 PACK_TYPE='C0402',
 LOCATION='PC263_2',
 CDS_LIB='pure_quanta',
 CDS_PART_NAME='Q_CAP_C0402-1UF,25V,10%,X6S,CH5104KEB02',
 VOLTAGE='25V',
 PART_NUMBER='CH5104KEB02',
 VALUE='1UF',
 PRIM_FILE='./archive_libs/logical/q_cap/chips/chips.prt';

PART_NAME
 PC264_1 'Q_CAP_C0805-22UF,16V,20%,X6S,CH6223MEA01':;

SECTION_NUMBER 1
 '@T6G_MB_LIB.T6G(SCH_1):PAGE186_I51@PURE_QUANTA.Q_CAP(CHIPS)':
 C_PATH='@t6g_mb_lib.t6g(sch_1):page186_i51@pure_quanta.q_cap(chips)',
 P_PATH='@t6g_mb_lib.t6g(sch_1):page211_i51@pure_quanta.q_cap(chips)',
 PATH='I51',
 DRAWING='@T6G_MB_LIB.T6G(SCH_1):PAGE186',
 TOLERANCE='20%',
 MATERIAL='X6S',
 PHYS_PAGE='211',
 XY='(-4825,5325)',
 ROT='0',
 VER='1',
 PACK_TYPE='C0805',
 LOCATION='PC264_1',
 CDS_LIB='pure_quanta',
 CDS_PART_NAME='Q_CAP_C0805-22UF,16V,20%,X6S,CH6223MEA01',
 VOLTAGE='16V',
 PART_NUMBER='CH6223MEA01',
 VALUE='22UF',
 PRIM_FILE='./archive_libs/logical/q_cap/chips/chips.prt';

PART_NAME
 PC265_2 'Q_CAP_C0805-22UF,16V,20%,X6S,CH6223MEA01':;

SECTION_NUMBER 1
 '@T6G_MB_LIB.T6G(SCH_1):PAGE186_I28@PURE_QUANTA.Q_CAP(CHIPS)':
 C_PATH='@t6g_mb_lib.t6g(sch_1):page186_i28@pure_quanta.q_cap(chips)',
 P_PATH='@t6g_mb_lib.t6g(sch_1):page211_i28@pure_quanta.q_cap(chips)',
 PATH='I28',
 DRAWING='@T6G_MB_LIB.T6G(SCH_1):PAGE186',
 TOLERANCE='20%',
 MATERIAL='X6S',
 PHYS_PAGE='211',
 XY='(-4825,2575)',
 ROT='0',
 VER='1',
 PACK_TYPE='C0805',
 LOCATION='PC265_2',
 CDS_LIB='pure_quanta',
 CDS_PART_NAME='Q_CAP_C0805-22UF,16V,20%,X6S,CH6223MEA01',
 VOLTAGE='16V',
 PART_NUMBER='CH6223MEA01',
 VALUE='22UF',
 PRIM_FILE='./archive_libs/logical/q_cap/chips/chips.prt';

PART_NAME
 PC266_1 'Q_CAP_C0805-22UF,16V,20%,X6S,CH6223MEA01':;

SECTION_NUMBER 1
 '@T6G_MB_LIB.T6G(SCH_1):PAGE186_I52@PURE_QUANTA.Q_CAP(CHIPS)':
 C_PATH='@t6g_mb_lib.t6g(sch_1):page186_i52@pure_quanta.q_cap(chips)',
 P_PATH='@t6g_mb_lib.t6g(sch_1):page211_i52@pure_quanta.q_cap(chips)',
 PATH='I52',
 DRAWING='@T6G_MB_LIB.T6G(SCH_1):PAGE186',
 TOLERANCE='20%',
 MATERIAL='X6S',
 PHYS_PAGE='211',
 XY='(-4500,5325)',
 ROT='0',
 VER='1',
 PACK_TYPE='C0805',
 LOCATION='PC266_1',
 CDS_LIB='pure_quanta',
 CDS_PART_NAME='Q_CAP_C0805-22UF,16V,20%,X6S,CH6223MEA01',
 VOLTAGE='16V',
 PART_NUMBER='CH6223MEA01',
 VALUE='22UF',
 PRIM_FILE='./archive_libs/logical/q_cap/chips/chips.prt';

PART_NAME
 PC267_2 'Q_CAP_C0805-22UF,16V,20%,X6S,CH6223MEA01':;

SECTION_NUMBER 1
 '@T6G_MB_LIB.T6G(SCH_1):PAGE186_I29@PURE_QUANTA.Q_CAP(CHIPS)':
 C_PATH='@t6g_mb_lib.t6g(sch_1):page186_i29@pure_quanta.q_cap(chips)',
 P_PATH='@t6g_mb_lib.t6g(sch_1):page211_i29@pure_quanta.q_cap(chips)',
 PATH='I29',
 DRAWING='@T6G_MB_LIB.T6G(SCH_1):PAGE186',
 TOLERANCE='20%',
 MATERIAL='X6S',
 PHYS_PAGE='211',
 XY='(-4500,2575)',
 ROT='0',
 VER='1',
 PACK_TYPE='C0805',
 LOCATION='PC267_2',
 CDS_LIB='pure_quanta',
 CDS_PART_NAME='Q_CAP_C0805-22UF,16V,20%,X6S,CH6223MEA01',
 VOLTAGE='16V',
 PART_NUMBER='CH6223MEA01',
 VALUE='22UF',
 PRIM_FILE='./archive_libs/logical/q_cap/chips/chips.prt';

PART_NAME
 PC268_1 'Q_CAP_C0805-22UF,16V,20%,X6S,CH6223MEA01':;

SECTION_NUMBER 1
 '@T6G_MB_LIB.T6G(SCH_1):PAGE186_I53@PURE_QUANTA.Q_CAP(CHIPS)':
 C_PATH='@t6g_mb_lib.t6g(sch_1):page186_i53@pure_quanta.q_cap(chips)',
 P_PATH='@t6g_mb_lib.t6g(sch_1):page211_i53@pure_quanta.q_cap(chips)',
 PATH='I53',
 DRAWING='@T6G_MB_LIB.T6G(SCH_1):PAGE186',
 TOLERANCE='20%',
 MATERIAL='X6S',
 PHYS_PAGE='211',
 XY='(-4200,5325)',
 ROT='0',
 VER='1',
 PACK_TYPE='C0805',
 LOCATION='PC268_1',
 CDS_LIB='pure_quanta',
 CDS_PART_NAME='Q_CAP_C0805-22UF,16V,20%,X6S,CH6223MEA01',
 VOLTAGE='16V',
 PART_NUMBER='CH6223MEA01',
 VALUE='22UF',
 PRIM_FILE='./archive_libs/logical/q_cap/chips/chips.prt';

PART_NAME
 PC269_2 'Q_CAP_C0805-22UF,16V,20%,X6S,CH6223MEA01':;

SECTION_NUMBER 1
 '@T6G_MB_LIB.T6G(SCH_1):PAGE186_I31@PURE_QUANTA.Q_CAP(CHIPS)':
 C_PATH='@t6g_mb_lib.t6g(sch_1):page186_i31@pure_quanta.q_cap(chips)',
 P_PATH='@t6g_mb_lib.t6g(sch_1):page211_i31@pure_quanta.q_cap(chips)',
 PATH='I31',
 DRAWING='@T6G_MB_LIB.T6G(SCH_1):PAGE186',
 TOLERANCE='20%',
 MATERIAL='X6S',
 PHYS_PAGE='211',
 XY='(-4200,2575)',
 ROT='0',
 VER='1',
 PACK_TYPE='C0805',
 LOCATION='PC269_2',
 CDS_LIB='pure_quanta',
 CDS_PART_NAME='Q_CAP_C0805-22UF,16V,20%,X6S,CH6223MEA01',
 VOLTAGE='16V',
 PART_NUMBER='CH6223MEA01',
 VALUE='22UF',
 PRIM_FILE='./archive_libs/logical/q_cap/chips/chips.prt';

PART_NAME
 PC270 'Q_CAP_0402-0.22UF,16V,10%,X7R,CH4223K1B00':;

SECTION_NUMBER 1
 '@T6G_MB_LIB.T6G(SCH_1):PAGE186_I89@PURE_QUANTA.Q_CAP(CHIPS)':
 C_PATH='@t6g_mb_lib.t6g(sch_1):page186_i89@pure_quanta.q_cap(chips)',
 P_PATH='@t6g_mb_lib.t6g(sch_1):page211_i89@pure_quanta.q_cap(chips)',
 PATH='I89',
 DRAWING='@T6G_MB_LIB.T6G(SCH_1):PAGE186',
 TOLERANCE='10%',
 MATERIAL='X7R',
 PHYS_PAGE='211',
 XY='(-4050,4675)',
 ROT='0',
 VER='1',
 PACK_TYPE='0402',
 LOCATION='PC270',
 CDS_LIB='pure_quanta',
 CDS_PART_NAME='Q_CAP_0402-0.22UF,16V,10%,X7R,CH4223K1B00',
 VOLTAGE='16V',
 PART_NUMBER='CH4223K1B00',
 VALUE='0.22UF',
 PRIM_FILE='./archive_libs/logical/q_cap/chips/chips.prt';

PART_NAME
 PC271 'Q_CAP_0402-0.22UF,16V,10%,X7R,CH4223K1B00':;

SECTION_NUMBER 1
 '@T6G_MB_LIB.T6G(SCH_1):PAGE186_I55@PURE_QUANTA.Q_CAP(CHIPS)':
 C_PATH='@t6g_mb_lib.t6g(sch_1):page186_i55@pure_quanta.q_cap(chips)',
 P_PATH='@t6g_mb_lib.t6g(sch_1):page211_i55@pure_quanta.q_cap(chips)',
 PATH='I55',
 DRAWING='@T6G_MB_LIB.T6G(SCH_1):PAGE186',
 TOLERANCE='10%',
 MATERIAL='X7R',
 PHYS_PAGE='211',
 XY='(-3675,1925)',
 ROT='0',
 VER='1',
 PACK_TYPE='0402',
 LOCATION='PC271',
 CDS_LIB='pure_quanta',
 CDS_PART_NAME='Q_CAP_0402-0.22UF,16V,10%,X7R,CH4223K1B00',
 VOLTAGE='16V',
 PART_NUMBER='CH4223K1B00',
 VALUE='0.22UF',
 PRIM_FILE='./archive_libs/logical/q_cap/chips/chips.prt';

PART_NAME
 PC272 'Q_CAPP_THLF-270UF,16V,20%,OSCON,CC72703MD38':;

SECTION_NUMBER 1
 '@T6G_MB_LIB.T6G(SCH_1):PAGE186_I70@PURE_QUANTA.Q_CAPP(CHIPS)':
 C_PATH='@t6g_mb_lib.t6g(sch_1):page186_i70@pure_quanta.q_capp(chips)',
 P_PATH='@t6g_mb_lib.t6g(sch_1):page211_i70@pure_quanta.q_capp(chips)',
 PATH='I70',
 DRAWING='@T6G_MB_LIB.T6G(SCH_1):PAGE186',
 TOLERANCE='20%',
 MATERIAL='OSCON',
 PHYS_PAGE='211',
 XY='(-3850,5325)',
 ROT='0',
 VER='1',
 PACK_TYPE='THLF',
 LOCATION='PC272',
 CDS_LIB='pure_quanta',
 CDS_PART_NAME='Q_CAPP_THLF-270UF,16V,20%,OSCON,CC72703MD38',
 VOLTAGE='16V',
 PART_NUMBER='CC72703MD38',
 VALUE='270UF',
 PRIM_FILE='./archive_libs/logical/q_capp/chips/chips.prt';

PART_NAME
 PC273 'Q_CAPP_THLF-270UF,16V,20%,OSCON,CC72703MD38':;

SECTION_NUMBER 1
 '@T6G_MB_LIB.T6G(SCH_1):PAGE186_I71@PURE_QUANTA.Q_CAPP(CHIPS)':
 C_PATH='@t6g_mb_lib.t6g(sch_1):page186_i71@pure_quanta.q_capp(chips)',
 P_PATH='@t6g_mb_lib.t6g(sch_1):page211_i71@pure_quanta.q_capp(chips)',
 PATH='I71',
 DRAWING='@T6G_MB_LIB.T6G(SCH_1):PAGE186',
 TOLERANCE='20%',
 MATERIAL='OSCON',
 PHYS_PAGE='211',
 XY='(-3475,5325)',
 ROT='0',
 VER='1',
 PACK_TYPE='THLF',
 LOCATION='PC273',
 CDS_LIB='pure_quanta',
 CDS_PART_NAME='Q_CAPP_THLF-270UF,16V,20%,OSCON,CC72703MD38',
 VOLTAGE='16V',
 PART_NUMBER='CC72703MD38',
 VALUE='270UF',
 PRIM_FILE='./archive_libs/logical/q_capp/chips/chips.prt';

PART_NAME
 PC275 'Q_CAPP_SMLF-220UF,4V,20%,SPCAP,CH122KM8801':;

SECTION_NUMBER 1
 '@T6G_MB_LIB.T6G(SCH_1):PAGE186_I58@PURE_QUANTA.Q_CAPP(CHIPS)':
 C_PATH='@t6g_mb_lib.t6g(sch_1):page186_i58@pure_quanta.q_capp(chips)',
 P_PATH='@t6g_mb_lib.t6g(sch_1):page211_i58@pure_quanta.q_capp(chips)',
 PATH='I58',
 DRAWING='@T6G_MB_LIB.T6G(SCH_1):PAGE186',
 TOLERANCE='20%',
 MATERIAL='SPCAP',
 PHYS_PAGE='211',
 XY='(-2750,2900)',
 ROT='0',
 VER='1',
 PACK_TYPE='SMLF',
 LOCATION='PC275',
 CDS_LIB='pure_quanta',
 CDS_PART_NAME='Q_CAPP_SMLF-220UF,4V,20%,SPCAP,CH122KM8801',
 VOLTAGE='4V',
 PART_NUMBER='CH122KM8801',
 VALUE='220UF',
 PRIM_FILE='./archive_libs/logical/q_capp/chips/chips.prt';

PART_NAME
 PC276 'Q_CAPP_SMLF-220UF,4V,20%,SPCAP,CH122KM8801':;

SECTION_NUMBER 1
 '@T6G_MB_LIB.T6G(SCH_1):PAGE186_I59@PURE_QUANTA.Q_CAPP(CHIPS)':
 C_PATH='@t6g_mb_lib.t6g(sch_1):page186_i59@pure_quanta.q_capp(chips)',
 P_PATH='@t6g_mb_lib.t6g(sch_1):page211_i59@pure_quanta.q_capp(chips)',
 PATH='I59',
 DRAWING='@T6G_MB_LIB.T6G(SCH_1):PAGE186',
 TOLERANCE='20%',
 MATERIAL='SPCAP',
 PHYS_PAGE='211',
 XY='(-2425,2900)',
 ROT='0',
 VER='1',
 PACK_TYPE='SMLF',
 LOCATION='PC276',
 CDS_LIB='pure_quanta',
 CDS_PART_NAME='Q_CAPP_SMLF-220UF,4V,20%,SPCAP,CH122KM8801',
 VOLTAGE='4V',
 PART_NUMBER='CH122KM8801',
 VALUE='220UF',
 PRIM_FILE='./archive_libs/logical/q_capp/chips/chips.prt';

PART_NAME
 PC277 'Q_CAPP_SMLF-220UF,4V,20%,SPCAP,CH122KM8801':;

SECTION_NUMBER 1
 '@T6G_MB_LIB.T6G(SCH_1):PAGE186_I60@PURE_QUANTA.Q_CAPP(CHIPS)':
 C_PATH='@t6g_mb_lib.t6g(sch_1):page186_i60@pure_quanta.q_capp(chips)',
 P_PATH='@t6g_mb_lib.t6g(sch_1):page211_i60@pure_quanta.q_capp(chips)',
 PATH='I60',
 DRAWING='@T6G_MB_LIB.T6G(SCH_1):PAGE186',
 TOLERANCE='20%',
 MATERIAL='SPCAP',
 PHYS_PAGE='211',
 XY='(-2100,2900)',
 ROT='0',
 VER='1',
 PACK_TYPE='SMLF',
 LOCATION='PC277',
 CDS_LIB='pure_quanta',
 CDS_PART_NAME='Q_CAPP_SMLF-220UF,4V,20%,SPCAP,CH122KM8801',
 VOLTAGE='4V',
 PART_NUMBER='CH122KM8801',
 VALUE='220UF',
 PRIM_FILE='./archive_libs/logical/q_capp/chips/chips.prt';

PART_NAME
 PC278 'Q_CAP_0402-0.1UF,25V,10%,X7R,CH4104K1B00':;

SECTION_NUMBER 1
 '@T6G_MB_LIB.T6G(SCH_1):PAGE186_I85@PURE_QUANTA.Q_CAP(CHIPS)':
 C_PATH='@t6g_mb_lib.t6g(sch_1):page186_i85@pure_quanta.q_cap(chips)',
 P_PATH='@t6g_mb_lib.t6g(sch_1):page211_i85@pure_quanta.q_cap(chips)',
 PATH='I85',
 DRAWING='@T6G_MB_LIB.T6G(SCH_1):PAGE186',
 TOLERANCE='10%',
 MATERIAL='X7R',
 PHYS_PAGE='211',
 XY='(-2025,4275)',
 ROT='0',
 VER='1',
 PACK_TYPE='0402',
 LOCATION='PC278',
 CDS_LIB='pure_quanta',
 CDS_PART_NAME='Q_CAP_0402-0.1UF,25V,10%,X7R,CH4104K1B00',
 VOLTAGE='25V',
 PART_NUMBER='CH4104K1B00',
 VALUE='0.1UF',
 PRIM_FILE='./archive_libs/logical/q_cap/chips/chips.prt';

PART_NAME
 PC279 'Q_CAPP_SMLF-220UF,4V,20%,SPCAP,CH122KM8801':;

SECTION_NUMBER 1
 '@T6G_MB_LIB.T6G(SCH_1):PAGE186_I66@PURE_QUANTA.Q_CAPP(CHIPS)':
 C_PATH='@t6g_mb_lib.t6g(sch_1):page186_i66@pure_quanta.q_capp(chips)',
 P_PATH='@t6g_mb_lib.t6g(sch_1):page211_i66@pure_quanta.q_capp(chips)',
 PATH='I66',
 DRAWING='@T6G_MB_LIB.T6G(SCH_1):PAGE186',
 TOLERANCE='20%',
 MATERIAL='SPCAP',
 PHYS_PAGE='211',
 XY='(-1800,2900)',
 ROT='0',
 VER='1',
 PACK_TYPE='SMLF',
 LOCATION='PC279',
 CDS_LIB='pure_quanta',
 CDS_PART_NAME='Q_CAPP_SMLF-220UF,4V,20%,SPCAP,CH122KM8801',
 VOLTAGE='4V',
 PART_NUMBER='CH122KM8801',
 VALUE='220UF',
 PRIM_FILE='./archive_libs/logical/q_capp/chips/chips.prt';

PART_NAME
 PC280_2 'Q_CAP_C0805-22UF,4V,20%,X6S,CH622KMEA03':;

SECTION_NUMBER 1
 '@T6G_MB_LIB.T6G(SCH_1):PAGE186_I61@PURE_QUANTA.Q_CAP(CHIPS)':
 C_PATH='@t6g_mb_lib.t6g(sch_1):page186_i61@pure_quanta.q_cap(chips)',
 P_PATH='@t6g_mb_lib.t6g(sch_1):page211_i61@pure_quanta.q_cap(chips)',
 PATH='I61',
 DRAWING='@T6G_MB_LIB.T6G(SCH_1):PAGE186',
 TOLERANCE='20%',
 MATERIAL='X6S',
 PHYS_PAGE='211',
 XY='(-1700,1525)',
 ROT='0',
 VER='1',
 PACK_TYPE='C0805',
 LOCATION='PC280_2',
 CDS_LIB='pure_quanta',
 CDS_PART_NAME='Q_CAP_C0805-22UF,4V,20%,X6S,CH622KMEA03',
 VOLTAGE='4V',
 PART_NUMBER='CH622KMEA03',
 VALUE='22UF',
 PRIM_FILE='./archive_libs/logical/q_cap/chips/chips.prt';

PART_NAME
 PC281_1 'Q_CAP_C0805-22UF,4V,20%,X6S,CH622KMEA03':;

SECTION_NUMBER 1
 '@T6G_MB_LIB.T6G(SCH_1):PAGE186_I76@PURE_QUANTA.Q_CAP(CHIPS)':
 C_PATH='@t6g_mb_lib.t6g(sch_1):page186_i76@pure_quanta.q_cap(chips)',
 P_PATH='@t6g_mb_lib.t6g(sch_1):page211_i76@pure_quanta.q_cap(chips)',
 PATH='I76',
 DRAWING='@T6G_MB_LIB.T6G(SCH_1):PAGE186',
 TOLERANCE='20%',
 MATERIAL='X6S',
 PHYS_PAGE='211',
 XY='(-1650,4275)',
 ROT='0',
 VER='1',
 PACK_TYPE='C0805',
 LOCATION='PC281_1',
 CDS_LIB='pure_quanta',
 CDS_PART_NAME='Q_CAP_C0805-22UF,4V,20%,X6S,CH622KMEA03',
 VOLTAGE='4V',
 PART_NUMBER='CH622KMEA03',
 VALUE='22UF',
 PRIM_FILE='./archive_libs/logical/q_cap/chips/chips.prt';

PART_NAME
 PC282_2 'Q_CAP_C0805-22UF,4V,20%,X6S,CH622KMEA03':;

SECTION_NUMBER 1
 '@T6G_MB_LIB.T6G(SCH_1):PAGE186_I63@PURE_QUANTA.Q_CAP(CHIPS)':
 C_PATH='@t6g_mb_lib.t6g(sch_1):page186_i63@pure_quanta.q_cap(chips)',
 P_PATH='@t6g_mb_lib.t6g(sch_1):page211_i63@pure_quanta.q_cap(chips)',
 PATH='I63',
 DRAWING='@T6G_MB_LIB.T6G(SCH_1):PAGE186',
 TOLERANCE='20%',
 MATERIAL='X6S',
 PHYS_PAGE='211',
 XY='(-1275,1525)',
 ROT='0',
 VER='1',
 PACK_TYPE='C0805',
 LOCATION='PC282_2',
 CDS_LIB='pure_quanta',
 CDS_PART_NAME='Q_CAP_C0805-22UF,4V,20%,X6S,CH622KMEA03',
 VOLTAGE='4V',
 PART_NUMBER='CH622KMEA03',
 VALUE='22UF',
 PRIM_FILE='./archive_libs/logical/q_cap/chips/chips.prt';

PART_NAME
 PC283_1 'Q_CAP_C0805-22UF,4V,20%,X6S,CH622KMEA03':;

SECTION_NUMBER 1
 '@T6G_MB_LIB.T6G(SCH_1):PAGE186_I77@PURE_QUANTA.Q_CAP(CHIPS)':
 C_PATH='@t6g_mb_lib.t6g(sch_1):page186_i77@pure_quanta.q_cap(chips)',
 P_PATH='@t6g_mb_lib.t6g(sch_1):page211_i77@pure_quanta.q_cap(chips)',
 PATH='I77',
 DRAWING='@T6G_MB_LIB.T6G(SCH_1):PAGE186',
 TOLERANCE='20%',
 MATERIAL='X6S',
 PHYS_PAGE='211',
 XY='(-1225,4275)',
 ROT='0',
 VER='1',
 PACK_TYPE='C0805',
 LOCATION='PC283_1',
 CDS_LIB='pure_quanta',
 CDS_PART_NAME='Q_CAP_C0805-22UF,4V,20%,X6S,CH622KMEA03',
 VOLTAGE='4V',
 PART_NUMBER='CH622KMEA03',
 VALUE='22UF',
 PRIM_FILE='./archive_libs/logical/q_cap/chips/chips.prt';

PART_NAME
 PC284_3 'Q_CAP_0402-0.1UF,25V,10%,X7R,CH4104K1B00':;

SECTION_NUMBER 1
 '@T6G_MB_LIB.T6G(SCH_1):PAGE187_I28@PURE_QUANTA.Q_CAP(CHIPS)':
 C_PATH='@t6g_mb_lib.t6g(sch_1):page187_i28@pure_quanta.q_cap(chips)',
 P_PATH='@t6g_mb_lib.t6g(sch_1):page212_i28@pure_quanta.q_cap(chips)',
 PATH='I28',
 DRAWING='@T6G_MB_LIB.T6G(SCH_1):PAGE187',
 TOLERANCE='10%',
 MATERIAL='X7R',
 PHYS_PAGE='212',
 XY='(-7575,4600)',
 ROT='0',
 VER='1',
 PACK_TYPE='0402',
 LOCATION='PC284_3',
 CDS_LIB='pure_quanta',
 CDS_PART_NAME='Q_CAP_0402-0.1UF,25V,10%,X7R,CH4104K1B00',
 VOLTAGE='25V',
 PART_NUMBER='CH4104K1B00',
 VALUE='0.1UF',
 PRIM_FILE='./archive_libs/logical/q_cap/chips/chips.prt';

PART_NAME
 PC285 'Q_CAP_C0805-22UF,4V,20%,X6S,CH622KMEA03':;

SECTION_NUMBER 1
 '@T6G_MB_LIB.T6G(SCH_1):PAGE184_I54@PURE_QUANTA.Q_CAP(CHIPS)':
 C_PATH='@t6g_mb_lib.t6g(sch_1):page184_i54@pure_quanta.q_cap(chips)',
 P_PATH='@t6g_mb_lib.t6g(sch_1):page209_i54@pure_quanta.q_cap(chips)',
 PATH='I54',
 DRAWING='@T6G_MB_LIB.T6G(SCH_1):PAGE184',
 TOLERANCE='20%',
 MATERIAL='X6S',
 PHYS_PAGE='209',
 XY='(-2475,3325)',
 ROT='0',
 VER='1',
 PACK_TYPE='C0805',
 LOCATION='PC285',
 CDS_LIB='pure_quanta',
 CDS_PART_NAME='Q_CAP_C0805-22UF,4V,20%,X6S,CH622KMEA03',
 VOLTAGE='4V',
 PART_NUMBER='CH622KMEA03',
 VALUE='22UF',
 PRIM_FILE='./archive_libs/logical/q_cap/chips/chips.prt';

PART_NAME
 PC285_4 'Q_CAP_0402-0.1UF,25V,10%,X7R,CH4104K1B00':;

SECTION_NUMBER 1
 '@T6G_MB_LIB.T6G(SCH_1):PAGE187_I2@PURE_QUANTA.Q_CAP(CHIPS)':
 C_PATH='@t6g_mb_lib.t6g(sch_1):page187_i2@pure_quanta.q_cap(chips)',
 P_PATH='@t6g_mb_lib.t6g(sch_1):page212_i2@pure_quanta.q_cap(chips)',
 PATH='I2',
 DRAWING='@T6G_MB_LIB.T6G(SCH_1):PAGE187',
 TOLERANCE='10%',
 MATERIAL='X7R',
 PHYS_PAGE='212',
 XY='(-7500,1300)',
 ROT='0',
 VER='1',
 PACK_TYPE='0402',
 LOCATION='PC285_4',
 CDS_LIB='pure_quanta',
 CDS_PART_NAME='Q_CAP_0402-0.1UF,25V,10%,X7R,CH4104K1B00',
 VOLTAGE='25V',
 PART_NUMBER='CH4104K1B00',
 VALUE='0.1UF',
 PRIM_FILE='./archive_libs/logical/q_cap/chips/chips.prt';

PART_NAME
 PC286 'Q_CAP_C0402-2.2UF,10V,10%,X6S,CH5222KEB01':;

SECTION_NUMBER 1
 '@T6G_MB_LIB.T6G(SCH_1):PAGE187_I37@PURE_QUANTA.Q_CAP(CHIPS)':
 C_PATH='@t6g_mb_lib.t6g(sch_1):page187_i37@pure_quanta.q_cap(chips)',
 P_PATH='@t6g_mb_lib.t6g(sch_1):page212_i37@pure_quanta.q_cap(chips)',
 PATH='I37',
 DRAWING='@T6G_MB_LIB.T6G(SCH_1):PAGE187',
 TOLERANCE='10%',
 MATERIAL='X6S',
 PHYS_PAGE='212',
 XY='(-7250,5225)',
 ROT='0',
 VER='1',
 PACK_TYPE='C0402',
 LOCATION='PC286',
 CDS_LIB='pure_quanta',
 CDS_PART_NAME='Q_CAP_C0402-2.2UF,10V,10%,X6S,CH5222KEB01',
 VOLTAGE='10V',
 PART_NUMBER='CH5222KEB01',
 VALUE='2.2UF',
 PRIM_FILE='./archive_libs/logical/q_cap/chips/chips.prt';

PART_NAME
 PC287 'Q_CAP_C0402-2.2UF,10V,10%,X6S,CH5222KEB01':;

SECTION_NUMBER 1
 '@T6G_MB_LIB.T6G(SCH_1):PAGE187_I6@PURE_QUANTA.Q_CAP(CHIPS)':
 C_PATH='@t6g_mb_lib.t6g(sch_1):page187_i6@pure_quanta.q_cap(chips)',
 P_PATH='@t6g_mb_lib.t6g(sch_1):page212_i6@pure_quanta.q_cap(chips)',
 PATH='I6',
 DRAWING='@T6G_MB_LIB.T6G(SCH_1):PAGE187',
 TOLERANCE='10%',
 MATERIAL='X6S',
 PHYS_PAGE='212',
 XY='(-7150,1925)',
 ROT='0',
 VER='1',
 PACK_TYPE='C0402',
 LOCATION='PC287',
 CDS_LIB='pure_quanta',
 CDS_PART_NAME='Q_CAP_C0402-2.2UF,10V,10%,X6S,CH5222KEB01',
 VOLTAGE='10V',
 PART_NUMBER='CH5222KEB01',
 VALUE='2.2UF',
 PRIM_FILE='./archive_libs/logical/q_cap/chips/chips.prt';

PART_NAME
 PC288 'Q_CAP_C0805-22UF,4V,20%,X6S,CH622KMEA03':;

SECTION_NUMBER 1
 '@T6G_MB_LIB.T6G(SCH_1):PAGE184_I40@PURE_QUANTA.Q_CAP(CHIPS)':
 C_PATH='@t6g_mb_lib.t6g(sch_1):page184_i40@pure_quanta.q_cap(chips)',
 P_PATH='@t6g_mb_lib.t6g(sch_1):page209_i40@pure_quanta.q_cap(chips)',
 PATH='I40',
 DRAWING='@T6G_MB_LIB.T6G(SCH_1):PAGE184',
 TOLERANCE='20%',
 MATERIAL='X6S',
 PHYS_PAGE='209',
 XY='(-2275,3325)',
 ROT='0',
 VER='1',
 PACK_TYPE='C0805',
 LOCATION='PC288',
 CDS_LIB='pure_quanta',
 CDS_PART_NAME='Q_CAP_C0805-22UF,4V,20%,X6S,CH622KMEA03',
 VOLTAGE='4V',
 PART_NUMBER='CH622KMEA03',
 VALUE='22UF',
 PRIM_FILE='./archive_libs/logical/q_cap/chips/chips.prt';

PART_NAME
 PC288_C0P1_3 'Q_CAP_C0402-2.2UF,10V,10%,X6S,CH5222KEB01':;

SECTION_NUMBER 1
 '@T6G_MB_LIB.T6G(SCH_1):PAGE187_I41@PURE_QUANTA.Q_CAP(CHIPS)':
 C_PATH='@t6g_mb_lib.t6g(sch_1):page187_i41@pure_quanta.q_cap(chips)',
 P_PATH='@t6g_mb_lib.t6g(sch_1):page212_i41@pure_quanta.q_cap(chips)',
 PATH='I41',
 DRAWING='@T6G_MB_LIB.T6G(SCH_1):PAGE187',
 TOLERANCE='10%',
 MATERIAL='X6S',
 PHYS_PAGE='212',
 XY='(-6900,5800)',
 ROT='0',
 VER='1',
 PACK_TYPE='C0402',
 LOCATION='PC288_C0P1_3',
 CDS_LIB='pure_quanta',
 CDS_PART_NAME='Q_CAP_C0402-2.2UF,10V,10%,X6S,CH5222KEB01',
 VOLTAGE='10V',
 PART_NUMBER='CH5222KEB01',
 VALUE='2.2UF',
 PRIM_FILE='./archive_libs/logical/q_cap/chips/chips.prt';

PART_NAME
 PC289_C0P1_4 'Q_CAP_C0402-2.2UF,10V,10%,X6S,CH5222KEB01':;

SECTION_NUMBER 1
 '@T6G_MB_LIB.T6G(SCH_1):PAGE187_I15@PURE_QUANTA.Q_CAP(CHIPS)':
 C_PATH='@t6g_mb_lib.t6g(sch_1):page187_i15@pure_quanta.q_cap(chips)',
 P_PATH='@t6g_mb_lib.t6g(sch_1):page212_i15@pure_quanta.q_cap(chips)',
 PATH='I15',
 DRAWING='@T6G_MB_LIB.T6G(SCH_1):PAGE187',
 TOLERANCE='10%',
 MATERIAL='X6S',
 PHYS_PAGE='212',
 XY='(-6800,2500)',
 ROT='0',
 VER='1',
 PACK_TYPE='C0402',
 LOCATION='PC289_C0P1_4',
 CDS_LIB='pure_quanta',
 CDS_PART_NAME='Q_CAP_C0402-2.2UF,10V,10%,X6S,CH5222KEB01',
 VOLTAGE='10V',
 PART_NUMBER='CH5222KEB01',
 VALUE='2.2UF',
 PRIM_FILE='./archive_libs/logical/q_cap/chips/chips.prt';

PART_NAME
 PC290_3 'Q_CAP_0402-0.1UF,25V,10%,X7R,CH4104K1B00':;

SECTION_NUMBER 1
 '@T6G_MB_LIB.T6G(SCH_1):PAGE187_I44@PURE_QUANTA.Q_CAP(CHIPS)':
 C_PATH='@t6g_mb_lib.t6g(sch_1):page187_i44@pure_quanta.q_cap(chips)',
 P_PATH='@t6g_mb_lib.t6g(sch_1):page212_i44@pure_quanta.q_cap(chips)',
 PATH='I44',
 DRAWING='@T6G_MB_LIB.T6G(SCH_1):PAGE187',
 TOLERANCE='10%',
 MATERIAL='X7R',
 PHYS_PAGE='212',
 XY='(-5125,5775)',
 ROT='0',
 VER='1',
 PACK_TYPE='0402',
 LOCATION='PC290_3',
 CDS_LIB='pure_quanta',
 CDS_PART_NAME='Q_CAP_0402-0.1UF,25V,10%,X7R,CH4104K1B00',
 VOLTAGE='25V',
 PART_NUMBER='CH4104K1B00',
 VALUE='0.1UF',
 PRIM_FILE='./archive_libs/logical/q_cap/chips/chips.prt';

PART_NAME
 PC291_4 'Q_CAP_C0402-1UF,25V,10%,X6S,CH5104KEB02':;

SECTION_NUMBER 1
 '@T6G_MB_LIB.T6G(SCH_1):PAGE187_I23@PURE_QUANTA.Q_CAP(CHIPS)':
 C_PATH='@t6g_mb_lib.t6g(sch_1):page187_i23@pure_quanta.q_cap(chips)',
 P_PATH='@t6g_mb_lib.t6g(sch_1):page212_i23@pure_quanta.q_cap(chips)',
 PATH='I23',
 DRAWING='@T6G_MB_LIB.T6G(SCH_1):PAGE187',
 TOLERANCE='10%',
 MATERIAL='X6S',
 PHYS_PAGE='212',
 XY='(-4625,2475)',
 ROT='0',
 VER='1',
 PACK_TYPE='C0402',
 LOCATION='PC291_4',
 CDS_LIB='pure_quanta',
 CDS_PART_NAME='Q_CAP_C0402-1UF,25V,10%,X6S,CH5104KEB02',
 VOLTAGE='25V',
 PART_NUMBER='CH5104KEB02',
 VALUE='1UF',
 PRIM_FILE='./archive_libs/logical/q_cap/chips/chips.prt';

PART_NAME
 PC292_3 'Q_CAP_C0402-1UF,25V,10%,X6S,CH5104KEB02':;

SECTION_NUMBER 1
 '@T6G_MB_LIB.T6G(SCH_1):PAGE187_I48@PURE_QUANTA.Q_CAP(CHIPS)':
 C_PATH='@t6g_mb_lib.t6g(sch_1):page187_i48@pure_quanta.q_cap(chips)',
 P_PATH='@t6g_mb_lib.t6g(sch_1):page212_i48@pure_quanta.q_cap(chips)',
 PATH='I48',
 DRAWING='@T6G_MB_LIB.T6G(SCH_1):PAGE187',
 TOLERANCE='10%',
 MATERIAL='X6S',
 PHYS_PAGE='212',
 XY='(-4775,5775)',
 ROT='0',
 VER='1',
 PACK_TYPE='C0402',
 LOCATION='PC292_3',
 CDS_LIB='pure_quanta',
 CDS_PART_NAME='Q_CAP_C0402-1UF,25V,10%,X6S,CH5104KEB02',
 VOLTAGE='25V',
 PART_NUMBER='CH5104KEB02',
 VALUE='1UF',
 PRIM_FILE='./archive_libs/logical/q_cap/chips/chips.prt';

PART_NAME
 PC293_4 'Q_CAP_0402-0.1UF,25V,10%,X7R,CH4104K1B00':;

SECTION_NUMBER 1
 '@T6G_MB_LIB.T6G(SCH_1):PAGE187_I22@PURE_QUANTA.Q_CAP(CHIPS)':
 C_PATH='@t6g_mb_lib.t6g(sch_1):page187_i22@pure_quanta.q_cap(chips)',
 P_PATH='@t6g_mb_lib.t6g(sch_1):page212_i22@pure_quanta.q_cap(chips)',
 PATH='I22',
 DRAWING='@T6G_MB_LIB.T6G(SCH_1):PAGE187',
 TOLERANCE='10%',
 MATERIAL='X7R',
 PHYS_PAGE='212',
 XY='(-5000,2475)',
 ROT='0',
 VER='1',
 PACK_TYPE='0402',
 LOCATION='PC293_4',
 CDS_LIB='pure_quanta',
 CDS_PART_NAME='Q_CAP_0402-0.1UF,25V,10%,X7R,CH4104K1B00',
 VOLTAGE='25V',
 PART_NUMBER='CH4104K1B00',
 VALUE='0.1UF',
 PRIM_FILE='./archive_libs/logical/q_cap/chips/chips.prt';

PART_NAME
 PC294_3 'Q_CAP_C0805-22UF,16V,20%,X6S,CH6223MEA01':;

SECTION_NUMBER 1
 '@T6G_MB_LIB.T6G(SCH_1):PAGE187_I49@PURE_QUANTA.Q_CAP(CHIPS)':
 C_PATH='@t6g_mb_lib.t6g(sch_1):page187_i49@pure_quanta.q_cap(chips)',
 P_PATH='@t6g_mb_lib.t6g(sch_1):page212_i49@pure_quanta.q_cap(chips)',
 PATH='I49',
 DRAWING='@T6G_MB_LIB.T6G(SCH_1):PAGE187',
 TOLERANCE='20%',
 MATERIAL='X6S',
 PHYS_PAGE='212',
 XY='(-4450,5775)',
 ROT='0',
 VER='1',
 PACK_TYPE='C0805',
 LOCATION='PC294_3',
 CDS_LIB='pure_quanta',
 CDS_PART_NAME='Q_CAP_C0805-22UF,16V,20%,X6S,CH6223MEA01',
 VOLTAGE='16V',
 PART_NUMBER='CH6223MEA01',
 VALUE='22UF',
 PRIM_FILE='./archive_libs/logical/q_cap/chips/chips.prt';

PART_NAME
 PC295_4 'Q_CAP_C0805-22UF,16V,20%,X6S,CH6223MEA01':;

SECTION_NUMBER 1
 '@T6G_MB_LIB.T6G(SCH_1):PAGE187_I24@PURE_QUANTA.Q_CAP(CHIPS)':
 C_PATH='@t6g_mb_lib.t6g(sch_1):page187_i24@pure_quanta.q_cap(chips)',
 P_PATH='@t6g_mb_lib.t6g(sch_1):page212_i24@pure_quanta.q_cap(chips)',
 PATH='I24',
 DRAWING='@T6G_MB_LIB.T6G(SCH_1):PAGE187',
 TOLERANCE='20%',
 MATERIAL='X6S',
 PHYS_PAGE='212',
 XY='(-4300,2475)',
 ROT='0',
 VER='1',
 PACK_TYPE='C0805',
 LOCATION='PC295_4',
 CDS_LIB='pure_quanta',
 CDS_PART_NAME='Q_CAP_C0805-22UF,16V,20%,X6S,CH6223MEA01',
 VOLTAGE='16V',
 PART_NUMBER='CH6223MEA01',
 VALUE='22UF',
 PRIM_FILE='./archive_libs/logical/q_cap/chips/chips.prt';

PART_NAME
 PC296_3 'Q_CAP_C0805-22UF,16V,20%,X6S,CH6223MEA01':;

SECTION_NUMBER 1
 '@T6G_MB_LIB.T6G(SCH_1):PAGE187_I50@PURE_QUANTA.Q_CAP(CHIPS)':
 C_PATH='@t6g_mb_lib.t6g(sch_1):page187_i50@pure_quanta.q_cap(chips)',
 P_PATH='@t6g_mb_lib.t6g(sch_1):page212_i50@pure_quanta.q_cap(chips)',
 PATH='I50',
 DRAWING='@T6G_MB_LIB.T6G(SCH_1):PAGE187',
 TOLERANCE='20%',
 MATERIAL='X6S',
 PHYS_PAGE='212',
 XY='(-4125,5775)',
 ROT='0',
 VER='1',
 PACK_TYPE='C0805',
 LOCATION='PC296_3',
 CDS_LIB='pure_quanta',
 CDS_PART_NAME='Q_CAP_C0805-22UF,16V,20%,X6S,CH6223MEA01',
 VOLTAGE='16V',
 PART_NUMBER='CH6223MEA01',
 VALUE='22UF',
 PRIM_FILE='./archive_libs/logical/q_cap/chips/chips.prt';

PART_NAME
 PC297_4 'Q_CAP_C0805-22UF,16V,20%,X6S,CH6223MEA01':;

SECTION_NUMBER 1
 '@T6G_MB_LIB.T6G(SCH_1):PAGE187_I25@PURE_QUANTA.Q_CAP(CHIPS)':
 C_PATH='@t6g_mb_lib.t6g(sch_1):page187_i25@pure_quanta.q_cap(chips)',
 P_PATH='@t6g_mb_lib.t6g(sch_1):page212_i25@pure_quanta.q_cap(chips)',
 PATH='I25',
 DRAWING='@T6G_MB_LIB.T6G(SCH_1):PAGE187',
 TOLERANCE='20%',
 MATERIAL='X6S',
 PHYS_PAGE='212',
 XY='(-3975,2475)',
 ROT='0',
 VER='1',
 PACK_TYPE='C0805',
 LOCATION='PC297_4',
 CDS_LIB='pure_quanta',
 CDS_PART_NAME='Q_CAP_C0805-22UF,16V,20%,X6S,CH6223MEA01',
 VOLTAGE='16V',
 PART_NUMBER='CH6223MEA01',
 VALUE='22UF',
 PRIM_FILE='./archive_libs/logical/q_cap/chips/chips.prt';

PART_NAME
 PC298_3 'Q_CAP_C0805-22UF,16V,20%,X6S,CH6223MEA01':;

SECTION_NUMBER 1
 '@T6G_MB_LIB.T6G(SCH_1):PAGE187_I65@PURE_QUANTA.Q_CAP(CHIPS)':
 C_PATH='@t6g_mb_lib.t6g(sch_1):page187_i65@pure_quanta.q_cap(chips)',
 P_PATH='@t6g_mb_lib.t6g(sch_1):page212_i65@pure_quanta.q_cap(chips)',
 PATH='I65',
 DRAWING='@T6G_MB_LIB.T6G(SCH_1):PAGE187',
 TOLERANCE='20%',
 MATERIAL='X6S',
 PHYS_PAGE='212',
 XY='(-3825,5775)',
 ROT='0',
 VER='1',
 PACK_TYPE='C0805',
 LOCATION='PC298_3',
 CDS_LIB='pure_quanta',
 CDS_PART_NAME='Q_CAP_C0805-22UF,16V,20%,X6S,CH6223MEA01',
 VOLTAGE='16V',
 PART_NUMBER='CH6223MEA01',
 VALUE='22UF',
 PRIM_FILE='./archive_libs/logical/q_cap/chips/chips.prt';

PART_NAME
 PC299_4 'Q_CAP_C0805-22UF,16V,20%,X6S,CH6223MEA01':;

SECTION_NUMBER 1
 '@T6G_MB_LIB.T6G(SCH_1):PAGE187_I55@PURE_QUANTA.Q_CAP(CHIPS)':
 C_PATH='@t6g_mb_lib.t6g(sch_1):page187_i55@pure_quanta.q_cap(chips)',
 P_PATH='@t6g_mb_lib.t6g(sch_1):page212_i55@pure_quanta.q_cap(chips)',
 PATH='I55',
 DRAWING='@T6G_MB_LIB.T6G(SCH_1):PAGE187',
 TOLERANCE='20%',
 MATERIAL='X6S',
 PHYS_PAGE='212',
 XY='(-3675,2475)',
 ROT='0',
 VER='1',
 PACK_TYPE='C0805',
 LOCATION='PC299_4',
 CDS_LIB='pure_quanta',
 CDS_PART_NAME='Q_CAP_C0805-22UF,16V,20%,X6S,CH6223MEA01',
 VOLTAGE='16V',
 PART_NUMBER='CH6223MEA01',
 VALUE='22UF',
 PRIM_FILE='./archive_libs/logical/q_cap/chips/chips.prt';

PART_NAME
 PC300 'Q_CAP_0402-0.22UF,16V,10%,X7R,CH4223K1B00':;

SECTION_NUMBER 1
 '@T6G_MB_LIB.T6G(SCH_1):PAGE187_I63@PURE_QUANTA.Q_CAP(CHIPS)':
 C_PATH='@t6g_mb_lib.t6g(sch_1):page187_i63@pure_quanta.q_cap(chips)',
 P_PATH='@t6g_mb_lib.t6g(sch_1):page212_i63@pure_quanta.q_cap(chips)',
 PATH='I63',
 DRAWING='@T6G_MB_LIB.T6G(SCH_1):PAGE187',
 TOLERANCE='10%',
 MATERIAL='X7R',
 PHYS_PAGE='212',
 XY='(-3400,5100)',
 ROT='0',
 VER='1',
 PACK_TYPE='0402',
 LOCATION='PC300',
 CDS_LIB='pure_quanta',
 CDS_PART_NAME='Q_CAP_0402-0.22UF,16V,10%,X7R,CH4223K1B00',
 VOLTAGE='16V',
 PART_NUMBER='CH4223K1B00',
 VALUE='0.22UF',
 PRIM_FILE='./archive_libs/logical/q_cap/chips/chips.prt';

PART_NAME
 PC301 'Q_CAP_0402-0.22UF,16V,10%,X7R,CH4223K1B00':;

SECTION_NUMBER 1
 '@T6G_MB_LIB.T6G(SCH_1):PAGE187_I52@PURE_QUANTA.Q_CAP(CHIPS)':
 C_PATH='@t6g_mb_lib.t6g(sch_1):page187_i52@pure_quanta.q_cap(chips)',
 P_PATH='@t6g_mb_lib.t6g(sch_1):page212_i52@pure_quanta.q_cap(chips)',
 PATH='I52',
 DRAWING='@T6G_MB_LIB.T6G(SCH_1):PAGE187',
 TOLERANCE='10%',
 MATERIAL='X7R',
 PHYS_PAGE='212',
 XY='(-3325,1800)',
 ROT='0',
 VER='1',
 PACK_TYPE='0402',
 LOCATION='PC301',
 CDS_LIB='pure_quanta',
 CDS_PART_NAME='Q_CAP_0402-0.22UF,16V,10%,X7R,CH4223K1B00',
 VOLTAGE='16V',
 PART_NUMBER='CH4223K1B00',
 VALUE='0.22UF',
 PRIM_FILE='./archive_libs/logical/q_cap/chips/chips.prt';

PART_NAME
 PC302_3 'Q_CAP_C0805-22UF,4V,20%,X6S,CH622KMEA03':;

SECTION_NUMBER 1
 '@T6G_MB_LIB.T6G(SCH_1):PAGE187_I69@PURE_QUANTA.Q_CAP(CHIPS)':
 C_PATH='@t6g_mb_lib.t6g(sch_1):page187_i69@pure_quanta.q_cap(chips)',
 P_PATH='@t6g_mb_lib.t6g(sch_1):page212_i69@pure_quanta.q_cap(chips)',
 PATH='I69',
 DRAWING='@T6G_MB_LIB.T6G(SCH_1):PAGE187',
 TOLERANCE='20%',
 MATERIAL='X6S',
 PHYS_PAGE='212',
 XY='(-1050,4700)',
 ROT='0',
 VER='1',
 PACK_TYPE='C0805',
 LOCATION='PC302_3',
 CDS_LIB='pure_quanta',
 CDS_PART_NAME='Q_CAP_C0805-22UF,4V,20%,X6S,CH622KMEA03',
 VOLTAGE='4V',
 PART_NUMBER='CH622KMEA03',
 VALUE='22UF',
 PRIM_FILE='./archive_libs/logical/q_cap/chips/chips.prt';

PART_NAME
 PC303_4 'Q_CAP_C0805-22UF,4V,20%,X6S,CH622KMEA03':;

SECTION_NUMBER 1
 '@T6G_MB_LIB.T6G(SCH_1):PAGE187_I58@PURE_QUANTA.Q_CAP(CHIPS)':
 C_PATH='@t6g_mb_lib.t6g(sch_1):page187_i58@pure_quanta.q_cap(chips)',
 P_PATH='@t6g_mb_lib.t6g(sch_1):page212_i58@pure_quanta.q_cap(chips)',
 PATH='I58',
 DRAWING='@T6G_MB_LIB.T6G(SCH_1):PAGE187',
 TOLERANCE='20%',
 MATERIAL='X6S',
 PHYS_PAGE='212',
 XY='(-1000,1400)',
 ROT='0',
 VER='1',
 PACK_TYPE='C0805',
 LOCATION='PC303_4',
 CDS_LIB='pure_quanta',
 CDS_PART_NAME='Q_CAP_C0805-22UF,4V,20%,X6S,CH622KMEA03',
 VOLTAGE='4V',
 PART_NUMBER='CH622KMEA03',
 VALUE='22UF',
 PRIM_FILE='./archive_libs/logical/q_cap/chips/chips.prt';

PART_NAME
 PC304_3 'Q_CAP_C0805-22UF,4V,20%,X6S,CH622KMEA03':;

SECTION_NUMBER 1
 '@T6G_MB_LIB.T6G(SCH_1):PAGE187_I71@PURE_QUANTA.Q_CAP(CHIPS)':
 C_PATH='@t6g_mb_lib.t6g(sch_1):page187_i71@pure_quanta.q_cap(chips)',
 P_PATH='@t6g_mb_lib.t6g(sch_1):page212_i71@pure_quanta.q_cap(chips)',
 PATH='I71',
 DRAWING='@T6G_MB_LIB.T6G(SCH_1):PAGE187',
 TOLERANCE='20%',
 MATERIAL='X6S',
 PHYS_PAGE='212',
 XY='(-625,4700)',
 ROT='0',
 VER='1',
 PACK_TYPE='C0805',
 LOCATION='PC304_3',
 CDS_LIB='pure_quanta',
 CDS_PART_NAME='Q_CAP_C0805-22UF,4V,20%,X6S,CH622KMEA03',
 VOLTAGE='4V',
 PART_NUMBER='CH622KMEA03',
 VALUE='22UF',
 PRIM_FILE='./archive_libs/logical/q_cap/chips/chips.prt';

PART_NAME
 PC305_4 'Q_CAP_C0805-22UF,4V,20%,X6S,CH622KMEA03':;

SECTION_NUMBER 1
 '@T6G_MB_LIB.T6G(SCH_1):PAGE187_I60@PURE_QUANTA.Q_CAP(CHIPS)':
 C_PATH='@t6g_mb_lib.t6g(sch_1):page187_i60@pure_quanta.q_cap(chips)',
 P_PATH='@t6g_mb_lib.t6g(sch_1):page212_i60@pure_quanta.q_cap(chips)',
 PATH='I60',
 DRAWING='@T6G_MB_LIB.T6G(SCH_1):PAGE187',
 TOLERANCE='20%',
 MATERIAL='X6S',
 PHYS_PAGE='212',
 XY='(-575,1400)',
 ROT='0',
 VER='1',
 PACK_TYPE='C0805',
 LOCATION='PC305_4',
 CDS_LIB='pure_quanta',
 CDS_PART_NAME='Q_CAP_C0805-22UF,4V,20%,X6S,CH622KMEA03',
 VOLTAGE='4V',
 PART_NUMBER='CH622KMEA03',
 VALUE='22UF',
 PRIM_FILE='./archive_libs/logical/q_cap/chips/chips.prt';

PART_NAME
 PC306_5 'Q_CAP_0402-0.1UF,25V,10%,X7R,CH4104K1B00':;

SECTION_NUMBER 1
 '@T6G_MB_LIB.T6G(SCH_1):PAGE188_I34@PURE_QUANTA.Q_CAP(CHIPS)':
 C_PATH='@t6g_mb_lib.t6g(sch_1):page188_i34@pure_quanta.q_cap(chips)',
 P_PATH='@t6g_mb_lib.t6g(sch_1):page213_i34@pure_quanta.q_cap(chips)',
 PATH='I34',
 DRAWING='@T6G_MB_LIB.T6G(SCH_1):PAGE188',
 TOLERANCE='10%',
 MATERIAL='X7R',
 PHYS_PAGE='213',
 XY='(-7525,4575)',
 ROT='0',
 VER='1',
 PACK_TYPE='0402',
 LOCATION='PC306_5',
 CDS_LIB='pure_quanta',
 CDS_PART_NAME='Q_CAP_0402-0.1UF,25V,10%,X7R,CH4104K1B00',
 VOLTAGE='25V',
 PART_NUMBER='CH4104K1B00',
 VALUE='0.1UF',
 PRIM_FILE='./archive_libs/logical/q_cap/chips/chips.prt';

PART_NAME
 PC307 'Q_CAP_C0402-2.2UF,10V,10%,X6S,CH5222KEB01':;

SECTION_NUMBER 1
 '@T6G_MB_LIB.T6G(SCH_1):PAGE188_I39@PURE_QUANTA.Q_CAP(CHIPS)':
 C_PATH='@t6g_mb_lib.t6g(sch_1):page188_i39@pure_quanta.q_cap(chips)',
 P_PATH='@t6g_mb_lib.t6g(sch_1):page213_i39@pure_quanta.q_cap(chips)',
 PATH='I39',
 DRAWING='@T6G_MB_LIB.T6G(SCH_1):PAGE188',
 TOLERANCE='10%',
 MATERIAL='X6S',
 PHYS_PAGE='213',
 XY='(-7200,5200)',
 ROT='0',
 VER='1',
 PACK_TYPE='C0402',
 LOCATION='PC307',
 CDS_LIB='pure_quanta',
 CDS_PART_NAME='Q_CAP_C0402-2.2UF,10V,10%,X6S,CH5222KEB01',
 VOLTAGE='10V',
 PART_NUMBER='CH5222KEB01',
 VALUE='2.2UF',
 PRIM_FILE='./archive_libs/logical/q_cap/chips/chips.prt';

PART_NAME
 PC308_C0P1_5 'Q_CAP_C0402-2.2UF,10V,10%,X6S,CH5222KEB01':;

SECTION_NUMBER 1
 '@T6G_MB_LIB.T6G(SCH_1):PAGE188_I43@PURE_QUANTA.Q_CAP(CHIPS)':
 C_PATH='@t6g_mb_lib.t6g(sch_1):page188_i43@pure_quanta.q_cap(chips)',
 P_PATH='@t6g_mb_lib.t6g(sch_1):page213_i43@pure_quanta.q_cap(chips)',
 PATH='I43',
 DRAWING='@T6G_MB_LIB.T6G(SCH_1):PAGE188',
 TOLERANCE='10%',
 MATERIAL='X6S',
 PHYS_PAGE='213',
 XY='(-6850,5775)',
 ROT='0',
 VER='1',
 PACK_TYPE='C0402',
 LOCATION='PC308_C0P1_5',
 CDS_LIB='pure_quanta',
 CDS_PART_NAME='Q_CAP_C0402-2.2UF,10V,10%,X6S,CH5222KEB01',
 VOLTAGE='10V',
 PART_NUMBER='CH5222KEB01',
 VALUE='2.2UF',
 PRIM_FILE='./archive_libs/logical/q_cap/chips/chips.prt';

PART_NAME
 PC309_5 'Q_CAP_0402-0.1UF,25V,10%,X7R,CH4104K1B00':;

SECTION_NUMBER 1
 '@T6G_MB_LIB.T6G(SCH_1):PAGE188_I45@PURE_QUANTA.Q_CAP(CHIPS)':
 C_PATH='@t6g_mb_lib.t6g(sch_1):page188_i45@pure_quanta.q_cap(chips)',
 P_PATH='@t6g_mb_lib.t6g(sch_1):page213_i45@pure_quanta.q_cap(chips)',
 PATH='I45',
 DRAWING='@T6G_MB_LIB.T6G(SCH_1):PAGE188',
 TOLERANCE='10%',
 MATERIAL='X7R',
 PHYS_PAGE='213',
 XY='(-4950,5725)',
 ROT='0',
 VER='1',
 PACK_TYPE='0402',
 LOCATION='PC309_5',
 CDS_LIB='pure_quanta',
 CDS_PART_NAME='Q_CAP_0402-0.1UF,25V,10%,X7R,CH4104K1B00',
 VOLTAGE='25V',
 PART_NUMBER='CH4104K1B00',
 VALUE='0.1UF',
 PRIM_FILE='./archive_libs/logical/q_cap/chips/chips.prt';

PART_NAME
 PC310_5 'Q_CAP_C0402-1UF,25V,10%,X6S,CH5104KEB02':;

SECTION_NUMBER 1
 '@T6G_MB_LIB.T6G(SCH_1):PAGE188_I48@PURE_QUANTA.Q_CAP(CHIPS)':
 C_PATH='@t6g_mb_lib.t6g(sch_1):page188_i48@pure_quanta.q_cap(chips)',
 P_PATH='@t6g_mb_lib.t6g(sch_1):page213_i48@pure_quanta.q_cap(chips)',
 PATH='I48',
 DRAWING='@T6G_MB_LIB.T6G(SCH_1):PAGE188',
 TOLERANCE='10%',
 MATERIAL='X6S',
 PHYS_PAGE='213',
 XY='(-4575,5725)',
 ROT='0',
 VER='1',
 PACK_TYPE='C0402',
 LOCATION='PC310_5',
 CDS_LIB='pure_quanta',
 CDS_PART_NAME='Q_CAP_C0402-1UF,25V,10%,X6S,CH5104KEB02',
 VOLTAGE='25V',
 PART_NUMBER='CH5104KEB02',
 VALUE='1UF',
 PRIM_FILE='./archive_libs/logical/q_cap/chips/chips.prt';

PART_NAME
 PC311_5 'Q_CAP_C0805-22UF,16V,20%,X6S,CH6223MEA01':;

SECTION_NUMBER 1
 '@T6G_MB_LIB.T6G(SCH_1):PAGE188_I49@PURE_QUANTA.Q_CAP(CHIPS)':
 C_PATH='@t6g_mb_lib.t6g(sch_1):page188_i49@pure_quanta.q_cap(chips)',
 P_PATH='@t6g_mb_lib.t6g(sch_1):page213_i49@pure_quanta.q_cap(chips)',
 PATH='I49',
 DRAWING='@T6G_MB_LIB.T6G(SCH_1):PAGE188',
 TOLERANCE='20%',
 MATERIAL='X6S',
 PHYS_PAGE='213',
 XY='(-4250,5725)',
 ROT='0',
 VER='1',
 PACK_TYPE='C0805',
 LOCATION='PC311_5',
 CDS_LIB='pure_quanta',
 CDS_PART_NAME='Q_CAP_C0805-22UF,16V,20%,X6S,CH6223MEA01',
 VOLTAGE='16V',
 PART_NUMBER='CH6223MEA01',
 VALUE='22UF',
 PRIM_FILE='./archive_libs/logical/q_cap/chips/chips.prt';

PART_NAME
 PC312_5 'Q_CAP_C0805-22UF,16V,20%,X6S,CH6223MEA01':;

SECTION_NUMBER 1
 '@T6G_MB_LIB.T6G(SCH_1):PAGE188_I50@PURE_QUANTA.Q_CAP(CHIPS)':
 C_PATH='@t6g_mb_lib.t6g(sch_1):page188_i50@pure_quanta.q_cap(chips)',
 P_PATH='@t6g_mb_lib.t6g(sch_1):page213_i50@pure_quanta.q_cap(chips)',
 PATH='I50',
 DRAWING='@T6G_MB_LIB.T6G(SCH_1):PAGE188',
 TOLERANCE='20%',
 MATERIAL='X6S',
 PHYS_PAGE='213',
 XY='(-3925,5725)',
 ROT='0',
 VER='1',
 PACK_TYPE='C0805',
 LOCATION='PC312_5',
 CDS_LIB='pure_quanta',
 CDS_PART_NAME='Q_CAP_C0805-22UF,16V,20%,X6S,CH6223MEA01',
 VOLTAGE='16V',
 PART_NUMBER='CH6223MEA01',
 VALUE='22UF',
 PRIM_FILE='./archive_libs/logical/q_cap/chips/chips.prt';

PART_NAME
 PC313_5 'Q_CAP_C0805-22UF,16V,20%,X6S,CH6223MEA01':;

SECTION_NUMBER 1
 '@T6G_MB_LIB.T6G(SCH_1):PAGE188_I66@PURE_QUANTA.Q_CAP(CHIPS)':
 C_PATH='@t6g_mb_lib.t6g(sch_1):page188_i66@pure_quanta.q_cap(chips)',
 P_PATH='@t6g_mb_lib.t6g(sch_1):page213_i66@pure_quanta.q_cap(chips)',
 PATH='I66',
 DRAWING='@T6G_MB_LIB.T6G(SCH_1):PAGE188',
 TOLERANCE='20%',
 MATERIAL='X6S',
 PHYS_PAGE='213',
 XY='(-3625,5725)',
 ROT='0',
 VER='1',
 PACK_TYPE='C0805',
 LOCATION='PC313_5',
 CDS_LIB='pure_quanta',
 CDS_PART_NAME='Q_CAP_C0805-22UF,16V,20%,X6S,CH6223MEA01',
 VOLTAGE='16V',
 PART_NUMBER='CH6223MEA01',
 VALUE='22UF',
 PRIM_FILE='./archive_libs/logical/q_cap/chips/chips.prt';

PART_NAME
 PC314 'Q_CAP_0402-0.22UF,16V,10%,X7R,CH4223K1B00':;

SECTION_NUMBER 1
 '@T6G_MB_LIB.T6G(SCH_1):PAGE188_I63@PURE_QUANTA.Q_CAP(CHIPS)':
 C_PATH='@t6g_mb_lib.t6g(sch_1):page188_i63@pure_quanta.q_cap(chips)',
 P_PATH='@t6g_mb_lib.t6g(sch_1):page213_i63@pure_quanta.q_cap(chips)',
 PATH='I63',
 DRAWING='@T6G_MB_LIB.T6G(SCH_1):PAGE188',
 TOLERANCE='10%',
 MATERIAL='X7R',
 PHYS_PAGE='213',
 XY='(-3325,5075)',
 ROT='0',
 VER='1',
 PACK_TYPE='0402',
 LOCATION='PC314',
 CDS_LIB='pure_quanta',
 CDS_PART_NAME='Q_CAP_0402-0.22UF,16V,10%,X7R,CH4223K1B00',
 VOLTAGE='16V',
 PART_NUMBER='CH4223K1B00',
 VALUE='0.22UF',
 PRIM_FILE='./archive_libs/logical/q_cap/chips/chips.prt';

PART_NAME
 PC315 'Q_CAP_C0402-560PF,50V,10%,EMPTY,CH1566K1B09':;

SECTION_NUMBER 1
 '@T6G_MB_LIB.T6G(SCH_1):PAGE200_I46@PURE_QUANTA.Q_CAP(CHIPS)':
 C_PATH='@t6g_mb_lib.t6g(sch_1):page200_i46@pure_quanta.q_cap(chips)',
 P_PATH='@t6g_mb_lib.t6g(sch_1):page225_i46@pure_quanta.q_cap(chips)',
 PATH='I46',
 DRAWING='@T6G_MB_LIB.T6G(SCH_1):PAGE200',
 TOLERANCE='10%',
 MATERIAL='EMPTY',
 PHYS_PAGE='225',
 XY='(-4600,4425)',
 ROT='0',
 VER='1',
 PACK_TYPE='C0402',
 LOCATION='PC315',
 CDS_LIB='pure_quanta',
 CDS_PART_NAME='Q_CAP_C0402-560PF,50V,10%,EMPTY,CH1566K1B09',
 VOLTAGE='50V',
 PART_NUMBER='CH1566K1B09',
 VALUE='560PF',
 PRIM_FILE='./archive_libs/logical/q_cap/chips/chips.prt';

PART_NAME
 PC315_5 'Q_CAP_C0805-22UF,4V,20%,X6S,CH622KMEA03':;

SECTION_NUMBER 1
 '@T6G_MB_LIB.T6G(SCH_1):PAGE188_I69@PURE_QUANTA.Q_CAP(CHIPS)':
 C_PATH='@t6g_mb_lib.t6g(sch_1):page188_i69@pure_quanta.q_cap(chips)',
 P_PATH='@t6g_mb_lib.t6g(sch_1):page213_i69@pure_quanta.q_cap(chips)',
 PATH='I69',
 DRAWING='@T6G_MB_LIB.T6G(SCH_1):PAGE188',
 TOLERANCE='20%',
 MATERIAL='X6S',
 PHYS_PAGE='213',
 XY='(-1175,4675)',
 ROT='0',
 VER='1',
 PACK_TYPE='C0805',
 LOCATION='PC315_5',
 CDS_LIB='pure_quanta',
 CDS_PART_NAME='Q_CAP_C0805-22UF,4V,20%,X6S,CH622KMEA03',
 VOLTAGE='4V',
 PART_NUMBER='CH622KMEA03',
 VALUE='22UF',
 PRIM_FILE='./archive_libs/logical/q_cap/chips/chips.prt';

PART_NAME
 PC316 'Q_CAP_C0402-560PF,50V,10%,EMPTY,CH1566K1B09':;

SECTION_NUMBER 1
 '@T6G_MB_LIB.T6G(SCH_1):PAGE187_I46@PURE_QUANTA.Q_CAP(CHIPS)':
 C_PATH='@t6g_mb_lib.t6g(sch_1):page187_i46@pure_quanta.q_cap(chips)',
 P_PATH='@t6g_mb_lib.t6g(sch_1):page212_i46@pure_quanta.q_cap(chips)',
 PATH='I46',
 DRAWING='@T6G_MB_LIB.T6G(SCH_1):PAGE187',
 TOLERANCE='10%',
 MATERIAL='EMPTY',
 PHYS_PAGE='212',
 XY='(-4250,4675)',
 ROT='0',
 VER='1',
 PACK_TYPE='C0402',
 LOCATION='PC316',
 CDS_LIB='pure_quanta',
 CDS_PART_NAME='Q_CAP_C0402-560PF,50V,10%,EMPTY,CH1566K1B09',
 VOLTAGE='50V',
 PART_NUMBER='CH1566K1B09',
 VALUE='560PF',
 PRIM_FILE='./archive_libs/logical/q_cap/chips/chips.prt';

PART_NAME
 PC316_5 'Q_CAP_C0805-22UF,4V,20%,X6S,CH622KMEA03':;

SECTION_NUMBER 1
 '@T6G_MB_LIB.T6G(SCH_1):PAGE188_I71@PURE_QUANTA.Q_CAP(CHIPS)':
 C_PATH='@t6g_mb_lib.t6g(sch_1):page188_i71@pure_quanta.q_cap(chips)',
 P_PATH='@t6g_mb_lib.t6g(sch_1):page213_i71@pure_quanta.q_cap(chips)',
 PATH='I71',
 DRAWING='@T6G_MB_LIB.T6G(SCH_1):PAGE188',
 TOLERANCE='20%',
 MATERIAL='X6S',
 PHYS_PAGE='213',
 XY='(-750,4675)',
 ROT='0',
 VER='1',
 PACK_TYPE='C0805',
 LOCATION='PC316_5',
 CDS_LIB='pure_quanta',
 CDS_PART_NAME='Q_CAP_C0805-22UF,4V,20%,X6S,CH622KMEA03',
 VOLTAGE='4V',
 PART_NUMBER='CH622KMEA03',
 VALUE='22UF',
 PRIM_FILE='./archive_libs/logical/q_cap/chips/chips.prt';

PART_NAME
 PC317 'Q_CAP_C0402-560PF,50V,10%,EMPTY,CH1566K1B09':;

SECTION_NUMBER 1
 '@T6G_MB_LIB.T6G(SCH_1):PAGE187_I20@PURE_QUANTA.Q_CAP(CHIPS)':
 C_PATH='@t6g_mb_lib.t6g(sch_1):page187_i20@pure_quanta.q_cap(chips)',
 P_PATH='@t6g_mb_lib.t6g(sch_1):page212_i20@pure_quanta.q_cap(chips)',
 PATH='I20',
 DRAWING='@T6G_MB_LIB.T6G(SCH_1):PAGE187',
 TOLERANCE='10%',
 MATERIAL='EMPTY',
 PHYS_PAGE='212',
 XY='(-4250,1375)',
 ROT='0',
 VER='1',
 PACK_TYPE='C0402',
 LOCATION='PC317',
 CDS_LIB='pure_quanta',
 CDS_PART_NAME='Q_CAP_C0402-560PF,50V,10%,EMPTY,CH1566K1B09',
 VOLTAGE='50V',
 PART_NUMBER='CH1566K1B09',
 VALUE='560PF',
 PRIM_FILE='./archive_libs/logical/q_cap/chips/chips.prt';

PART_NAME
 PC317_7 'Q_CAP_0402-0.1UF,25V,10%,X7R,CH4104K1B00':;

SECTION_NUMBER 1
 '@T6G_MB_LIB.T6G(SCH_1):PAGE190_I32@PURE_QUANTA.Q_CAP(CHIPS)':
 C_PATH='@t6g_mb_lib.t6g(sch_1):page190_i32@pure_quanta.q_cap(chips)',
 P_PATH='@t6g_mb_lib.t6g(sch_1):page215_i32@pure_quanta.q_cap(chips)',
 PATH='I32',
 DRAWING='@T6G_MB_LIB.T6G(SCH_1):PAGE190',
 TOLERANCE='10%',
 MATERIAL='X7R',
 PHYS_PAGE='215',
 XY='(-7875,4475)',
 ROT='0',
 VER='1',
 PACK_TYPE='0402',
 LOCATION='PC317_7',
 CDS_LIB='pure_quanta',
 CDS_PART_NAME='Q_CAP_0402-0.1UF,25V,10%,X7R,CH4104K1B00',
 VOLTAGE='25V',
 PART_NUMBER='CH4104K1B00',
 VALUE='0.1UF',
 PRIM_FILE='./archive_libs/logical/q_cap/chips/chips.prt';

PART_NAME
 PC318 'Q_CAP_C0402-560PF,50V,10%,EMPTY,CH1566K1B09':;

SECTION_NUMBER 1
 '@T6G_MB_LIB.T6G(SCH_1):PAGE188_I46@PURE_QUANTA.Q_CAP(CHIPS)':
 C_PATH='@t6g_mb_lib.t6g(sch_1):page188_i46@pure_quanta.q_cap(chips)',
 P_PATH='@t6g_mb_lib.t6g(sch_1):page213_i46@pure_quanta.q_cap(chips)',
 PATH='I46',
 DRAWING='@T6G_MB_LIB.T6G(SCH_1):PAGE188',
 TOLERANCE='10%',
 MATERIAL='EMPTY',
 PHYS_PAGE='213',
 XY='(-4275,4650)',
 ROT='0',
 VER='1',
 PACK_TYPE='C0402',
 LOCATION='PC318',
 CDS_LIB='pure_quanta',
 CDS_PART_NAME='Q_CAP_C0402-560PF,50V,10%,EMPTY,CH1566K1B09',
 VOLTAGE='50V',
 PART_NUMBER='CH1566K1B09',
 VALUE='560PF',
 PRIM_FILE='./archive_libs/logical/q_cap/chips/chips.prt';

PART_NAME
 PC318_8 'Q_CAP_0402-0.1UF,25V,10%,X7R,CH4104K1B00':;

SECTION_NUMBER 1
 '@T6G_MB_LIB.T6G(SCH_1):PAGE190_I4@PURE_QUANTA.Q_CAP(CHIPS)':
 C_PATH='@t6g_mb_lib.t6g(sch_1):page190_i4@pure_quanta.q_cap(chips)',
 P_PATH='@t6g_mb_lib.t6g(sch_1):page215_i4@pure_quanta.q_cap(chips)',
 PATH='I4',
 DRAWING='@T6G_MB_LIB.T6G(SCH_1):PAGE190',
 TOLERANCE='10%',
 MATERIAL='X7R',
 PHYS_PAGE='215',
 XY='(-7850,1700)',
 ROT='0',
 VER='1',
 PACK_TYPE='0402',
 LOCATION='PC318_8',
 CDS_LIB='pure_quanta',
 CDS_PART_NAME='Q_CAP_0402-0.1UF,25V,10%,X7R,CH4104K1B00',
 VOLTAGE='25V',
 PART_NUMBER='CH4104K1B00',
 VALUE='0.1UF',
 PRIM_FILE='./archive_libs/logical/q_cap/chips/chips.prt';

PART_NAME
 PC319 'Q_CAP_C0402-2.2UF,10V,10%,X6S,CH5222KEB01':;

SECTION_NUMBER 1
 '@T6G_MB_LIB.T6G(SCH_1):PAGE190_I36@PURE_QUANTA.Q_CAP(CHIPS)':
 C_PATH='@t6g_mb_lib.t6g(sch_1):page190_i36@pure_quanta.q_cap(chips)',
 P_PATH='@t6g_mb_lib.t6g(sch_1):page215_i36@pure_quanta.q_cap(chips)',
 PATH='I36',
 DRAWING='@T6G_MB_LIB.T6G(SCH_1):PAGE190',
 TOLERANCE='10%',
 MATERIAL='X6S',
 PHYS_PAGE='215',
 XY='(-7550,5100)',
 ROT='0',
 VER='1',
 PACK_TYPE='C0402',
 LOCATION='PC319',
 CDS_LIB='pure_quanta',
 CDS_PART_NAME='Q_CAP_C0402-2.2UF,10V,10%,X6S,CH5222KEB01',
 VOLTAGE='10V',
 PART_NUMBER='CH5222KEB01',
 VALUE='2.2UF',
 PRIM_FILE='./archive_libs/logical/q_cap/chips/chips.prt';

PART_NAME
 PC320 'Q_CAP_C0402-2.2UF,10V,10%,X6S,CH5222KEB01':;

SECTION_NUMBER 1
 '@T6G_MB_LIB.T6G(SCH_1):PAGE190_I11@PURE_QUANTA.Q_CAP(CHIPS)':
 C_PATH='@t6g_mb_lib.t6g(sch_1):page190_i11@pure_quanta.q_cap(chips)',
 P_PATH='@t6g_mb_lib.t6g(sch_1):page215_i11@pure_quanta.q_cap(chips)',
 PATH='I11',
 DRAWING='@T6G_MB_LIB.T6G(SCH_1):PAGE190',
 TOLERANCE='10%',
 MATERIAL='X6S',
 PHYS_PAGE='215',
 XY='(-7525,2325)',
 ROT='0',
 VER='1',
 PACK_TYPE='C0402',
 LOCATION='PC320',
 CDS_LIB='pure_quanta',
 CDS_PART_NAME='Q_CAP_C0402-2.2UF,10V,10%,X6S,CH5222KEB01',
 VOLTAGE='10V',
 PART_NUMBER='CH5222KEB01',
 VALUE='2.2UF',
 PRIM_FILE='./archive_libs/logical/q_cap/chips/chips.prt';

PART_NAME
 PC321 'Q_CAP_C0402-560PF,50V,10%,EMPTY,CH1566K1B09':;

SECTION_NUMBER 1
 '@T6G_MB_LIB.T6G(SCH_1):PAGE188_I23@PURE_QUANTA.Q_CAP(CHIPS)':
 C_PATH='@t6g_mb_lib.t6g(sch_1):page188_i23@pure_quanta.q_cap(chips)',
 P_PATH='@t6g_mb_lib.t6g(sch_1):page213_i23@pure_quanta.q_cap(chips)',
 PATH='I23',
 DRAWING='@T6G_MB_LIB.T6G(SCH_1):PAGE188',
 TOLERANCE='10%',
 MATERIAL='EMPTY',
 PHYS_PAGE='213',
 XY='(-4225,1750)',
 ROT='0',
 VER='1',
 PACK_TYPE='C0402',
 LOCATION='PC321',
 CDS_LIB='pure_quanta',
 CDS_PART_NAME='Q_CAP_C0402-560PF,50V,10%,EMPTY,CH1566K1B09',
 VOLTAGE='50V',
 PART_NUMBER='CH1566K1B09',
 VALUE='560PF',
 PRIM_FILE='./archive_libs/logical/q_cap/chips/chips.prt';

PART_NAME
 PC321_SOP1_1 'Q_CAP_C0402-2.2UF,10V,10%,X6S,CH5222KEB01':;

SECTION_NUMBER 1
 '@T6G_MB_LIB.T6G(SCH_1):PAGE190_I41@PURE_QUANTA.Q_CAP(CHIPS)':
 C_PATH='@t6g_mb_lib.t6g(sch_1):page190_i41@pure_quanta.q_cap(chips)',
 P_PATH='@t6g_mb_lib.t6g(sch_1):page215_i41@pure_quanta.q_cap(chips)',
 PATH='I41',
 DRAWING='@T6G_MB_LIB.T6G(SCH_1):PAGE190',
 TOLERANCE='10%',
 MATERIAL='X6S',
 PHYS_PAGE='215',
 XY='(-7200,5675)',
 ROT='0',
 VER='1',
 PACK_TYPE='C0402',
 LOCATION='PC321_SOP1_1',
 CDS_LIB='pure_quanta',
 CDS_PART_NAME='Q_CAP_C0402-2.2UF,10V,10%,X6S,CH5222KEB01',
 VOLTAGE='10V',
 PART_NUMBER='CH5222KEB01',
 VALUE='2.2UF',
 PRIM_FILE='./archive_libs/logical/q_cap/chips/chips.prt';

PART_NAME
 PC322_SOP1_2 'Q_CAP_C0402-2.2UF,10V,10%,X6S,CH5222KEB01':;

SECTION_NUMBER 1
 '@T6G_MB_LIB.T6G(SCH_1):PAGE190_I14@PURE_QUANTA.Q_CAP(CHIPS)':
 C_PATH='@t6g_mb_lib.t6g(sch_1):page190_i14@pure_quanta.q_cap(chips)',
 P_PATH='@t6g_mb_lib.t6g(sch_1):page215_i14@pure_quanta.q_cap(chips)',
 PATH='I14',
 DRAWING='@T6G_MB_LIB.T6G(SCH_1):PAGE190',
 TOLERANCE='10%',
 MATERIAL='X6S',
 PHYS_PAGE='215',
 XY='(-7175,2900)',
 ROT='0',
 VER='1',
 PACK_TYPE='C0402',
 LOCATION='PC322_SOP1_2',
 CDS_LIB='pure_quanta',
 CDS_PART_NAME='Q_CAP_C0402-2.2UF,10V,10%,X6S,CH5222KEB01',
 VOLTAGE='10V',
 PART_NUMBER='CH5222KEB01',
 VALUE='2.2UF',
 PRIM_FILE='./archive_libs/logical/q_cap/chips/chips.prt';

PART_NAME
 PC323_1 'Q_CAP_C0402-1UF,25V,10%,X6S,CH5104KEB02':;

SECTION_NUMBER 1
 '@T6G_MB_LIB.T6G(SCH_1):PAGE190_I44@PURE_QUANTA.Q_CAP(CHIPS)':
 C_PATH='@t6g_mb_lib.t6g(sch_1):page190_i44@pure_quanta.q_cap(chips)',
 P_PATH='@t6g_mb_lib.t6g(sch_1):page215_i44@pure_quanta.q_cap(chips)',
 PATH='I44',
 DRAWING='@T6G_MB_LIB.T6G(SCH_1):PAGE190',
 TOLERANCE='10%',
 MATERIAL='X6S',
 PHYS_PAGE='215',
 XY='(-5125,5600)',
 ROT='0',
 VER='1',
 PACK_TYPE='C0402',
 LOCATION='PC323_1',
 CDS_LIB='pure_quanta',
 CDS_PART_NAME='Q_CAP_C0402-1UF,25V,10%,X6S,CH5104KEB02',
 VOLTAGE='25V',
 PART_NUMBER='CH5104KEB02',
 VALUE='1UF',
 PRIM_FILE='./archive_libs/logical/q_cap/chips/chips.prt';

PART_NAME
 PC324_2 'Q_CAP_C0402-1UF,25V,10%,X6S,CH5104KEB02':;

SECTION_NUMBER 1
 '@T6G_MB_LIB.T6G(SCH_1):PAGE190_I25@PURE_QUANTA.Q_CAP(CHIPS)':
 C_PATH='@t6g_mb_lib.t6g(sch_1):page190_i25@pure_quanta.q_cap(chips)',
 P_PATH='@t6g_mb_lib.t6g(sch_1):page215_i25@pure_quanta.q_cap(chips)',
 PATH='I25',
 DRAWING='@T6G_MB_LIB.T6G(SCH_1):PAGE190',
 TOLERANCE='10%',
 MATERIAL='X6S',
 PHYS_PAGE='215',
 XY='(-5000,2875)',
 ROT='0',
 VER='1',
 PACK_TYPE='C0402',
 LOCATION='PC324_2',
 CDS_LIB='pure_quanta',
 CDS_PART_NAME='Q_CAP_C0402-1UF,25V,10%,X6S,CH5104KEB02',
 VOLTAGE='25V',
 PART_NUMBER='CH5104KEB02',
 VALUE='1UF',
 PRIM_FILE='./archive_libs/logical/q_cap/chips/chips.prt';

PART_NAME
 PC325_1 'Q_CAP_0402-0.1UF,25V,10%,X7R,CH4104K1B00':;

SECTION_NUMBER 1
 '@T6G_MB_LIB.T6G(SCH_1):PAGE190_I43@PURE_QUANTA.Q_CAP(CHIPS)':
 C_PATH='@t6g_mb_lib.t6g(sch_1):page190_i43@pure_quanta.q_cap(chips)',
 P_PATH='@t6g_mb_lib.t6g(sch_1):page215_i43@pure_quanta.q_cap(chips)',
 PATH='I43',
 DRAWING='@T6G_MB_LIB.T6G(SCH_1):PAGE190',
 TOLERANCE='10%',
 MATERIAL='X7R',
 PHYS_PAGE='215',
 XY='(-5450,5600)',
 ROT='0',
 VER='1',
 PACK_TYPE='0402',
 LOCATION='PC325_1',
 CDS_LIB='pure_quanta',
 CDS_PART_NAME='Q_CAP_0402-0.1UF,25V,10%,X7R,CH4104K1B00',
 VOLTAGE='25V',
 PART_NUMBER='CH4104K1B00',
 VALUE='0.1UF',
 PRIM_FILE='./archive_libs/logical/q_cap/chips/chips.prt';

PART_NAME
 PC326_2 'Q_CAP_0402-0.1UF,25V,10%,X7R,CH4104K1B00':;

SECTION_NUMBER 1
 '@T6G_MB_LIB.T6G(SCH_1):PAGE190_I22@PURE_QUANTA.Q_CAP(CHIPS)':
 C_PATH='@t6g_mb_lib.t6g(sch_1):page190_i22@pure_quanta.q_cap(chips)',
 P_PATH='@t6g_mb_lib.t6g(sch_1):page215_i22@pure_quanta.q_cap(chips)',
 PATH='I22',
 DRAWING='@T6G_MB_LIB.T6G(SCH_1):PAGE190',
 TOLERANCE='10%',
 MATERIAL='X7R',
 PHYS_PAGE='215',
 XY='(-5375,2875)',
 ROT='0',
 VER='1',
 PACK_TYPE='0402',
 LOCATION='PC326_2',
 CDS_LIB='pure_quanta',
 CDS_PART_NAME='Q_CAP_0402-0.1UF,25V,10%,X7R,CH4104K1B00',
 VOLTAGE='25V',
 PART_NUMBER='CH4104K1B00',
 VALUE='0.1UF',
 PRIM_FILE='./archive_libs/logical/q_cap/chips/chips.prt';

PART_NAME
 PC327_1 'Q_CAP_C0805-22UF,16V,20%,X6S,CH6223MEA01':;

SECTION_NUMBER 1
 '@T6G_MB_LIB.T6G(SCH_1):PAGE190_I48@PURE_QUANTA.Q_CAP(CHIPS)':
 C_PATH='@t6g_mb_lib.t6g(sch_1):page190_i48@pure_quanta.q_cap(chips)',
 P_PATH='@t6g_mb_lib.t6g(sch_1):page215_i48@pure_quanta.q_cap(chips)',
 PATH='I48',
 DRAWING='@T6G_MB_LIB.T6G(SCH_1):PAGE190',
 TOLERANCE='20%',
 MATERIAL='X6S',
 PHYS_PAGE='215',
 XY='(-4800,5600)',
 ROT='0',
 VER='1',
 PACK_TYPE='C0805',
 LOCATION='PC327_1',
 CDS_LIB='pure_quanta',
 CDS_PART_NAME='Q_CAP_C0805-22UF,16V,20%,X6S,CH6223MEA01',
 VOLTAGE='16V',
 PART_NUMBER='CH6223MEA01',
 VALUE='22UF',
 PRIM_FILE='./archive_libs/logical/q_cap/chips/chips.prt';

PART_NAME
 PC328_2 'Q_CAP_C0805-22UF,16V,20%,X6S,CH6223MEA01':;

SECTION_NUMBER 1
 '@T6G_MB_LIB.T6G(SCH_1):PAGE190_I26@PURE_QUANTA.Q_CAP(CHIPS)':
 C_PATH='@t6g_mb_lib.t6g(sch_1):page190_i26@pure_quanta.q_cap(chips)',
 P_PATH='@t6g_mb_lib.t6g(sch_1):page215_i26@pure_quanta.q_cap(chips)',
 PATH='I26',
 DRAWING='@T6G_MB_LIB.T6G(SCH_1):PAGE190',
 TOLERANCE='20%',
 MATERIAL='X6S',
 PHYS_PAGE='215',
 XY='(-4675,2875)',
 ROT='0',
 VER='1',
 PACK_TYPE='C0805',
 LOCATION='PC328_2',
 CDS_LIB='pure_quanta',
 CDS_PART_NAME='Q_CAP_C0805-22UF,16V,20%,X6S,CH6223MEA01',
 VOLTAGE='16V',
 PART_NUMBER='CH6223MEA01',
 VALUE='22UF',
 PRIM_FILE='./archive_libs/logical/q_cap/chips/chips.prt';

PART_NAME
 PC329_1 'Q_CAP_C0805-22UF,16V,20%,X6S,CH6223MEA01':;

SECTION_NUMBER 1
 '@T6G_MB_LIB.T6G(SCH_1):PAGE190_I49@PURE_QUANTA.Q_CAP(CHIPS)':
 C_PATH='@t6g_mb_lib.t6g(sch_1):page190_i49@pure_quanta.q_cap(chips)',
 P_PATH='@t6g_mb_lib.t6g(sch_1):page215_i49@pure_quanta.q_cap(chips)',
 PATH='I49',
 DRAWING='@T6G_MB_LIB.T6G(SCH_1):PAGE190',
 TOLERANCE='20%',
 MATERIAL='X6S',
 PHYS_PAGE='215',
 XY='(-4475,5600)',
 ROT='0',
 VER='1',
 PACK_TYPE='C0805',
 LOCATION='PC329_1',
 CDS_LIB='pure_quanta',
 CDS_PART_NAME='Q_CAP_C0805-22UF,16V,20%,X6S,CH6223MEA01',
 VOLTAGE='16V',
 PART_NUMBER='CH6223MEA01',
 VALUE='22UF',
 PRIM_FILE='./archive_libs/logical/q_cap/chips/chips.prt';

PART_NAME
 PC330_2 'Q_CAP_C0805-22UF,16V,20%,X6S,CH6223MEA01':;

SECTION_NUMBER 1
 '@T6G_MB_LIB.T6G(SCH_1):PAGE190_I27@PURE_QUANTA.Q_CAP(CHIPS)':
 C_PATH='@t6g_mb_lib.t6g(sch_1):page190_i27@pure_quanta.q_cap(chips)',
 P_PATH='@t6g_mb_lib.t6g(sch_1):page215_i27@pure_quanta.q_cap(chips)',
 PATH='I27',
 DRAWING='@T6G_MB_LIB.T6G(SCH_1):PAGE190',
 TOLERANCE='20%',
 MATERIAL='X6S',
 PHYS_PAGE='215',
 XY='(-4350,2875)',
 ROT='0',
 VER='1',
 PACK_TYPE='C0805',
 LOCATION='PC330_2',
 CDS_LIB='pure_quanta',
 CDS_PART_NAME='Q_CAP_C0805-22UF,16V,20%,X6S,CH6223MEA01',
 VOLTAGE='16V',
 PART_NUMBER='CH6223MEA01',
 VALUE='22UF',
 PRIM_FILE='./archive_libs/logical/q_cap/chips/chips.prt';

PART_NAME
 PC331_1 'Q_CAP_C0805-22UF,16V,20%,X6S,CH6223MEA01':;

SECTION_NUMBER 1
 '@T6G_MB_LIB.T6G(SCH_1):PAGE190_I50@PURE_QUANTA.Q_CAP(CHIPS)':
 C_PATH='@t6g_mb_lib.t6g(sch_1):page190_i50@pure_quanta.q_cap(chips)',
 P_PATH='@t6g_mb_lib.t6g(sch_1):page215_i50@pure_quanta.q_cap(chips)',
 PATH='I50',
 DRAWING='@T6G_MB_LIB.T6G(SCH_1):PAGE190',
 TOLERANCE='20%',
 MATERIAL='X6S',
 PHYS_PAGE='215',
 XY='(-4175,5600)',
 ROT='0',
 VER='1',
 PACK_TYPE='C0805',
 LOCATION='PC331_1',
 CDS_LIB='pure_quanta',
 CDS_PART_NAME='Q_CAP_C0805-22UF,16V,20%,X6S,CH6223MEA01',
 VOLTAGE='16V',
 PART_NUMBER='CH6223MEA01',
 VALUE='22UF',
 PRIM_FILE='./archive_libs/logical/q_cap/chips/chips.prt';

PART_NAME
 PC332_2 'Q_CAP_C0805-22UF,16V,20%,X6S,CH6223MEA01':;

SECTION_NUMBER 1
 '@T6G_MB_LIB.T6G(SCH_1):PAGE190_I56@PURE_QUANTA.Q_CAP(CHIPS)':
 C_PATH='@t6g_mb_lib.t6g(sch_1):page190_i56@pure_quanta.q_cap(chips)',
 P_PATH='@t6g_mb_lib.t6g(sch_1):page215_i56@pure_quanta.q_cap(chips)',
 PATH='I56',
 DRAWING='@T6G_MB_LIB.T6G(SCH_1):PAGE190',
 TOLERANCE='20%',
 MATERIAL='X6S',
 PHYS_PAGE='215',
 XY='(-4050,2875)',
 ROT='0',
 VER='1',
 PACK_TYPE='C0805',
 LOCATION='PC332_2',
 CDS_LIB='pure_quanta',
 CDS_PART_NAME='Q_CAP_C0805-22UF,16V,20%,X6S,CH6223MEA01',
 VOLTAGE='16V',
 PART_NUMBER='CH6223MEA01',
 VALUE='22UF',
 PRIM_FILE='./archive_libs/logical/q_cap/chips/chips.prt';

PART_NAME
 PC333 'Q_CAP_0402-0.22UF,16V,10%,X7R,CH4223K1B00':;

SECTION_NUMBER 1
 '@T6G_MB_LIB.T6G(SCH_1):PAGE190_I68@PURE_QUANTA.Q_CAP(CHIPS)':
 C_PATH='@t6g_mb_lib.t6g(sch_1):page190_i68@pure_quanta.q_cap(chips)',
 P_PATH='@t6g_mb_lib.t6g(sch_1):page215_i68@pure_quanta.q_cap(chips)',
 PATH='I68',
 DRAWING='@T6G_MB_LIB.T6G(SCH_1):PAGE190',
 TOLERANCE='10%',
 MATERIAL='X7R',
 PHYS_PAGE='215',
 XY='(-3950,4975)',
 ROT='0',
 VER='1',
 PACK_TYPE='0402',
 LOCATION='PC333',
 CDS_LIB='pure_quanta',
 CDS_PART_NAME='Q_CAP_0402-0.22UF,16V,10%,X7R,CH4223K1B00',
 VOLTAGE='16V',
 PART_NUMBER='CH4223K1B00',
 VALUE='0.22UF',
 PRIM_FILE='./archive_libs/logical/q_cap/chips/chips.prt';

PART_NAME
 PC334 'Q_CAP_0402-0.22UF,16V,10%,X7R,CH4223K1B00':;

SECTION_NUMBER 1
 '@T6G_MB_LIB.T6G(SCH_1):PAGE190_I54@PURE_QUANTA.Q_CAP(CHIPS)':
 C_PATH='@t6g_mb_lib.t6g(sch_1):page190_i54@pure_quanta.q_cap(chips)',
 P_PATH='@t6g_mb_lib.t6g(sch_1):page215_i54@pure_quanta.q_cap(chips)',
 PATH='I54',
 DRAWING='@T6G_MB_LIB.T6G(SCH_1):PAGE190',
 TOLERANCE='10%',
 MATERIAL='X7R',
 PHYS_PAGE='215',
 XY='(-3825,2200)',
 ROT='0',
 VER='1',
 PACK_TYPE='0402',
 LOCATION='PC334',
 CDS_LIB='pure_quanta',
 CDS_PART_NAME='Q_CAP_0402-0.22UF,16V,10%,X7R,CH4223K1B00',
 VOLTAGE='16V',
 PART_NUMBER='CH4223K1B00',
 VALUE='0.22UF',
 PRIM_FILE='./archive_libs/logical/q_cap/chips/chips.prt';

PART_NAME
 PC334_1 'Q_CAP_C0805-22UF,16V,20%,X6S,CH6223MEA01':;

SECTION_NUMBER 1
 '@T6G_MB_LIB.T6G(SCH_1):PAGE190_I71@PURE_QUANTA.Q_CAP(CHIPS)':
 C_PATH='@t6g_mb_lib.t6g(sch_1):page190_i71@pure_quanta.q_cap(chips)',
 P_PATH='@t6g_mb_lib.t6g(sch_1):page215_i71@pure_quanta.q_cap(chips)',
 PATH='I71',
 DRAWING='@T6G_MB_LIB.T6G(SCH_1):PAGE190',
 TOLERANCE='20%',
 MATERIAL='X6S',
 PHYS_PAGE='215',
 XY='(-3950,5600)',
 ROT='0',
 VER='1',
 PACK_TYPE='C0805',
 LOCATION='PC334_1',
 CDS_LIB='pure_quanta',
 CDS_PART_NAME='Q_CAP_C0805-22UF,16V,20%,X6S,CH6223MEA01',
 VOLTAGE='16V',
 PART_NUMBER='CH6223MEA01',
 VALUE='22UF',
 PRIM_FILE='./archive_libs/logical/q_cap/chips/chips.prt';

PART_NAME
 PC335_2 'Q_CAP_C0805-22UF,16V,20%,X6S,CH6223MEA01':;

SECTION_NUMBER 1
 '@T6G_MB_LIB.T6G(SCH_1):PAGE190_I57@PURE_QUANTA.Q_CAP(CHIPS)':
 C_PATH='@t6g_mb_lib.t6g(sch_1):page190_i57@pure_quanta.q_cap(chips)',
 P_PATH='@t6g_mb_lib.t6g(sch_1):page215_i57@pure_quanta.q_cap(chips)',
 PATH='I57',
 DRAWING='@T6G_MB_LIB.T6G(SCH_1):PAGE190',
 TOLERANCE='20%',
 MATERIAL='X6S',
 PHYS_PAGE='215',
 XY='(-3725,2875)',
 ROT='0',
 VER='1',
 PACK_TYPE='C0805',
 LOCATION='PC335_2',
 CDS_LIB='pure_quanta',
 CDS_PART_NAME='Q_CAP_C0805-22UF,16V,20%,X6S,CH6223MEA01',
 VOLTAGE='16V',
 PART_NUMBER='CH6223MEA01',
 VALUE='22UF',
 PRIM_FILE='./archive_libs/logical/q_cap/chips/chips.prt';

PART_NAME
 PC336 'Q_CAPP_THLF-270UF,16V,20%,OSCON,CC72703MD38':;

SECTION_NUMBER 1
 '@T6G_MB_LIB.T6G(SCH_1):PAGE190_I73@PURE_QUANTA.Q_CAPP(CHIPS)':
 C_PATH='@t6g_mb_lib.t6g(sch_1):page190_i73@pure_quanta.q_capp(chips)',
 P_PATH='@t6g_mb_lib.t6g(sch_1):page215_i73@pure_quanta.q_capp(chips)',
 PATH='I73',
 DRAWING='@T6G_MB_LIB.T6G(SCH_1):PAGE190',
 TOLERANCE='20%',
 MATERIAL='OSCON',
 PHYS_PAGE='215',
 XY='(-3450,5600)',
 ROT='0',
 VER='1',
 PACK_TYPE='THLF',
 LOCATION='PC336',
 CDS_LIB='pure_quanta',
 CDS_PART_NAME='Q_CAPP_THLF-270UF,16V,20%,OSCON,CC72703MD38',
 VOLTAGE='16V',
 PART_NUMBER='CC72703MD38',
 VALUE='270UF',
 PRIM_FILE='./archive_libs/logical/q_capp/chips/chips.prt';

PART_NAME
 PC337 'Q_CAPP_SMLF-470UF,2.5V,20%,SPCAP,CH747LM8825':;

SECTION_NUMBER 1
 '@T6G_MB_LIB.T6G(SCH_1):PAGE190_I59@PURE_QUANTA.Q_CAPP(CHIPS)':
 C_PATH='@t6g_mb_lib.t6g(sch_1):page190_i59@pure_quanta.q_capp(chips)',
 P_PATH='@t6g_mb_lib.t6g(sch_1):page215_i59@pure_quanta.q_capp(chips)',
 PATH='I59',
 DRAWING='@T6G_MB_LIB.T6G(SCH_1):PAGE190',
 TOLERANCE='20%',
 MATERIAL='SPCAP',
 PHYS_PAGE='215',
 XY='(-2125,3075)',
 ROT='0',
 VER='1',
 PACK_TYPE='SMLF',
 LOCATION='PC337',
 CDS_LIB='pure_quanta',
 CDS_PART_NAME='Q_CAPP_SMLF-470UF,2.5V,20%,SPCAP,CH747LM8825',
 VOLTAGE='2.5V',
 PART_NUMBER='CH747LM8825',
 VALUE='470UF',
 PRIM_FILE='./archive_libs/logical/q_capp/chips/chips.prt';

PART_NAME
 PC338 'Q_CAP_0402-0.1UF,25V,10%,X7R,CH4104K1B00':;

SECTION_NUMBER 1
 '@T6G_MB_LIB.T6G(SCH_1):PAGE190_I79@PURE_QUANTA.Q_CAP(CHIPS)':
 C_PATH='@t6g_mb_lib.t6g(sch_1):page190_i79@pure_quanta.q_cap(chips)',
 P_PATH='@t6g_mb_lib.t6g(sch_1):page215_i79@pure_quanta.q_cap(chips)',
 PATH='I79',
 DRAWING='@T6G_MB_LIB.T6G(SCH_1):PAGE190',
 TOLERANCE='10%',
 MATERIAL='X7R',
 PHYS_PAGE='215',
 XY='(-1975,4550)',
 ROT='0',
 VER='1',
 PACK_TYPE='0402',
 LOCATION='PC338',
 CDS_LIB='pure_quanta',
 CDS_PART_NAME='Q_CAP_0402-0.1UF,25V,10%,X7R,CH4104K1B00',
 VOLTAGE='25V',
 PART_NUMBER='CH4104K1B00',
 VALUE='0.1UF',
 PRIM_FILE='./archive_libs/logical/q_cap/chips/chips.prt';

PART_NAME
 PC339_2 'Q_CAP_C0805-22UF,4V,20%,X6S,CH622KMEA03':;

SECTION_NUMBER 1
 '@T6G_MB_LIB.T6G(SCH_1):PAGE190_I60@PURE_QUANTA.Q_CAP(CHIPS)':
 C_PATH='@t6g_mb_lib.t6g(sch_1):page190_i60@pure_quanta.q_cap(chips)',
 P_PATH='@t6g_mb_lib.t6g(sch_1):page215_i60@pure_quanta.q_cap(chips)',
 PATH='I60',
 DRAWING='@T6G_MB_LIB.T6G(SCH_1):PAGE190',
 TOLERANCE='20%',
 MATERIAL='X6S',
 PHYS_PAGE='215',
 XY='(-1700,1800)',
 ROT='0',
 VER='1',
 PACK_TYPE='C0805',
 LOCATION='PC339_2',
 CDS_LIB='pure_quanta',
 CDS_PART_NAME='Q_CAP_C0805-22UF,4V,20%,X6S,CH622KMEA03',
 VOLTAGE='4V',
 PART_NUMBER='CH622KMEA03',
 VALUE='22UF',
 PRIM_FILE='./archive_libs/logical/q_cap/chips/chips.prt';

PART_NAME
 PC340 'Q_CAPP_SMLF-470UF,2.5V,20%,EMPTY,CH747LM8825':;

SECTION_NUMBER 1
 '@T6G_MB_LIB.T6G(SCH_1):PAGE190_I63@PURE_QUANTA.Q_CAPP(CHIPS)':
 C_PATH='@t6g_mb_lib.t6g(sch_1):page190_i63@pure_quanta.q_capp(chips)',
 P_PATH='@t6g_mb_lib.t6g(sch_1):page215_i63@pure_quanta.q_capp(chips)',
 PATH='I63',
 DRAWING='@T6G_MB_LIB.T6G(SCH_1):PAGE190',
 TOLERANCE='20%',
 MATERIAL='EMPTY',
 PHYS_PAGE='215',
 XY='(-1775,3075)',
 ROT='0',
 VER='1',
 PACK_TYPE='SMLF',
 LOCATION='PC340',
 CDS_LIB='pure_quanta',
 CDS_PART_NAME='Q_CAPP_SMLF-470UF,2.5V,20%,EMPTY,CH747LM8825',
 VOLTAGE='2.5V',
 PART_NUMBER='CH747LM8825',
 VALUE='470UF',
 PRIM_FILE='./archive_libs/logical/q_capp/chips/chips.prt';

PART_NAME
 PC341_1 'Q_CAP_C0805-22UF,4V,20%,X6S,CH622KMEA03':;

SECTION_NUMBER 1
 '@T6G_MB_LIB.T6G(SCH_1):PAGE190_I80@PURE_QUANTA.Q_CAP(CHIPS)':
 C_PATH='@t6g_mb_lib.t6g(sch_1):page190_i80@pure_quanta.q_cap(chips)',
 P_PATH='@t6g_mb_lib.t6g(sch_1):page215_i80@pure_quanta.q_cap(chips)',
 PATH='I80',
 DRAWING='@T6G_MB_LIB.T6G(SCH_1):PAGE190',
 TOLERANCE='20%',
 MATERIAL='X6S',
 PHYS_PAGE='215',
 XY='(-1575,4575)',
 ROT='0',
 VER='1',
 PACK_TYPE='C0805',
 LOCATION='PC341_1',
 CDS_LIB='pure_quanta',
 CDS_PART_NAME='Q_CAP_C0805-22UF,4V,20%,X6S,CH622KMEA03',
 VOLTAGE='4V',
 PART_NUMBER='CH622KMEA03',
 VALUE='22UF',
 PRIM_FILE='./archive_libs/logical/q_cap/chips/chips.prt';

PART_NAME
 PC342_2 'Q_CAP_C0805-22UF,4V,20%,X6S,CH622KMEA03':;

SECTION_NUMBER 1
 '@T6G_MB_LIB.T6G(SCH_1):PAGE190_I62@PURE_QUANTA.Q_CAP(CHIPS)':
 C_PATH='@t6g_mb_lib.t6g(sch_1):page190_i62@pure_quanta.q_cap(chips)',
 P_PATH='@t6g_mb_lib.t6g(sch_1):page215_i62@pure_quanta.q_cap(chips)',
 PATH='I62',
 DRAWING='@T6G_MB_LIB.T6G(SCH_1):PAGE190',
 TOLERANCE='20%',
 MATERIAL='X6S',
 PHYS_PAGE='215',
 XY='(-1275,1800)',
 ROT='0',
 VER='1',
 PACK_TYPE='C0805',
 LOCATION='PC342_2',
 CDS_LIB='pure_quanta',
 CDS_PART_NAME='Q_CAP_C0805-22UF,4V,20%,X6S,CH622KMEA03',
 VOLTAGE='4V',
 PART_NUMBER='CH622KMEA03',
 VALUE='22UF',
 PRIM_FILE='./archive_libs/logical/q_cap/chips/chips.prt';

PART_NAME
 PC343 'Q_CAPP_SMLF-470UF,2.5V,20%,SPCAP,CH747LM8825':;

SECTION_NUMBER 1
 '@T6G_MB_LIB.T6G(SCH_1):PAGE190_I66@PURE_QUANTA.Q_CAPP(CHIPS)':
 C_PATH='@t6g_mb_lib.t6g(sch_1):page190_i66@pure_quanta.q_capp(chips)',
 P_PATH='@t6g_mb_lib.t6g(sch_1):page215_i66@pure_quanta.q_capp(chips)',
 PATH='I66',
 DRAWING='@T6G_MB_LIB.T6G(SCH_1):PAGE190',
 TOLERANCE='20%',
 MATERIAL='SPCAP',
 PHYS_PAGE='215',
 XY='(-1450,3075)',
 ROT='0',
 VER='1',
 PACK_TYPE='SMLF',
 LOCATION='PC343',
 CDS_LIB='pure_quanta',
 CDS_PART_NAME='Q_CAPP_SMLF-470UF,2.5V,20%,SPCAP,CH747LM8825',
 VOLTAGE='2.5V',
 PART_NUMBER='CH747LM8825',
 VALUE='470UF',
 PRIM_FILE='./archive_libs/logical/q_capp/chips/chips.prt';

PART_NAME
 PC344_1 'Q_CAP_C0805-22UF,4V,20%,X6S,CH622KMEA03':;

SECTION_NUMBER 1
 '@T6G_MB_LIB.T6G(SCH_1):PAGE190_I81@PURE_QUANTA.Q_CAP(CHIPS)':
 C_PATH='@t6g_mb_lib.t6g(sch_1):page190_i81@pure_quanta.q_cap(chips)',
 P_PATH='@t6g_mb_lib.t6g(sch_1):page215_i81@pure_quanta.q_cap(chips)',
 PATH='I81',
 DRAWING='@T6G_MB_LIB.T6G(SCH_1):PAGE190',
 TOLERANCE='20%',
 MATERIAL='X6S',
 PHYS_PAGE='215',
 XY='(-1150,4575)',
 ROT='0',
 VER='1',
 PACK_TYPE='C0805',
 LOCATION='PC344_1',
 CDS_LIB='pure_quanta',
 CDS_PART_NAME='Q_CAP_C0805-22UF,4V,20%,X6S,CH622KMEA03',
 VOLTAGE='4V',
 PART_NUMBER='CH622KMEA03',
 VALUE='22UF',
 PRIM_FILE='./archive_libs/logical/q_cap/chips/chips.prt';

PART_NAME
 PC345_9 'Q_CAP_0402-0.1UF,25V,10%,X7R,CH4104K1B00':;

SECTION_NUMBER 1
 '@T6G_MB_LIB.T6G(SCH_1):PAGE191_I2@PURE_QUANTA.Q_CAP(CHIPS)':
 C_PATH='@t6g_mb_lib.t6g(sch_1):page191_i2@pure_quanta.q_cap(chips)',
 P_PATH='@t6g_mb_lib.t6g(sch_1):page216_i2@pure_quanta.q_cap(chips)',
 PATH='I2',
 DRAWING='@T6G_MB_LIB.T6G(SCH_1):PAGE191',
 TOLERANCE='10%',
 MATERIAL='X7R',
 PHYS_PAGE='216',
 XY='(-7675,4225)',
 ROT='0',
 VER='1',
 PACK_TYPE='0402',
 LOCATION='PC345_9',
 CDS_LIB='pure_quanta',
 CDS_PART_NAME='Q_CAP_0402-0.1UF,25V,10%,X7R,CH4104K1B00',
 VOLTAGE='25V',
 PART_NUMBER='CH4104K1B00',
 VALUE='0.1UF',
 PRIM_FILE='./archive_libs/logical/q_cap/chips/chips.prt';

PART_NAME
 PC346 'Q_CAP_C0402-2.2UF,10V,10%,X6S,CH5222KEB01':;

SECTION_NUMBER 1
 '@T6G_MB_LIB.T6G(SCH_1):PAGE191_I13@PURE_QUANTA.Q_CAP(CHIPS)':
 C_PATH='@t6g_mb_lib.t6g(sch_1):page191_i13@pure_quanta.q_cap(chips)',
 P_PATH='@t6g_mb_lib.t6g(sch_1):page216_i13@pure_quanta.q_cap(chips)',
 PATH='I13',
 DRAWING='@T6G_MB_LIB.T6G(SCH_1):PAGE191',
 TOLERANCE='10%',
 MATERIAL='X6S',
 PHYS_PAGE='216',
 XY='(-7350,4850)',
 ROT='0',
 VER='1',
 PACK_TYPE='C0402',
 LOCATION='PC346',
 CDS_LIB='pure_quanta',
 CDS_PART_NAME='Q_CAP_C0402-2.2UF,10V,10%,X6S,CH5222KEB01',
 VOLTAGE='10V',
 PART_NUMBER='CH5222KEB01',
 VALUE='2.2UF',
 PRIM_FILE='./archive_libs/logical/q_cap/chips/chips.prt';

PART_NAME
 PC347_SOP1_3 'Q_CAP_C0402-2.2UF,10V,10%,X6S,CH5222KEB01':;

SECTION_NUMBER 1
 '@T6G_MB_LIB.T6G(SCH_1):PAGE191_I18@PURE_QUANTA.Q_CAP(CHIPS)':
 C_PATH='@t6g_mb_lib.t6g(sch_1):page191_i18@pure_quanta.q_cap(chips)',
 P_PATH='@t6g_mb_lib.t6g(sch_1):page216_i18@pure_quanta.q_cap(chips)',
 PATH='I18',
 DRAWING='@T6G_MB_LIB.T6G(SCH_1):PAGE191',
 TOLERANCE='10%',
 MATERIAL='X6S',
 PHYS_PAGE='216',
 XY='(-7000,5425)',
 ROT='0',
 VER='1',
 PACK_TYPE='C0402',
 LOCATION='PC347_SOP1_3',
 CDS_LIB='pure_quanta',
 CDS_PART_NAME='Q_CAP_C0402-2.2UF,10V,10%,X6S,CH5222KEB01',
 VOLTAGE='10V',
 PART_NUMBER='CH5222KEB01',
 VALUE='2.2UF',
 PRIM_FILE='./archive_libs/logical/q_cap/chips/chips.prt';

PART_NAME
 PC348_3 'Q_CAP_0402-0.1UF,25V,10%,X7R,CH4104K1B00':;

SECTION_NUMBER 1
 '@T6G_MB_LIB.T6G(SCH_1):PAGE191_I19@PURE_QUANTA.Q_CAP(CHIPS)':
 C_PATH='@t6g_mb_lib.t6g(sch_1):page191_i19@pure_quanta.q_cap(chips)',
 P_PATH='@t6g_mb_lib.t6g(sch_1):page216_i19@pure_quanta.q_cap(chips)',
 PATH='I19',
 DRAWING='@T6G_MB_LIB.T6G(SCH_1):PAGE191',
 TOLERANCE='10%',
 MATERIAL='X7R',
 PHYS_PAGE='216',
 XY='(-5050,5375)',
 ROT='0',
 VER='1',
 PACK_TYPE='0402',
 LOCATION='PC348_3',
 CDS_LIB='pure_quanta',
 CDS_PART_NAME='Q_CAP_0402-0.1UF,25V,10%,X7R,CH4104K1B00',
 VOLTAGE='25V',
 PART_NUMBER='CH4104K1B00',
 VALUE='0.1UF',
 PRIM_FILE='./archive_libs/logical/q_cap/chips/chips.prt';

PART_NAME
 PC349_3 'Q_CAP_C0402-1UF,25V,10%,X6S,CH5104KEB02':;

SECTION_NUMBER 1
 '@T6G_MB_LIB.T6G(SCH_1):PAGE191_I20@PURE_QUANTA.Q_CAP(CHIPS)':
 C_PATH='@t6g_mb_lib.t6g(sch_1):page191_i20@pure_quanta.q_cap(chips)',
 P_PATH='@t6g_mb_lib.t6g(sch_1):page216_i20@pure_quanta.q_cap(chips)',
 PATH='I20',
 DRAWING='@T6G_MB_LIB.T6G(SCH_1):PAGE191',
 TOLERANCE='10%',
 MATERIAL='X6S',
 PHYS_PAGE='216',
 XY='(-4650,5375)',
 ROT='0',
 VER='1',
 PACK_TYPE='C0402',
 LOCATION='PC349_3',
 CDS_LIB='pure_quanta',
 CDS_PART_NAME='Q_CAP_C0402-1UF,25V,10%,X6S,CH5104KEB02',
 VOLTAGE='25V',
 PART_NUMBER='CH5104KEB02',
 VALUE='1UF',
 PRIM_FILE='./archive_libs/logical/q_cap/chips/chips.prt';

PART_NAME
 PC350_3 'Q_CAP_C0805-22UF,16V,20%,X6S,CH6223MEA01':;

SECTION_NUMBER 1
 '@T6G_MB_LIB.T6G(SCH_1):PAGE191_I22@PURE_QUANTA.Q_CAP(CHIPS)':
 C_PATH='@t6g_mb_lib.t6g(sch_1):page191_i22@pure_quanta.q_cap(chips)',
 P_PATH='@t6g_mb_lib.t6g(sch_1):page216_i22@pure_quanta.q_cap(chips)',
 PATH='I22',
 DRAWING='@T6G_MB_LIB.T6G(SCH_1):PAGE191',
 TOLERANCE='20%',
 MATERIAL='X6S',
 PHYS_PAGE='216',
 XY='(-4325,5375)',
 ROT='0',
 VER='1',
 PACK_TYPE='C0805',
 LOCATION='PC350_3',
 CDS_LIB='pure_quanta',
 CDS_PART_NAME='Q_CAP_C0805-22UF,16V,20%,X6S,CH6223MEA01',
 VOLTAGE='16V',
 PART_NUMBER='CH6223MEA01',
 VALUE='22UF',
 PRIM_FILE='./archive_libs/logical/q_cap/chips/chips.prt';

PART_NAME
 PC351_3 'Q_CAP_C0805-22UF,16V,20%,X6S,CH6223MEA01':;

SECTION_NUMBER 1
 '@T6G_MB_LIB.T6G(SCH_1):PAGE191_I31@PURE_QUANTA.Q_CAP(CHIPS)':
 C_PATH='@t6g_mb_lib.t6g(sch_1):page191_i31@pure_quanta.q_cap(chips)',
 P_PATH='@t6g_mb_lib.t6g(sch_1):page216_i31@pure_quanta.q_cap(chips)',
 PATH='I31',
 DRAWING='@T6G_MB_LIB.T6G(SCH_1):PAGE191',
 TOLERANCE='20%',
 MATERIAL='X6S',
 PHYS_PAGE='216',
 XY='(-4000,5375)',
 ROT='0',
 VER='1',
 PACK_TYPE='C0805',
 LOCATION='PC351_3',
 CDS_LIB='pure_quanta',
 CDS_PART_NAME='Q_CAP_C0805-22UF,16V,20%,X6S,CH6223MEA01',
 VOLTAGE='16V',
 PART_NUMBER='CH6223MEA01',
 VALUE='22UF',
 PRIM_FILE='./archive_libs/logical/q_cap/chips/chips.prt';

PART_NAME
 PC352_3 'Q_CAP_C0805-22UF,16V,20%,X6S,CH6223MEA01':;

SECTION_NUMBER 1
 '@T6G_MB_LIB.T6G(SCH_1):PAGE191_I32@PURE_QUANTA.Q_CAP(CHIPS)':
 C_PATH='@t6g_mb_lib.t6g(sch_1):page191_i32@pure_quanta.q_cap(chips)',
 P_PATH='@t6g_mb_lib.t6g(sch_1):page216_i32@pure_quanta.q_cap(chips)',
 PATH='I32',
 DRAWING='@T6G_MB_LIB.T6G(SCH_1):PAGE191',
 TOLERANCE='20%',
 MATERIAL='X6S',
 PHYS_PAGE='216',
 XY='(-3700,5375)',
 ROT='0',
 VER='1',
 PACK_TYPE='C0805',
 LOCATION='PC352_3',
 CDS_LIB='pure_quanta',
 CDS_PART_NAME='Q_CAP_C0805-22UF,16V,20%,X6S,CH6223MEA01',
 VOLTAGE='16V',
 PART_NUMBER='CH6223MEA01',
 VALUE='22UF',
 PRIM_FILE='./archive_libs/logical/q_cap/chips/chips.prt';

PART_NAME
 PC353 'Q_CAP_0402-0.22UF,16V,10%,X7R,CH4223K1B00':;

SECTION_NUMBER 1
 '@T6G_MB_LIB.T6G(SCH_1):PAGE191_I33@PURE_QUANTA.Q_CAP(CHIPS)':
 C_PATH='@t6g_mb_lib.t6g(sch_1):page191_i33@pure_quanta.q_cap(chips)',
 P_PATH='@t6g_mb_lib.t6g(sch_1):page216_i33@pure_quanta.q_cap(chips)',
 PATH='I33',
 DRAWING='@T6G_MB_LIB.T6G(SCH_1):PAGE191',
 TOLERANCE='10%',
 MATERIAL='X7R',
 PHYS_PAGE='216',
 XY='(-3500,4725)',
 ROT='0',
 VER='1',
 PACK_TYPE='0402',
 LOCATION='PC353',
 CDS_LIB='pure_quanta',
 CDS_PART_NAME='Q_CAP_0402-0.22UF,16V,10%,X7R,CH4223K1B00',
 VOLTAGE='16V',
 PART_NUMBER='CH4223K1B00',
 VALUE='0.22UF',
 PRIM_FILE='./archive_libs/logical/q_cap/chips/chips.prt';

PART_NAME
 PC353_3 'Q_CAP_C0805-22UF,16V,20%,X6S,CH6223MEA01':;

SECTION_NUMBER 1
 '@T6G_MB_LIB.T6G(SCH_1):PAGE191_I34@PURE_QUANTA.Q_CAP(CHIPS)':
 C_PATH='@t6g_mb_lib.t6g(sch_1):page191_i34@pure_quanta.q_cap(chips)',
 P_PATH='@t6g_mb_lib.t6g(sch_1):page216_i34@pure_quanta.q_cap(chips)',
 PATH='I34',
 DRAWING='@T6G_MB_LIB.T6G(SCH_1):PAGE191',
 TOLERANCE='20%',
 MATERIAL='X6S',
 PHYS_PAGE='216',
 XY='(-3325,5375)',
 ROT='0',
 VER='1',
 PACK_TYPE='C0805',
 LOCATION='PC353_3',
 CDS_LIB='pure_quanta',
 CDS_PART_NAME='Q_CAP_C0805-22UF,16V,20%,X6S,CH6223MEA01',
 VOLTAGE='16V',
 PART_NUMBER='CH6223MEA01',
 VALUE='22UF',
 PRIM_FILE='./archive_libs/logical/q_cap/chips/chips.prt';

PART_NAME
 PC354_3 'Q_CAP_C0805-22UF,4V,20%,X6S,CH622KMEA03':;

SECTION_NUMBER 1
 '@T6G_MB_LIB.T6G(SCH_1):PAGE191_I28@PURE_QUANTA.Q_CAP(CHIPS)':
 C_PATH='@t6g_mb_lib.t6g(sch_1):page191_i28@pure_quanta.q_cap(chips)',
 P_PATH='@t6g_mb_lib.t6g(sch_1):page216_i28@pure_quanta.q_cap(chips)',
 PATH='I28',
 DRAWING='@T6G_MB_LIB.T6G(SCH_1):PAGE191',
 TOLERANCE='20%',
 MATERIAL='X6S',
 PHYS_PAGE='216',
 XY='(-1425,4325)',
 ROT='0',
 VER='1',
 PACK_TYPE='C0805',
 LOCATION='PC354_3',
 CDS_LIB='pure_quanta',
 CDS_PART_NAME='Q_CAP_C0805-22UF,4V,20%,X6S,CH622KMEA03',
 VOLTAGE='4V',
 PART_NUMBER='CH622KMEA03',
 VALUE='22UF',
 PRIM_FILE='./archive_libs/logical/q_cap/chips/chips.prt';

PART_NAME
 PC355_3 'Q_CAP_C0805-22UF,4V,20%,X6S,CH622KMEA03':;

SECTION_NUMBER 1
 '@T6G_MB_LIB.T6G(SCH_1):PAGE191_I30@PURE_QUANTA.Q_CAP(CHIPS)':
 C_PATH='@t6g_mb_lib.t6g(sch_1):page191_i30@pure_quanta.q_cap(chips)',
 P_PATH='@t6g_mb_lib.t6g(sch_1):page216_i30@pure_quanta.q_cap(chips)',
 PATH='I30',
 DRAWING='@T6G_MB_LIB.T6G(SCH_1):PAGE191',
 TOLERANCE='20%',
 MATERIAL='X6S',
 PHYS_PAGE='216',
 XY='(-1000,4325)',
 ROT='0',
 VER='1',
 PACK_TYPE='C0805',
 LOCATION='PC355_3',
 CDS_LIB='pure_quanta',
 CDS_PART_NAME='Q_CAP_C0805-22UF,4V,20%,X6S,CH622KMEA03',
 VOLTAGE='4V',
 PART_NUMBER='CH622KMEA03',
 VALUE='22UF',
 PRIM_FILE='./archive_libs/logical/q_cap/chips/chips.prt';

PART_NAME
 PC357 'Q_CAP_0402-0.1UF,25V,10%,X7R,CH4104K1B00':;

SECTION_NUMBER 1
 '@T6G_MB_LIB.T6G(SCH_1):PAGE192_I47@PURE_QUANTA.Q_CAP(CHIPS)':
 C_PATH='@t6g_mb_lib.t6g(sch_1):page192_i47@pure_quanta.q_cap(chips)',
 P_PATH='@t6g_mb_lib.t6g(sch_1):page217_i47@pure_quanta.q_cap(chips)',
 PATH='I47',
 DRAWING='@T6G_MB_LIB.T6G(SCH_1):PAGE192',
 TOLERANCE='10%',
 MATERIAL='X7R',
 PHYS_PAGE='217',
 XY='(-2600,1725)',
 ROT='0',
 VER='1',
 PACK_TYPE='0402',
 LOCATION='PC357',
 CDS_LIB='pure_quanta',
 CDS_PART_NAME='Q_CAP_0402-0.1UF,25V,10%,X7R,CH4104K1B00',
 VOLTAGE='25V',
 PART_NUMBER='CH4104K1B00',
 VALUE='0.1UF',
 PRIM_FILE='./archive_libs/logical/q_cap/chips/chips.prt';

PART_NAME
 PC358 'Q_CAP_0402-3300PF,50V,10%,X7R,TMP_QCH2336K1B12':;

SECTION_NUMBER 1
 '@T6G_MB_LIB.T6G(SCH_1):PAGE192_I79@PURE_QUANTA.Q_CAP(CHIPS)':
 C_PATH='@t6g_mb_lib.t6g(sch_1):page192_i79@pure_quanta.q_cap(chips)',
 P_PATH='@t6g_mb_lib.t6g(sch_1):page217_i79@pure_quanta.q_cap(chips)',
 PATH='I79',
 DRAWING='@T6G_MB_LIB.T6G(SCH_1):PAGE192',
 TOLERANCE='10%',
 MATERIAL='X7R',
 PHYS_PAGE='217',
 XY='(-2075,5050)',
 ROT='0',
 VER='1',
 PACK_TYPE='0402',
 LOCATION='PC358',
 CDS_LIB='pure_quanta',
 CDS_PART_NAME='Q_CAP_0402-3300PF,50V,10%,X7R,TMP_QCH2336K1B12',
 VOLTAGE='50V',
 PART_NUMBER='TMP_QCH2336K1B12',
 VALUE='3300PF',
 PRIM_FILE='./archive_libs/logical/q_cap/chips/chips.prt';

PART_NAME
 PC361 'Q_CAP_0402-3300PF,50V,10%,X7R,TMP_QCH2336K1B12':;

SECTION_NUMBER 1
 '@T6G_MB_LIB.T6G(SCH_1):PAGE192_I67@PURE_QUANTA.Q_CAP(CHIPS)':
 C_PATH='@t6g_mb_lib.t6g(sch_1):page192_i67@pure_quanta.q_cap(chips)',
 P_PATH='@t6g_mb_lib.t6g(sch_1):page217_i67@pure_quanta.q_cap(chips)',
 PATH='I67',
 DRAWING='@T6G_MB_LIB.T6G(SCH_1):PAGE192',
 TOLERANCE='10%',
 MATERIAL='X7R',
 PHYS_PAGE='217',
 XY='(-2025,3950)',
 ROT='0',
 VER='1',
 PACK_TYPE='0402',
 LOCATION='PC361',
 CDS_LIB='pure_quanta',
 CDS_PART_NAME='Q_CAP_0402-3300PF,50V,10%,X7R,TMP_QCH2336K1B12',
 VOLTAGE='50V',
 PART_NUMBER='TMP_QCH2336K1B12',
 VALUE='3300PF',
 PRIM_FILE='./archive_libs/logical/q_cap/chips/chips.prt';

PART_NAME
 PC363 'Q_CAP_0402-1UF,6.3V,10%,X7R,CH5101K1B01':;

SECTION_NUMBER 1
 '@T6G_MB_LIB.T6G(SCH_1):PAGE192_I60@PURE_QUANTA.Q_CAP(CHIPS)':
 C_PATH='@t6g_mb_lib.t6g(sch_1):page192_i60@pure_quanta.q_cap(chips)',
 P_PATH='@t6g_mb_lib.t6g(sch_1):page217_i60@pure_quanta.q_cap(chips)',
 PATH='I60',
 DRAWING='@T6G_MB_LIB.T6G(SCH_1):PAGE192',
 TOLERANCE='10%',
 MATERIAL='X7R',
 PHYS_PAGE='217',
 XY='(-1825,2850)',
 ROT='0',
 VER='2',
 PACK_TYPE='0402',
 LOCATION='PC363',
 CDS_LIB='pure_quanta',
 CDS_PART_NAME='Q_CAP_0402-1UF,6.3V,10%,X7R,CH5101K1B01',
 VOLTAGE='6.3V',
 PART_NUMBER='CH5101K1B01',
 VALUE='1UF',
 PRIM_FILE='./archive_libs/logical/q_cap/chips/chips.prt';

PART_NAME
 PC364 'Q_CAP_0402-0.1UF,25V,10%,X7R,CH4104K1B00':;

SECTION_NUMBER 1
 '@T6G_MB_LIB.T6G(SCH_1):PAGE192_I56@PURE_QUANTA.Q_CAP(CHIPS)':
 C_PATH='@t6g_mb_lib.t6g(sch_1):page192_i56@pure_quanta.q_cap(chips)',
 P_PATH='@t6g_mb_lib.t6g(sch_1):page217_i56@pure_quanta.q_cap(chips)',
 PATH='I56',
 DRAWING='@T6G_MB_LIB.T6G(SCH_1):PAGE192',
 TOLERANCE='10%',
 MATERIAL='X7R',
 PHYS_PAGE='217',
 XY='(-1450,1525)',
 ROT='0',
 VER='1',
 PACK_TYPE='0402',
 LOCATION='PC364',
 CDS_LIB='pure_quanta',
 CDS_PART_NAME='Q_CAP_0402-0.1UF,25V,10%,X7R,CH4104K1B00',
 VOLTAGE='25V',
 PART_NUMBER='CH4104K1B00',
 VALUE='0.1UF',
 PRIM_FILE='./archive_libs/logical/q_cap/chips/chips.prt';

PART_NAME
 PC365 'Q_CAP_C0402-1UF,16V,10%,X6S,CH5103KEB01':;

SECTION_NUMBER 1
 '@T6G_MB_LIB.T6G(SCH_1):PAGE192_I99@PURE_QUANTA.Q_CAP(CHIPS)':
 C_PATH='@t6g_mb_lib.t6g(sch_1):page192_i99@pure_quanta.q_cap(chips)',
 P_PATH='@t6g_mb_lib.t6g(sch_1):page217_i99@pure_quanta.q_cap(chips)',
 PATH='I99',
 DRAWING='@T6G_MB_LIB.T6G(SCH_1):PAGE192',
 TOLERANCE='10%',
 MATERIAL='X6S',
 PHYS_PAGE='217',
 XY='(850,7050)',
 ROT='0',
 VER='1',
 PACK_TYPE='C0402',
 LOCATION='PC365',
 CDS_LIB='pure_quanta',
 CDS_PART_NAME='Q_CAP_C0402-1UF,16V,10%,X6S,CH5103KEB01',
 VOLTAGE='16V',
 PART_NUMBER='CH5103KEB01',
 VALUE='1UF',
 PRIM_FILE='./archive_libs/logical/q_cap/chips/chips.prt';

PART_NAME
 PC366 'Q_CAP_C0402-10UF,6.3V,20%,X6S,CH6101MEB03':;

SECTION_NUMBER 1
 '@T6G_MB_LIB.T6G(SCH_1):PAGE192_I97@PURE_QUANTA.Q_CAP(CHIPS)':
 C_PATH='@t6g_mb_lib.t6g(sch_1):page192_i97@pure_quanta.q_cap(chips)',
 P_PATH='@t6g_mb_lib.t6g(sch_1):page217_i97@pure_quanta.q_cap(chips)',
 PATH='I97',
 DRAWING='@T6G_MB_LIB.T6G(SCH_1):PAGE192',
 TOLERANCE='20%',
 MATERIAL='X6S',
 PHYS_PAGE='217',
 XY='(850,6575)',
 ROT='0',
 VER='1',
 PACK_TYPE='C0402',
 LOCATION='PC366',
 CDS_LIB='pure_quanta',
 CDS_PART_NAME='Q_CAP_C0402-10UF,6.3V,20%,X6S,CH6101MEB03',
 VOLTAGE='6.3V',
 PART_NUMBER='CH6101MEB03',
 VALUE='10UF',
 PRIM_FILE='./archive_libs/logical/q_cap/chips/chips.prt';

PART_NAME
 PC367 'Q_CAP_0402-470PF,50V,10%,X7R,TMP_QCH14706KB18':;

SECTION_NUMBER 1
 '@T6G_MB_LIB.T6G(SCH_1):PAGE192_I75@PURE_QUANTA.Q_CAP(CHIPS)':
 C_PATH='@t6g_mb_lib.t6g(sch_1):page192_i75@pure_quanta.q_cap(chips)',
 P_PATH='@t6g_mb_lib.t6g(sch_1):page217_i75@pure_quanta.q_cap(chips)',
 PATH='I75',
 DRAWING='@T6G_MB_LIB.T6G(SCH_1):PAGE192',
 TOLERANCE='10%',
 MATERIAL='X7R',
 PHYS_PAGE='217',
 XY='(850,2425)',
 ROT='0',
 VER='1',
 PACK_TYPE='0402',
 LOCATION='PC367',
 CDS_LIB='pure_quanta',
 CDS_PART_NAME='Q_CAP_0402-470PF,50V,10%,X7R,TMP_QCH14706KB18',
 VOLTAGE='50V',
 PART_NUMBER='TMP_QCH14706KB18',
 VALUE='470PF',
 PRIM_FILE='./archive_libs/logical/q_cap/chips/chips.prt';

PART_NAME
 PC368 'Q_CAP_0402-470PF,50V,10%,X7R,TMP_QCH14706KB18':;

SECTION_NUMBER 1
 '@T6G_MB_LIB.T6G(SCH_1):PAGE192_I73@PURE_QUANTA.Q_CAP(CHIPS)':
 C_PATH='@t6g_mb_lib.t6g(sch_1):page192_i73@pure_quanta.q_cap(chips)',
 P_PATH='@t6g_mb_lib.t6g(sch_1):page217_i73@pure_quanta.q_cap(chips)',
 PATH='I73',
 DRAWING='@T6G_MB_LIB.T6G(SCH_1):PAGE192',
 TOLERANCE='10%',
 MATERIAL='X7R',
 PHYS_PAGE='217',
 XY='(850,1850)',
 ROT='0',
 VER='1',
 PACK_TYPE='0402',
 LOCATION='PC368',
 CDS_LIB='pure_quanta',
 CDS_PART_NAME='Q_CAP_0402-470PF,50V,10%,X7R,TMP_QCH14706KB18',
 VOLTAGE='50V',
 PART_NUMBER='TMP_QCH14706KB18',
 VALUE='470PF',
 PRIM_FILE='./archive_libs/logical/q_cap/chips/chips.prt';

PART_NAME
 PC369 'Q_CAP_C0402-2.2UF,10V,10%,X6S,CH5222KEB01':;

SECTION_NUMBER 1
 '@T6G_MB_LIB.T6G(SCH_1):PAGE193_I23@PURE_QUANTA.Q_CAP(CHIPS)':
 C_PATH='@t6g_mb_lib.t6g(sch_1):page193_i23@pure_quanta.q_cap(chips)',
 P_PATH='@t6g_mb_lib.t6g(sch_1):page218_i23@pure_quanta.q_cap(chips)',
 PATH='I23',
 DRAWING='@T6G_MB_LIB.T6G(SCH_1):PAGE193',
 TOLERANCE='10%',
 MATERIAL='X6S',
 PHYS_PAGE='218',
 XY='(-8575,5050)',
 ROT='0',
 VER='1',
 PACK_TYPE='C0402',
 LOCATION='PC369',
 CDS_LIB='pure_quanta',
 CDS_PART_NAME='Q_CAP_C0402-2.2UF,10V,10%,X6S,CH5222KEB01',
 VOLTAGE='10V',
 PART_NUMBER='CH5222KEB01',
 VALUE='2.2UF',
 PRIM_FILE='./archive_libs/logical/q_cap/chips/chips.prt';

PART_NAME
 PC370 'Q_CAP_C0402-2.2UF,10V,10%,X6S,CH5222KEB01':;

SECTION_NUMBER 1
 '@T6G_MB_LIB.T6G(SCH_1):PAGE193_I12@PURE_QUANTA.Q_CAP(CHIPS)':
 C_PATH='@t6g_mb_lib.t6g(sch_1):page193_i12@pure_quanta.q_cap(chips)',
 P_PATH='@t6g_mb_lib.t6g(sch_1):page218_i12@pure_quanta.q_cap(chips)',
 PATH='I12',
 DRAWING='@T6G_MB_LIB.T6G(SCH_1):PAGE193',
 TOLERANCE='10%',
 MATERIAL='X6S',
 PHYS_PAGE='218',
 XY='(-8475,2400)',
 ROT='0',
 VER='1',
 PACK_TYPE='C0402',
 LOCATION='PC370',
 CDS_LIB='pure_quanta',
 CDS_PART_NAME='Q_CAP_C0402-2.2UF,10V,10%,X6S,CH5222KEB01',
 VOLTAGE='10V',
 PART_NUMBER='CH5222KEB01',
 VALUE='2.2UF',
 PRIM_FILE='./archive_libs/logical/q_cap/chips/chips.prt';

PART_NAME
 PC371_C1P1_1 'Q_CAP_C0402-2.2UF,10V,10%,X6S,CH5222KEB01':;

SECTION_NUMBER 1
 '@T6G_MB_LIB.T6G(SCH_1):PAGE193_I29@PURE_QUANTA.Q_CAP(CHIPS)':
 C_PATH='@t6g_mb_lib.t6g(sch_1):page193_i29@pure_quanta.q_cap(chips)',
 P_PATH='@t6g_mb_lib.t6g(sch_1):page218_i29@pure_quanta.q_cap(chips)',
 PATH='I29',
 DRAWING='@T6G_MB_LIB.T6G(SCH_1):PAGE193',
 TOLERANCE='10%',
 MATERIAL='X6S',
 PHYS_PAGE='218',
 XY='(-8225,5625)',
 ROT='0',
 VER='1',
 PACK_TYPE='C0402',
 LOCATION='PC371_C1P1_1',
 CDS_LIB='pure_quanta',
 CDS_PART_NAME='Q_CAP_C0402-2.2UF,10V,10%,X6S,CH5222KEB01',
 VOLTAGE='10V',
 PART_NUMBER='CH5222KEB01',
 VALUE='2.2UF',
 PRIM_FILE='./archive_libs/logical/q_cap/chips/chips.prt';

PART_NAME
 PC372_C1P1_2 'Q_CAP_C0402-2.2UF,10V,10%,X6S,CH5222KEB01':;

SECTION_NUMBER 1
 '@T6G_MB_LIB.T6G(SCH_1):PAGE193_I15@PURE_QUANTA.Q_CAP(CHIPS)':
 C_PATH='@t6g_mb_lib.t6g(sch_1):page193_i15@pure_quanta.q_cap(chips)',
 P_PATH='@t6g_mb_lib.t6g(sch_1):page218_i15@pure_quanta.q_cap(chips)',
 PATH='I15',
 DRAWING='@T6G_MB_LIB.T6G(SCH_1):PAGE193',
 TOLERANCE='10%',
 MATERIAL='X6S',
 PHYS_PAGE='218',
 XY='(-8125,2975)',
 ROT='0',
 VER='1',
 PACK_TYPE='C0402',
 LOCATION='PC372_C1P1_2',
 CDS_LIB='pure_quanta',
 CDS_PART_NAME='Q_CAP_C0402-2.2UF,10V,10%,X6S,CH5222KEB01',
 VOLTAGE='10V',
 PART_NUMBER='CH5222KEB01',
 VALUE='2.2UF',
 PRIM_FILE='./archive_libs/logical/q_cap/chips/chips.prt';

PART_NAME
 PC373_2 'Q_CAP_0402-0.1UF,25V,10%,X7R,CH4104K1B00':;

SECTION_NUMBER 1
 '@T6G_MB_LIB.T6G(SCH_1):PAGE193_I2@PURE_QUANTA.Q_CAP(CHIPS)':
 C_PATH='@t6g_mb_lib.t6g(sch_1):page193_i2@pure_quanta.q_cap(chips)',
 P_PATH='@t6g_mb_lib.t6g(sch_1):page218_i2@pure_quanta.q_cap(chips)',
 PATH='I2',
 DRAWING='@T6G_MB_LIB.T6G(SCH_1):PAGE193',
 TOLERANCE='10%',
 MATERIAL='X7R',
 PHYS_PAGE='218',
 XY='(-9250,1600)',
 ROT='0',
 VER='1',
 PACK_TYPE='0402',
 LOCATION='PC373_2',
 CDS_LIB='pure_quanta',
 CDS_PART_NAME='Q_CAP_0402-0.1UF,25V,10%,X7R,CH4104K1B00',
 VOLTAGE='25V',
 PART_NUMBER='CH4104K1B00',
 VALUE='0.1UF',
 PRIM_FILE='./archive_libs/logical/q_cap/chips/chips.prt';

PART_NAME
 PC374_1 'Q_CAP_0402-0.1UF,25V,10%,X7R,CH4104K1B00':;

SECTION_NUMBER 1
 '@T6G_MB_LIB.T6G(SCH_1):PAGE193_I11@PURE_QUANTA.Q_CAP(CHIPS)':
 C_PATH='@t6g_mb_lib.t6g(sch_1):page193_i11@pure_quanta.q_cap(chips)',
 P_PATH='@t6g_mb_lib.t6g(sch_1):page218_i11@pure_quanta.q_cap(chips)',
 PATH='I11',
 DRAWING='@T6G_MB_LIB.T6G(SCH_1):PAGE193',
 TOLERANCE='10%',
 MATERIAL='X7R',
 PHYS_PAGE='218',
 XY='(-9225,4225)',
 ROT='0',
 VER='1',
 PACK_TYPE='0402',
 LOCATION='PC374_1',
 CDS_LIB='pure_quanta',
 CDS_PART_NAME='Q_CAP_0402-0.1UF,25V,10%,X7R,CH4104K1B00',
 VOLTAGE='25V',
 PART_NUMBER='CH4104K1B00',
 VALUE='0.1UF',
 PRIM_FILE='./archive_libs/logical/q_cap/chips/chips.prt';

PART_NAME
 PC375 'Q_CAP_0402-0.1UF,25V,10%,X7R,CH4104K1B00':;

SECTION_NUMBER 1
 '@T6G_MB_LIB.T6G(SCH_1):PAGE193_I83@PURE_QUANTA.Q_CAP(CHIPS)':
 C_PATH='@t6g_mb_lib.t6g(sch_1):page193_i83@pure_quanta.q_cap(chips)',
 P_PATH='@t6g_mb_lib.t6g(sch_1):page218_i83@pure_quanta.q_cap(chips)',
 PATH='I83',
 DRAWING='@T6G_MB_LIB.T6G(SCH_1):PAGE193',
 TOLERANCE='10%',
 MATERIAL='X7R',
 PHYS_PAGE='218',
 XY='(-2875,5550)',
 ROT='0',
 VER='1',
 PACK_TYPE='0402',
 LOCATION='PC375',
 CDS_LIB='pure_quanta',
 CDS_PART_NAME='Q_CAP_0402-0.1UF,25V,10%,X7R,CH4104K1B00',
 VOLTAGE='25V',
 PART_NUMBER='CH4104K1B00',
 VALUE='0.1UF',
 PRIM_FILE='./archive_libs/logical/q_cap/chips/chips.prt';

PART_NAME
 PC375_1 'Q_CAP_0402-0.1UF,25V,10%,X7R,CH4104K1B00':;

SECTION_NUMBER 1
 '@T6G_MB_LIB.T6G(SCH_1):PAGE193_I50@PURE_QUANTA.Q_CAP(CHIPS)':
 C_PATH='@t6g_mb_lib.t6g(sch_1):page193_i50@pure_quanta.q_cap(chips)',
 P_PATH='@t6g_mb_lib.t6g(sch_1):page218_i50@pure_quanta.q_cap(chips)',
 PATH='I50',
 DRAWING='@T6G_MB_LIB.T6G(SCH_1):PAGE193',
 TOLERANCE='10%',
 MATERIAL='X7R',
 PHYS_PAGE='218',
 XY='(-6025,5500)',
 ROT='0',
 VER='1',
 PACK_TYPE='0402',
 LOCATION='PC375_1',
 CDS_LIB='pure_quanta',
 CDS_PART_NAME='Q_CAP_0402-0.1UF,25V,10%,X7R,CH4104K1B00',
 VOLTAGE='25V',
 PART_NUMBER='CH4104K1B00',
 VALUE='0.1UF',
 PRIM_FILE='./archive_libs/logical/q_cap/chips/chips.prt';

PART_NAME
 PC376_2 'Q_CAP_0402-0.1UF,25V,10%,X7R,CH4104K1B00':;

SECTION_NUMBER 1
 '@T6G_MB_LIB.T6G(SCH_1):PAGE193_I34@PURE_QUANTA.Q_CAP(CHIPS)':
 C_PATH='@t6g_mb_lib.t6g(sch_1):page193_i34@pure_quanta.q_cap(chips)',
 P_PATH='@t6g_mb_lib.t6g(sch_1):page218_i34@pure_quanta.q_cap(chips)',
 PATH='I34',
 DRAWING='@T6G_MB_LIB.T6G(SCH_1):PAGE193',
 TOLERANCE='10%',
 MATERIAL='X7R',
 PHYS_PAGE='218',
 XY='(-6000,2875)',
 ROT='0',
 VER='1',
 PACK_TYPE='0402',
 LOCATION='PC376_2',
 CDS_LIB='pure_quanta',
 CDS_PART_NAME='Q_CAP_0402-0.1UF,25V,10%,X7R,CH4104K1B00',
 VOLTAGE='25V',
 PART_NUMBER='CH4104K1B00',
 VALUE='0.1UF',
 PRIM_FILE='./archive_libs/logical/q_cap/chips/chips.prt';

PART_NAME
 PC377_1 'Q_CAP_C0402-1UF,25V,10%,X6S,CH5104KEB02':;

SECTION_NUMBER 1
 '@T6G_MB_LIB.T6G(SCH_1):PAGE193_I53@PURE_QUANTA.Q_CAP(CHIPS)':
 C_PATH='@t6g_mb_lib.t6g(sch_1):page193_i53@pure_quanta.q_cap(chips)',
 P_PATH='@t6g_mb_lib.t6g(sch_1):page218_i53@pure_quanta.q_cap(chips)',
 PATH='I53',
 DRAWING='@T6G_MB_LIB.T6G(SCH_1):PAGE193',
 TOLERANCE='10%',
 MATERIAL='X6S',
 PHYS_PAGE='218',
 XY='(-5625,5500)',
 ROT='0',
 VER='1',
 PACK_TYPE='C0402',
 LOCATION='PC377_1',
 CDS_LIB='pure_quanta',
 CDS_PART_NAME='Q_CAP_C0402-1UF,25V,10%,X6S,CH5104KEB02',
 VOLTAGE='25V',
 PART_NUMBER='CH5104KEB02',
 VALUE='1UF',
 PRIM_FILE='./archive_libs/logical/q_cap/chips/chips.prt';

PART_NAME
 PC378_2 'Q_CAP_C0402-1UF,25V,10%,X6S,CH5104KEB02':;

SECTION_NUMBER 1
 '@T6G_MB_LIB.T6G(SCH_1):PAGE193_I42@PURE_QUANTA.Q_CAP(CHIPS)':
 C_PATH='@t6g_mb_lib.t6g(sch_1):page193_i42@pure_quanta.q_cap(chips)',
 P_PATH='@t6g_mb_lib.t6g(sch_1):page218_i42@pure_quanta.q_cap(chips)',
 PATH='I42',
 DRAWING='@T6G_MB_LIB.T6G(SCH_1):PAGE193',
 TOLERANCE='10%',
 MATERIAL='X6S',
 PHYS_PAGE='218',
 XY='(-5600,2875)',
 ROT='0',
 VER='1',
 PACK_TYPE='C0402',
 LOCATION='PC378_2',
 CDS_LIB='pure_quanta',
 CDS_PART_NAME='Q_CAP_C0402-1UF,25V,10%,X6S,CH5104KEB02',
 VOLTAGE='25V',
 PART_NUMBER='CH5104KEB02',
 VALUE='1UF',
 PRIM_FILE='./archive_libs/logical/q_cap/chips/chips.prt';

PART_NAME
 PC379_1 'Q_CAP_C0805-22UF,16V,20%,X6S,CH6223MEA01':;

SECTION_NUMBER 1
 '@T6G_MB_LIB.T6G(SCH_1):PAGE193_I54@PURE_QUANTA.Q_CAP(CHIPS)':
 C_PATH='@t6g_mb_lib.t6g(sch_1):page193_i54@pure_quanta.q_cap(chips)',
 P_PATH='@t6g_mb_lib.t6g(sch_1):page218_i54@pure_quanta.q_cap(chips)',
 PATH='I54',
 DRAWING='@T6G_MB_LIB.T6G(SCH_1):PAGE193',
 TOLERANCE='20%',
 MATERIAL='X6S',
 PHYS_PAGE='218',
 XY='(-5225,5500)',
 ROT='0',
 VER='1',
 PACK_TYPE='C0805',
 LOCATION='PC379_1',
 CDS_LIB='pure_quanta',
 CDS_PART_NAME='Q_CAP_C0805-22UF,16V,20%,X6S,CH6223MEA01',
 VOLTAGE='16V',
 PART_NUMBER='CH6223MEA01',
 VALUE='22UF',
 PRIM_FILE='./archive_libs/logical/q_cap/chips/chips.prt';

PART_NAME
 PC380_2 'Q_CAP_C0805-22UF,16V,20%,X6S,CH6223MEA01':;

SECTION_NUMBER 1
 '@T6G_MB_LIB.T6G(SCH_1):PAGE193_I43@PURE_QUANTA.Q_CAP(CHIPS)':
 C_PATH='@t6g_mb_lib.t6g(sch_1):page193_i43@pure_quanta.q_cap(chips)',
 P_PATH='@t6g_mb_lib.t6g(sch_1):page218_i43@pure_quanta.q_cap(chips)',
 PATH='I43',
 DRAWING='@T6G_MB_LIB.T6G(SCH_1):PAGE193',
 TOLERANCE='20%',
 MATERIAL='X6S',
 PHYS_PAGE='218',
 XY='(-5200,2875)',
 ROT='0',
 VER='1',
 PACK_TYPE='C0805',
 LOCATION='PC380_2',
 CDS_LIB='pure_quanta',
 CDS_PART_NAME='Q_CAP_C0805-22UF,16V,20%,X6S,CH6223MEA01',
 VOLTAGE='16V',
 PART_NUMBER='CH6223MEA01',
 VALUE='22UF',
 PRIM_FILE='./archive_libs/logical/q_cap/chips/chips.prt';

PART_NAME
 PC381_1 'Q_CAP_C0805-22UF,16V,20%,X6S,CH6223MEA01':;

SECTION_NUMBER 1
 '@T6G_MB_LIB.T6G(SCH_1):PAGE193_I58@PURE_QUANTA.Q_CAP(CHIPS)':
 C_PATH='@t6g_mb_lib.t6g(sch_1):page193_i58@pure_quanta.q_cap(chips)',
 P_PATH='@t6g_mb_lib.t6g(sch_1):page218_i58@pure_quanta.q_cap(chips)',
 PATH='I58',
 DRAWING='@T6G_MB_LIB.T6G(SCH_1):PAGE193',
 TOLERANCE='20%',
 MATERIAL='X6S',
 PHYS_PAGE='218',
 XY='(-4825,5500)',
 ROT='0',
 VER='1',
 PACK_TYPE='C0805',
 LOCATION='PC381_1',
 CDS_LIB='pure_quanta',
 CDS_PART_NAME='Q_CAP_C0805-22UF,16V,20%,X6S,CH6223MEA01',
 VOLTAGE='16V',
 PART_NUMBER='CH6223MEA01',
 VALUE='22UF',
 PRIM_FILE='./archive_libs/logical/q_cap/chips/chips.prt';

PART_NAME
 PC382_2 'Q_CAP_C0805-22UF,16V,20%,X6S,CH6223MEA01':;

SECTION_NUMBER 1
 '@T6G_MB_LIB.T6G(SCH_1):PAGE193_I46@PURE_QUANTA.Q_CAP(CHIPS)':
 C_PATH='@t6g_mb_lib.t6g(sch_1):page193_i46@pure_quanta.q_cap(chips)',
 P_PATH='@t6g_mb_lib.t6g(sch_1):page218_i46@pure_quanta.q_cap(chips)',
 PATH='I46',
 DRAWING='@T6G_MB_LIB.T6G(SCH_1):PAGE193',
 TOLERANCE='20%',
 MATERIAL='X6S',
 PHYS_PAGE='218',
 XY='(-4800,2875)',
 ROT='0',
 VER='1',
 PACK_TYPE='C0805',
 LOCATION='PC382_2',
 CDS_LIB='pure_quanta',
 CDS_PART_NAME='Q_CAP_C0805-22UF,16V,20%,X6S,CH6223MEA01',
 VOLTAGE='16V',
 PART_NUMBER='CH6223MEA01',
 VALUE='22UF',
 PRIM_FILE='./archive_libs/logical/q_cap/chips/chips.prt';

PART_NAME
 PC383 'Q_CAP_0402-0.22UF,16V,10%,X7R,CH4223K1B00':;

SECTION_NUMBER 1
 '@T6G_MB_LIB.T6G(SCH_1):PAGE193_I57@PURE_QUANTA.Q_CAP(CHIPS)':
 C_PATH='@t6g_mb_lib.t6g(sch_1):page193_i57@pure_quanta.q_cap(chips)',
 P_PATH='@t6g_mb_lib.t6g(sch_1):page218_i57@pure_quanta.q_cap(chips)',
 PATH='I57',
 DRAWING='@T6G_MB_LIB.T6G(SCH_1):PAGE193',
 TOLERANCE='10%',
 MATERIAL='X7R',
 PHYS_PAGE='218',
 XY='(-4475,4825)',
 ROT='0',
 VER='1',
 PACK_TYPE='0402',
 LOCATION='PC383',
 CDS_LIB='pure_quanta',
 CDS_PART_NAME='Q_CAP_0402-0.22UF,16V,10%,X7R,CH4223K1B00',
 VOLTAGE='16V',
 PART_NUMBER='CH4223K1B00',
 VALUE='0.22UF',
 PRIM_FILE='./archive_libs/logical/q_cap/chips/chips.prt';

PART_NAME
 PC384 'Q_CAP_0402-3300PF,50V,10%,X7R,TMP_QCH2336K1B12':;

SECTION_NUMBER 1
 '@T6G_MB_LIB.T6G(SCH_1):PAGE315_I21@PURE_QUANTA.Q_CAP(CHIPS)':
 C_PATH='@t6g_mb_lib.t6g(sch_1):page315_i21@pure_quanta.q_cap(chips)',
 P_PATH='@t6g_mb_lib.t6g(sch_1):page269_i21@pure_quanta.q_cap(chips)',
 PATH='I21',
 DRAWING='@T6G_MB_LIB.T6G(SCH_1):PAGE315',
 TOLERANCE='10%',
 MATERIAL='X7R',
 PHYS_PAGE='269',
 XY='(-125,1050)',
 ROT='0',
 VER='1',
 PACK_TYPE='0402',
 LOCATION='PC384',
 CDS_LIB='pure_quanta',
 CDS_PART_NAME='Q_CAP_0402-3300PF,50V,10%,X7R,TMP_QCH2336K1B12',
 VOLTAGE='50V',
 PART_NUMBER='TMP_QCH2336K1B12',
 VALUE='3300PF',
 PRIM_FILE='./archive_libs/logical/q_cap/chips/chips.prt';

PART_NAME
 PC384_1 'Q_CAP_C0805-22UF,16V,20%,X6S,CH6223MEA01':;

SECTION_NUMBER 1
 '@T6G_MB_LIB.T6G(SCH_1):PAGE193_I60@PURE_QUANTA.Q_CAP(CHIPS)':
 C_PATH='@t6g_mb_lib.t6g(sch_1):page193_i60@pure_quanta.q_cap(chips)',
 P_PATH='@t6g_mb_lib.t6g(sch_1):page218_i60@pure_quanta.q_cap(chips)',
 PATH='I60',
 DRAWING='@T6G_MB_LIB.T6G(SCH_1):PAGE193',
 TOLERANCE='20%',
 MATERIAL='X6S',
 PHYS_PAGE='218',
 XY='(-4450,5500)',
 ROT='0',
 VER='1',
 PACK_TYPE='C0805',
 LOCATION='PC384_1',
 CDS_LIB='pure_quanta',
 CDS_PART_NAME='Q_CAP_C0805-22UF,16V,20%,X6S,CH6223MEA01',
 VOLTAGE='16V',
 PART_NUMBER='CH6223MEA01',
 VALUE='22UF',
 PRIM_FILE='./archive_libs/logical/q_cap/chips/chips.prt';

PART_NAME
 PC385_2 'Q_CAP_C0805-22UF,16V,20%,X6S,CH6223MEA01':;

SECTION_NUMBER 1
 '@T6G_MB_LIB.T6G(SCH_1):PAGE193_I48@PURE_QUANTA.Q_CAP(CHIPS)':
 C_PATH='@t6g_mb_lib.t6g(sch_1):page193_i48@pure_quanta.q_cap(chips)',
 P_PATH='@t6g_mb_lib.t6g(sch_1):page218_i48@pure_quanta.q_cap(chips)',
 PATH='I48',
 DRAWING='@T6G_MB_LIB.T6G(SCH_1):PAGE193',
 TOLERANCE='20%',
 MATERIAL='X6S',
 PHYS_PAGE='218',
 XY='(-4425,2875)',
 ROT='0',
 VER='1',
 PACK_TYPE='C0805',
 LOCATION='PC385_2',
 CDS_LIB='pure_quanta',
 CDS_PART_NAME='Q_CAP_C0805-22UF,16V,20%,X6S,CH6223MEA01',
 VOLTAGE='16V',
 PART_NUMBER='CH6223MEA01',
 VALUE='22UF',
 PRIM_FILE='./archive_libs/logical/q_cap/chips/chips.prt';

PART_NAME
 PC386 'Q_CAP_0402-0.22UF,16V,10%,X7R,CH4223K1B00':;

SECTION_NUMBER 1
 '@T6G_MB_LIB.T6G(SCH_1):PAGE193_I40@PURE_QUANTA.Q_CAP(CHIPS)':
 C_PATH='@t6g_mb_lib.t6g(sch_1):page193_i40@pure_quanta.q_cap(chips)',
 P_PATH='@t6g_mb_lib.t6g(sch_1):page218_i40@pure_quanta.q_cap(chips)',
 PATH='I40',
 DRAWING='@T6G_MB_LIB.T6G(SCH_1):PAGE193',
 TOLERANCE='10%',
 MATERIAL='X7R',
 PHYS_PAGE='218',
 XY='(-4350,2200)',
 ROT='0',
 VER='1',
 PACK_TYPE='0402',
 LOCATION='PC386',
 CDS_LIB='pure_quanta',
 CDS_PART_NAME='Q_CAP_0402-0.22UF,16V,10%,X7R,CH4223K1B00',
 VOLTAGE='16V',
 PART_NUMBER='CH4223K1B00',
 VALUE='0.22UF',
 PRIM_FILE='./archive_libs/logical/q_cap/chips/chips.prt';

PART_NAME
 PC387 'Q_CAPP_SMLF-220UF,4V,20%,SPCAP,CH122KM8801':;

SECTION_NUMBER 1
 '@T6G_MB_LIB.T6G(SCH_1):PAGE193_I66@PURE_QUANTA.Q_CAPP(CHIPS)':
 C_PATH='@t6g_mb_lib.t6g(sch_1):page193_i66@pure_quanta.q_capp(chips)',
 P_PATH='@t6g_mb_lib.t6g(sch_1):page218_i66@pure_quanta.q_capp(chips)',
 PATH='I66',
 DRAWING='@T6G_MB_LIB.T6G(SCH_1):PAGE193',
 TOLERANCE='20%',
 MATERIAL='SPCAP',
 PHYS_PAGE='218',
 XY='(-2450,2925)',
 ROT='0',
 VER='1',
 PACK_TYPE='SMLF',
 LOCATION='PC387',
 CDS_LIB='pure_quanta',
 CDS_PART_NAME='Q_CAPP_SMLF-220UF,4V,20%,SPCAP,CH122KM8801',
 VOLTAGE='4V',
 PART_NUMBER='CH122KM8801',
 VALUE='220UF',
 PRIM_FILE='./archive_libs/logical/q_capp/chips/chips.prt';

PART_NAME
 PC388 'Q_CAPP_SMLF-220UF,4V,20%,SPCAP,CH122KM8801':;

SECTION_NUMBER 1
 '@T6G_MB_LIB.T6G(SCH_1):PAGE193_I67@PURE_QUANTA.Q_CAPP(CHIPS)':
 C_PATH='@t6g_mb_lib.t6g(sch_1):page193_i67@pure_quanta.q_capp(chips)',
 P_PATH='@t6g_mb_lib.t6g(sch_1):page218_i67@pure_quanta.q_capp(chips)',
 PATH='I67',
 DRAWING='@T6G_MB_LIB.T6G(SCH_1):PAGE193',
 TOLERANCE='20%',
 MATERIAL='SPCAP',
 PHYS_PAGE='218',
 XY='(-2125,2925)',
 ROT='0',
 VER='1',
 PACK_TYPE='SMLF',
 LOCATION='PC388',
 CDS_LIB='pure_quanta',
 CDS_PART_NAME='Q_CAPP_SMLF-220UF,4V,20%,SPCAP,CH122KM8801',
 VOLTAGE='4V',
 PART_NUMBER='CH122KM8801',
 VALUE='220UF',
 PRIM_FILE='./archive_libs/logical/q_capp/chips/chips.prt';

PART_NAME
 PC389 'Q_CAPP_SMLF-220UF,4V,20%,SPCAP,CH122KM8801':;

SECTION_NUMBER 1
 '@T6G_MB_LIB.T6G(SCH_1):PAGE193_I73@PURE_QUANTA.Q_CAPP(CHIPS)':
 C_PATH='@t6g_mb_lib.t6g(sch_1):page193_i73@pure_quanta.q_capp(chips)',
 P_PATH='@t6g_mb_lib.t6g(sch_1):page218_i73@pure_quanta.q_capp(chips)',
 PATH='I73',
 DRAWING='@T6G_MB_LIB.T6G(SCH_1):PAGE193',
 TOLERANCE='20%',
 MATERIAL='SPCAP',
 PHYS_PAGE='218',
 XY='(-1800,2925)',
 ROT='0',
 VER='1',
 PACK_TYPE='SMLF',
 LOCATION='PC389',
 CDS_LIB='pure_quanta',
 CDS_PART_NAME='Q_CAPP_SMLF-220UF,4V,20%,SPCAP,CH122KM8801',
 VOLTAGE='4V',
 PART_NUMBER='CH122KM8801',
 VALUE='220UF',
 PRIM_FILE='./archive_libs/logical/q_capp/chips/chips.prt';

PART_NAME
 PC390 'Q_CAPP_SMLF-270UF,16V,20%,OSCON,CC72703MZ11':;

SECTION_NUMBER 1
 '@T6G_MB_LIB.T6G(SCH_1):PAGE193_I93@PURE_QUANTA.Q_CAPP(CHIPS)':
 C_PATH='@t6g_mb_lib.t6g(sch_1):page193_i93@pure_quanta.q_capp(chips)',
 P_PATH='@t6g_mb_lib.t6g(sch_1):page218_i93@pure_quanta.q_capp(chips)',
 PATH='I93',
 DRAWING='@T6G_MB_LIB.T6G(SCH_1):PAGE193',
 TOLERANCE='20%',
 MATERIAL='OSCON',
 PHYS_PAGE='218',
 XY='(-4125,5500)',
 ROT='0',
 VER='1',
 PACK_TYPE='SMLF',
 LOCATION='PC390',
 CDS_LIB='pure_quanta',
 CDS_PART_NAME='Q_CAPP_SMLF-270UF,16V,20%,OSCON,CC72703MZ11',
 VOLTAGE='16V',
 PART_NUMBER='CC72703MZ11',
 VALUE='270UF',
 PRIM_FILE='./archive_libs/logical/q_capp/chips/chips.prt';

PART_NAME
 PC391 'Q_CAPP_SMLF-220UF,4V,20%,SPCAP,CH122KM8801':;

SECTION_NUMBER 1
 '@T6G_MB_LIB.T6G(SCH_1):PAGE193_I74@PURE_QUANTA.Q_CAPP(CHIPS)':
 C_PATH='@t6g_mb_lib.t6g(sch_1):page193_i74@pure_quanta.q_capp(chips)',
 P_PATH='@t6g_mb_lib.t6g(sch_1):page218_i74@pure_quanta.q_capp(chips)',
 PATH='I74',
 DRAWING='@T6G_MB_LIB.T6G(SCH_1):PAGE193',
 TOLERANCE='20%',
 MATERIAL='SPCAP',
 PHYS_PAGE='218',
 XY='(-1500,2925)',
 ROT='0',
 VER='1',
 PACK_TYPE='SMLF',
 LOCATION='PC391',
 CDS_LIB='pure_quanta',
 CDS_PART_NAME='Q_CAPP_SMLF-220UF,4V,20%,SPCAP,CH122KM8801',
 VOLTAGE='4V',
 PART_NUMBER='CH122KM8801',
 VALUE='220UF',
 PRIM_FILE='./archive_libs/logical/q_capp/chips/chips.prt';

PART_NAME
 PC392 'Q_CAP_0402-0.1UF,25V,10%,X7R,CH4104K1B00':;

SECTION_NUMBER 1
 '@T6G_MB_LIB.T6G(SCH_1):PAGE193_I82@PURE_QUANTA.Q_CAP(CHIPS)':
 C_PATH='@t6g_mb_lib.t6g(sch_1):page193_i82@pure_quanta.q_cap(chips)',
 P_PATH='@t6g_mb_lib.t6g(sch_1):page218_i82@pure_quanta.q_cap(chips)',
 PATH='I82',
 DRAWING='@T6G_MB_LIB.T6G(SCH_1):PAGE193',
 TOLERANCE='10%',
 MATERIAL='X7R',
 PHYS_PAGE='218',
 XY='(-2025,4400)',
 ROT='0',
 VER='1',
 PACK_TYPE='0402',
 LOCATION='PC392',
 CDS_LIB='pure_quanta',
 CDS_PART_NAME='Q_CAP_0402-0.1UF,25V,10%,X7R,CH4104K1B00',
 VOLTAGE='25V',
 PART_NUMBER='CH4104K1B00',
 VALUE='0.1UF',
 PRIM_FILE='./archive_libs/logical/q_cap/chips/chips.prt';

PART_NAME
 PC393 'Q_CAPP_SMLF-270UF,16V,20%,OSCON,CC72703MZ11':;

SECTION_NUMBER 1
 '@T6G_MB_LIB.T6G(SCH_1):PAGE193_I92@PURE_QUANTA.Q_CAPP(CHIPS)':
 C_PATH='@t6g_mb_lib.t6g(sch_1):page193_i92@pure_quanta.q_capp(chips)',
 P_PATH='@t6g_mb_lib.t6g(sch_1):page218_i92@pure_quanta.q_capp(chips)',
 PATH='I92',
 DRAWING='@T6G_MB_LIB.T6G(SCH_1):PAGE193',
 TOLERANCE='20%',
 MATERIAL='OSCON',
 PHYS_PAGE='218',
 XY='(-3725,5500)',
 ROT='0',
 VER='1',
 PACK_TYPE='SMLF',
 LOCATION='PC393',
 CDS_LIB='pure_quanta',
 CDS_PART_NAME='Q_CAPP_SMLF-270UF,16V,20%,OSCON,CC72703MZ11',
 VOLTAGE='16V',
 PART_NUMBER='CC72703MZ11',
 VALUE='270UF',
 PRIM_FILE='./archive_libs/logical/q_capp/chips/chips.prt';

PART_NAME
 PC394_2 'Q_CAP_C0805-22UF,4V,20%,X6S,CH622KMEA03':;

SECTION_NUMBER 1
 '@T6G_MB_LIB.T6G(SCH_1):PAGE193_I68@PURE_QUANTA.Q_CAP(CHIPS)':
 C_PATH='@t6g_mb_lib.t6g(sch_1):page193_i68@pure_quanta.q_cap(chips)',
 P_PATH='@t6g_mb_lib.t6g(sch_1):page218_i68@pure_quanta.q_cap(chips)',
 PATH='I68',
 DRAWING='@T6G_MB_LIB.T6G(SCH_1):PAGE193',
 TOLERANCE='20%',
 MATERIAL='X6S',
 PHYS_PAGE='218',
 XY='(-1650,1775)',
 ROT='0',
 VER='1',
 PACK_TYPE='C0805',
 LOCATION='PC394_2',
 CDS_LIB='pure_quanta',
 CDS_PART_NAME='Q_CAP_C0805-22UF,4V,20%,X6S,CH622KMEA03',
 VOLTAGE='4V',
 PART_NUMBER='CH622KMEA03',
 VALUE='22UF',
 PRIM_FILE='./archive_libs/logical/q_cap/chips/chips.prt';

PART_NAME
 PC395_1 'Q_CAP_C0805-22UF,4V,20%,X6S,CH622KMEA03':;

SECTION_NUMBER 1
 '@T6G_MB_LIB.T6G(SCH_1):PAGE193_I85@PURE_QUANTA.Q_CAP(CHIPS)':
 C_PATH='@t6g_mb_lib.t6g(sch_1):page193_i85@pure_quanta.q_cap(chips)',
 P_PATH='@t6g_mb_lib.t6g(sch_1):page218_i85@pure_quanta.q_cap(chips)',
 PATH='I85',
 DRAWING='@T6G_MB_LIB.T6G(SCH_1):PAGE193',
 TOLERANCE='20%',
 MATERIAL='X6S',
 PHYS_PAGE='218',
 XY='(-1675,4400)',
 ROT='0',
 VER='1',
 PACK_TYPE='C0805',
 LOCATION='PC395_1',
 CDS_LIB='pure_quanta',
 CDS_PART_NAME='Q_CAP_C0805-22UF,4V,20%,X6S,CH622KMEA03',
 VOLTAGE='4V',
 PART_NUMBER='CH622KMEA03',
 VALUE='22UF',
 PRIM_FILE='./archive_libs/logical/q_cap/chips/chips.prt';

PART_NAME
 PC397_2 'Q_CAP_C0805-22UF,4V,20%,X6S,CH622KMEA03':;

SECTION_NUMBER 1
 '@T6G_MB_LIB.T6G(SCH_1):PAGE193_I70@PURE_QUANTA.Q_CAP(CHIPS)':
 C_PATH='@t6g_mb_lib.t6g(sch_1):page193_i70@pure_quanta.q_cap(chips)',
 P_PATH='@t6g_mb_lib.t6g(sch_1):page218_i70@pure_quanta.q_cap(chips)',
 PATH='I70',
 DRAWING='@T6G_MB_LIB.T6G(SCH_1):PAGE193',
 TOLERANCE='20%',
 MATERIAL='X6S',
 PHYS_PAGE='218',
 XY='(-1225,1775)',
 ROT='0',
 VER='1',
 PACK_TYPE='C0805',
 LOCATION='PC397_2',
 CDS_LIB='pure_quanta',
 CDS_PART_NAME='Q_CAP_C0805-22UF,4V,20%,X6S,CH622KMEA03',
 VOLTAGE='4V',
 PART_NUMBER='CH622KMEA03',
 VALUE='22UF',
 PRIM_FILE='./archive_libs/logical/q_cap/chips/chips.prt';

PART_NAME
 PC398_1 'Q_CAP_C0805-22UF,4V,20%,X6S,CH622KMEA03':;

SECTION_NUMBER 1
 '@T6G_MB_LIB.T6G(SCH_1):PAGE193_I86@PURE_QUANTA.Q_CAP(CHIPS)':
 C_PATH='@t6g_mb_lib.t6g(sch_1):page193_i86@pure_quanta.q_cap(chips)',
 P_PATH='@t6g_mb_lib.t6g(sch_1):page218_i86@pure_quanta.q_cap(chips)',
 PATH='I86',
 DRAWING='@T6G_MB_LIB.T6G(SCH_1):PAGE193',
 TOLERANCE='20%',
 MATERIAL='X6S',
 PHYS_PAGE='218',
 XY='(-1250,4400)',
 ROT='0',
 VER='1',
 PACK_TYPE='C0805',
 LOCATION='PC398_1',
 CDS_LIB='pure_quanta',
 CDS_PART_NAME='Q_CAP_C0805-22UF,4V,20%,X6S,CH622KMEA03',
 VOLTAGE='4V',
 PART_NUMBER='CH622KMEA03',
 VALUE='22UF',
 PRIM_FILE='./archive_libs/logical/q_cap/chips/chips.prt';

PART_NAME
 PC399 'Q_CAP_C0402-2.2UF,10V,10%,X6S,CH5222KEB01':;

SECTION_NUMBER 1
 '@T6G_MB_LIB.T6G(SCH_1):PAGE194_I7@PURE_QUANTA.Q_CAP(CHIPS)':
 C_PATH='@t6g_mb_lib.t6g(sch_1):page194_i7@pure_quanta.q_cap(chips)',
 P_PATH='@t6g_mb_lib.t6g(sch_1):page219_i7@pure_quanta.q_cap(chips)',
 PATH='I7',
 DRAWING='@T6G_MB_LIB.T6G(SCH_1):PAGE194',
 TOLERANCE='10%',
 MATERIAL='X6S',
 PHYS_PAGE='219',
 XY='(1500,1925)',
 ROT='0',
 VER='1',
 PACK_TYPE='C0402',
 LOCATION='PC399',
 CDS_LIB='pure_quanta',
 CDS_PART_NAME='Q_CAP_C0402-2.2UF,10V,10%,X6S,CH5222KEB01',
 VOLTAGE='10V',
 PART_NUMBER='CH5222KEB01',
 VALUE='2.2UF',
 PRIM_FILE='./archive_libs/logical/q_cap/chips/chips.prt';

PART_NAME
 PC400 'Q_CAP_C0402-2.2UF,10V,10%,X6S,CH5222KEB01':;

SECTION_NUMBER 1
 '@T6G_MB_LIB.T6G(SCH_1):PAGE194_I27@PURE_QUANTA.Q_CAP(CHIPS)':
 C_PATH='@t6g_mb_lib.t6g(sch_1):page194_i27@pure_quanta.q_cap(chips)',
 P_PATH='@t6g_mb_lib.t6g(sch_1):page219_i27@pure_quanta.q_cap(chips)',
 PATH='I27',
 DRAWING='@T6G_MB_LIB.T6G(SCH_1):PAGE194',
 TOLERANCE='10%',
 MATERIAL='X6S',
 PHYS_PAGE='219',
 XY='(1675,4750)',
 ROT='0',
 VER='1',
 PACK_TYPE='C0402',
 LOCATION='PC400',
 CDS_LIB='pure_quanta',
 CDS_PART_NAME='Q_CAP_C0402-2.2UF,10V,10%,X6S,CH5222KEB01',
 VOLTAGE='10V',
 PART_NUMBER='CH5222KEB01',
 VALUE='2.2UF',
 PRIM_FILE='./archive_libs/logical/q_cap/chips/chips.prt';

PART_NAME
 PC401_C1P1_4 'Q_CAP_C0402-2.2UF,10V,10%,X6S,CH5222KEB01':;

SECTION_NUMBER 1
 '@T6G_MB_LIB.T6G(SCH_1):PAGE194_I16@PURE_QUANTA.Q_CAP(CHIPS)':
 C_PATH='@t6g_mb_lib.t6g(sch_1):page194_i16@pure_quanta.q_cap(chips)',
 P_PATH='@t6g_mb_lib.t6g(sch_1):page219_i16@pure_quanta.q_cap(chips)',
 PATH='I16',
 DRAWING='@T6G_MB_LIB.T6G(SCH_1):PAGE194',
 TOLERANCE='10%',
 MATERIAL='X6S',
 PHYS_PAGE='219',
 XY='(1850,2500)',
 ROT='0',
 VER='1',
 PACK_TYPE='C0402',
 LOCATION='PC401_C1P1_4',
 CDS_LIB='pure_quanta',
 CDS_PART_NAME='Q_CAP_C0402-2.2UF,10V,10%,X6S,CH5222KEB01',
 VOLTAGE='10V',
 PART_NUMBER='CH5222KEB01',
 VALUE='2.2UF',
 PRIM_FILE='./archive_libs/logical/q_cap/chips/chips.prt';

PART_NAME
 PC402_C1P1_3 'Q_CAP_C0402-2.2UF,10V,10%,X6S,CH5222KEB01':;

SECTION_NUMBER 1
 '@T6G_MB_LIB.T6G(SCH_1):PAGE194_I31@PURE_QUANTA.Q_CAP(CHIPS)':
 C_PATH='@t6g_mb_lib.t6g(sch_1):page194_i31@pure_quanta.q_cap(chips)',
 P_PATH='@t6g_mb_lib.t6g(sch_1):page219_i31@pure_quanta.q_cap(chips)',
 PATH='I31',
 DRAWING='@T6G_MB_LIB.T6G(SCH_1):PAGE194',
 TOLERANCE='10%',
 MATERIAL='X6S',
 PHYS_PAGE='219',
 XY='(2025,5325)',
 ROT='0',
 VER='1',
 PACK_TYPE='C0402',
 LOCATION='PC402_C1P1_3',
 CDS_LIB='pure_quanta',
 CDS_PART_NAME='Q_CAP_C0402-2.2UF,10V,10%,X6S,CH5222KEB01',
 VOLTAGE='10V',
 PART_NUMBER='CH5222KEB01',
 VALUE='2.2UF',
 PRIM_FILE='./archive_libs/logical/q_cap/chips/chips.prt';

PART_NAME
 PC403_4 'Q_CAP_0402-0.1UF,25V,10%,X7R,CH4104K1B00':;

SECTION_NUMBER 1
 '@T6G_MB_LIB.T6G(SCH_1):PAGE194_I2@PURE_QUANTA.Q_CAP(CHIPS)':
 C_PATH='@t6g_mb_lib.t6g(sch_1):page194_i2@pure_quanta.q_cap(chips)',
 P_PATH='@t6g_mb_lib.t6g(sch_1):page219_i2@pure_quanta.q_cap(chips)',
 PATH='I2',
 DRAWING='@T6G_MB_LIB.T6G(SCH_1):PAGE194',
 TOLERANCE='10%',
 MATERIAL='X7R',
 PHYS_PAGE='219',
 XY='(850,1100)',
 ROT='0',
 VER='1',
 PACK_TYPE='0402',
 LOCATION='PC403_4',
 CDS_LIB='pure_quanta',
 CDS_PART_NAME='Q_CAP_0402-0.1UF,25V,10%,X7R,CH4104K1B00',
 VOLTAGE='25V',
 PART_NUMBER='CH4104K1B00',
 VALUE='0.1UF',
 PRIM_FILE='./archive_libs/logical/q_cap/chips/chips.prt';

PART_NAME
 PC404_3 'Q_CAP_0402-0.1UF,25V,10%,X7R,CH4104K1B00':;

SECTION_NUMBER 1
 '@T6G_MB_LIB.T6G(SCH_1):PAGE194_I12@PURE_QUANTA.Q_CAP(CHIPS)':
 C_PATH='@t6g_mb_lib.t6g(sch_1):page194_i12@pure_quanta.q_cap(chips)',
 P_PATH='@t6g_mb_lib.t6g(sch_1):page219_i12@pure_quanta.q_cap(chips)',
 PATH='I12',
 DRAWING='@T6G_MB_LIB.T6G(SCH_1):PAGE194',
 TOLERANCE='10%',
 MATERIAL='X7R',
 PHYS_PAGE='219',
 XY='(875,3925)',
 ROT='0',
 VER='1',
 PACK_TYPE='0402',
 LOCATION='PC404_3',
 CDS_LIB='pure_quanta',
 CDS_PART_NAME='Q_CAP_0402-0.1UF,25V,10%,X7R,CH4104K1B00',
 VOLTAGE='25V',
 PART_NUMBER='CH4104K1B00',
 VALUE='0.1UF',
 PRIM_FILE='./archive_libs/logical/q_cap/chips/chips.prt';

PART_NAME
 PC405_4 'Q_CAP_0402-0.1UF,25V,10%,X7R,CH4104K1B00':;

SECTION_NUMBER 1
 '@T6G_MB_LIB.T6G(SCH_1):PAGE194_I23@PURE_QUANTA.Q_CAP(CHIPS)':
 C_PATH='@t6g_mb_lib.t6g(sch_1):page194_i23@pure_quanta.q_cap(chips)',
 P_PATH='@t6g_mb_lib.t6g(sch_1):page219_i23@pure_quanta.q_cap(chips)',
 PATH='I23',
 DRAWING='@T6G_MB_LIB.T6G(SCH_1):PAGE194',
 TOLERANCE='10%',
 MATERIAL='X7R',
 PHYS_PAGE='219',
 XY='(4075,2400)',
 ROT='0',
 VER='1',
 PACK_TYPE='0402',
 LOCATION='PC405_4',
 CDS_LIB='pure_quanta',
 CDS_PART_NAME='Q_CAP_0402-0.1UF,25V,10%,X7R,CH4104K1B00',
 VOLTAGE='25V',
 PART_NUMBER='CH4104K1B00',
 VALUE='0.1UF',
 PRIM_FILE='./archive_libs/logical/q_cap/chips/chips.prt';

PART_NAME
 PC406_3 'Q_CAP_C0402-1UF,25V,10%,X6S,CH5104KEB02':;

SECTION_NUMBER 1
 '@T6G_MB_LIB.T6G(SCH_1):PAGE194_I54@PURE_QUANTA.Q_CAP(CHIPS)':
 C_PATH='@t6g_mb_lib.t6g(sch_1):page194_i54@pure_quanta.q_cap(chips)',
 P_PATH='@t6g_mb_lib.t6g(sch_1):page219_i54@pure_quanta.q_cap(chips)',
 PATH='I54',
 DRAWING='@T6G_MB_LIB.T6G(SCH_1):PAGE194',
 TOLERANCE='10%',
 MATERIAL='X6S',
 PHYS_PAGE='219',
 XY='(4525,5225)',
 ROT='0',
 VER='1',
 PACK_TYPE='C0402',
 LOCATION='PC406_3',
 CDS_LIB='pure_quanta',
 CDS_PART_NAME='Q_CAP_C0402-1UF,25V,10%,X6S,CH5104KEB02',
 VOLTAGE='25V',
 PART_NUMBER='CH5104KEB02',
 VALUE='1UF',
 PRIM_FILE='./archive_libs/logical/q_cap/chips/chips.prt';

PART_NAME
 PC407_4 'Q_CAP_C0402-1UF,25V,10%,X6S,CH5104KEB02':;

SECTION_NUMBER 1
 '@T6G_MB_LIB.T6G(SCH_1):PAGE194_I41@PURE_QUANTA.Q_CAP(CHIPS)':
 C_PATH='@t6g_mb_lib.t6g(sch_1):page194_i41@pure_quanta.q_cap(chips)',
 P_PATH='@t6g_mb_lib.t6g(sch_1):page219_i41@pure_quanta.q_cap(chips)',
 PATH='I41',
 DRAWING='@T6G_MB_LIB.T6G(SCH_1):PAGE194',
 TOLERANCE='10%',
 MATERIAL='X6S',
 PHYS_PAGE='219',
 XY='(4475,2375)',
 ROT='0',
 VER='1',
 PACK_TYPE='C0402',
 LOCATION='PC407_4',
 CDS_LIB='pure_quanta',
 CDS_PART_NAME='Q_CAP_C0402-1UF,25V,10%,X6S,CH5104KEB02',
 VOLTAGE='25V',
 PART_NUMBER='CH5104KEB02',
 VALUE='1UF',
 PRIM_FILE='./archive_libs/logical/q_cap/chips/chips.prt';

PART_NAME
 PC408_3 'Q_CAP_0402-0.1UF,25V,10%,X7R,CH4104K1B00':;

SECTION_NUMBER 1
 '@T6G_MB_LIB.T6G(SCH_1):PAGE194_I33@PURE_QUANTA.Q_CAP(CHIPS)':
 C_PATH='@t6g_mb_lib.t6g(sch_1):page194_i33@pure_quanta.q_cap(chips)',
 P_PATH='@t6g_mb_lib.t6g(sch_1):page219_i33@pure_quanta.q_cap(chips)',
 PATH='I33',
 DRAWING='@T6G_MB_LIB.T6G(SCH_1):PAGE194',
 TOLERANCE='10%',
 MATERIAL='X7R',
 PHYS_PAGE='219',
 XY='(4125,5250)',
 ROT='0',
 VER='1',
 PACK_TYPE='0402',
 LOCATION='PC408_3',
 CDS_LIB='pure_quanta',
 CDS_PART_NAME='Q_CAP_0402-0.1UF,25V,10%,X7R,CH4104K1B00',
 VOLTAGE='25V',
 PART_NUMBER='CH4104K1B00',
 VALUE='0.1UF',
 PRIM_FILE='./archive_libs/logical/q_cap/chips/chips.prt';

PART_NAME
 PC409_4 'Q_CAP_C0805-22UF,16V,20%,X6S,CH6223MEA01':;

SECTION_NUMBER 1
 '@T6G_MB_LIB.T6G(SCH_1):PAGE194_I42@PURE_QUANTA.Q_CAP(CHIPS)':
 C_PATH='@t6g_mb_lib.t6g(sch_1):page194_i42@pure_quanta.q_cap(chips)',
 P_PATH='@t6g_mb_lib.t6g(sch_1):page219_i42@pure_quanta.q_cap(chips)',
 PATH='I42',
 DRAWING='@T6G_MB_LIB.T6G(SCH_1):PAGE194',
 TOLERANCE='20%',
 MATERIAL='X6S',
 PHYS_PAGE='219',
 XY='(4875,2375)',
 ROT='0',
 VER='1',
 PACK_TYPE='C0805',
 LOCATION='PC409_4',
 CDS_LIB='pure_quanta',
 CDS_PART_NAME='Q_CAP_C0805-22UF,16V,20%,X6S,CH6223MEA01',
 VOLTAGE='16V',
 PART_NUMBER='CH6223MEA01',
 VALUE='22UF',
 PRIM_FILE='./archive_libs/logical/q_cap/chips/chips.prt';

PART_NAME
 PC410_3 'Q_CAP_C0805-22UF,16V,20%,X6S,CH6223MEA01':;

SECTION_NUMBER 1
 '@T6G_MB_LIB.T6G(SCH_1):PAGE194_I55@PURE_QUANTA.Q_CAP(CHIPS)':
 C_PATH='@t6g_mb_lib.t6g(sch_1):page194_i55@pure_quanta.q_cap(chips)',
 P_PATH='@t6g_mb_lib.t6g(sch_1):page219_i55@pure_quanta.q_cap(chips)',
 PATH='I55',
 DRAWING='@T6G_MB_LIB.T6G(SCH_1):PAGE194',
 TOLERANCE='20%',
 MATERIAL='X6S',
 PHYS_PAGE='219',
 XY='(4925,5225)',
 ROT='0',
 VER='1',
 PACK_TYPE='C0805',
 LOCATION='PC410_3',
 CDS_LIB='pure_quanta',
 CDS_PART_NAME='Q_CAP_C0805-22UF,16V,20%,X6S,CH6223MEA01',
 VOLTAGE='16V',
 PART_NUMBER='CH6223MEA01',
 VALUE='22UF',
 PRIM_FILE='./archive_libs/logical/q_cap/chips/chips.prt';

PART_NAME
 PC411_4 'Q_CAP_C0805-22UF,16V,20%,X6S,CH6223MEA01':;

SECTION_NUMBER 1
 '@T6G_MB_LIB.T6G(SCH_1):PAGE194_I45@PURE_QUANTA.Q_CAP(CHIPS)':
 C_PATH='@t6g_mb_lib.t6g(sch_1):page194_i45@pure_quanta.q_cap(chips)',
 P_PATH='@t6g_mb_lib.t6g(sch_1):page219_i45@pure_quanta.q_cap(chips)',
 PATH='I45',
 DRAWING='@T6G_MB_LIB.T6G(SCH_1):PAGE194',
 TOLERANCE='20%',
 MATERIAL='X6S',
 PHYS_PAGE='219',
 XY='(5275,2375)',
 ROT='0',
 VER='1',
 PACK_TYPE='C0805',
 LOCATION='PC411_4',
 CDS_LIB='pure_quanta',
 CDS_PART_NAME='Q_CAP_C0805-22UF,16V,20%,X6S,CH6223MEA01',
 VOLTAGE='16V',
 PART_NUMBER='CH6223MEA01',
 VALUE='22UF',
 PRIM_FILE='./archive_libs/logical/q_cap/chips/chips.prt';

PART_NAME
 PC412_3 'Q_CAP_C0805-22UF,16V,20%,X6S,CH6223MEA01':;

SECTION_NUMBER 1
 '@T6G_MB_LIB.T6G(SCH_1):PAGE194_I59@PURE_QUANTA.Q_CAP(CHIPS)':
 C_PATH='@t6g_mb_lib.t6g(sch_1):page194_i59@pure_quanta.q_cap(chips)',
 P_PATH='@t6g_mb_lib.t6g(sch_1):page219_i59@pure_quanta.q_cap(chips)',
 PATH='I59',
 DRAWING='@T6G_MB_LIB.T6G(SCH_1):PAGE194',
 TOLERANCE='20%',
 MATERIAL='X6S',
 PHYS_PAGE='219',
 XY='(5325,5225)',
 ROT='0',
 VER='1',
 PACK_TYPE='C0805',
 LOCATION='PC412_3',
 CDS_LIB='pure_quanta',
 CDS_PART_NAME='Q_CAP_C0805-22UF,16V,20%,X6S,CH6223MEA01',
 VOLTAGE='16V',
 PART_NUMBER='CH6223MEA01',
 VALUE='22UF',
 PRIM_FILE='./archive_libs/logical/q_cap/chips/chips.prt';

PART_NAME
 PC413 'Q_CAP_0402-0.22UF,16V,10%,X7R,CH4223K1B00':;

SECTION_NUMBER 1
 '@T6G_MB_LIB.T6G(SCH_1):PAGE194_I40@PURE_QUANTA.Q_CAP(CHIPS)':
 C_PATH='@t6g_mb_lib.t6g(sch_1):page194_i40@pure_quanta.q_cap(chips)',
 P_PATH='@t6g_mb_lib.t6g(sch_1):page219_i40@pure_quanta.q_cap(chips)',
 PATH='I40',
 DRAWING='@T6G_MB_LIB.T6G(SCH_1):PAGE194',
 TOLERANCE='10%',
 MATERIAL='X7R',
 PHYS_PAGE='219',
 XY='(5500,1700)',
 ROT='0',
 VER='1',
 PACK_TYPE='0402',
 LOCATION='PC413',
 CDS_LIB='pure_quanta',
 CDS_PART_NAME='Q_CAP_0402-0.22UF,16V,10%,X7R,CH4223K1B00',
 VOLTAGE='16V',
 PART_NUMBER='CH4223K1B00',
 VALUE='0.22UF',
 PRIM_FILE='./archive_libs/logical/q_cap/chips/chips.prt';

PART_NAME
 PC414 'Q_CAP_0402-0.22UF,16V,10%,X7R,CH4223K1B00':;

SECTION_NUMBER 1
 '@T6G_MB_LIB.T6G(SCH_1):PAGE194_I57@PURE_QUANTA.Q_CAP(CHIPS)':
 C_PATH='@t6g_mb_lib.t6g(sch_1):page194_i57@pure_quanta.q_cap(chips)',
 P_PATH='@t6g_mb_lib.t6g(sch_1):page219_i57@pure_quanta.q_cap(chips)',
 PATH='I57',
 DRAWING='@T6G_MB_LIB.T6G(SCH_1):PAGE194',
 TOLERANCE='10%',
 MATERIAL='X7R',
 PHYS_PAGE='219',
 XY='(5650,4525)',
 ROT='0',
 VER='1',
 PACK_TYPE='0402',
 LOCATION='PC414',
 CDS_LIB='pure_quanta',
 CDS_PART_NAME='Q_CAP_0402-0.22UF,16V,10%,X7R,CH4223K1B00',
 VOLTAGE='16V',
 PART_NUMBER='CH4223K1B00',
 VALUE='0.22UF',
 PRIM_FILE='./archive_libs/logical/q_cap/chips/chips.prt';

PART_NAME
 PC415_4 'Q_CAP_C0805-22UF,16V,20%,X6S,CH6223MEA01':;

SECTION_NUMBER 1
 '@T6G_MB_LIB.T6G(SCH_1):PAGE194_I47@PURE_QUANTA.Q_CAP(CHIPS)':
 C_PATH='@t6g_mb_lib.t6g(sch_1):page194_i47@pure_quanta.q_cap(chips)',
 P_PATH='@t6g_mb_lib.t6g(sch_1):page219_i47@pure_quanta.q_cap(chips)',
 PATH='I47',
 DRAWING='@T6G_MB_LIB.T6G(SCH_1):PAGE194',
 TOLERANCE='20%',
 MATERIAL='X6S',
 PHYS_PAGE='219',
 XY='(5650,2375)',
 ROT='0',
 VER='1',
 PACK_TYPE='C0805',
 LOCATION='PC415_4',
 CDS_LIB='pure_quanta',
 CDS_PART_NAME='Q_CAP_C0805-22UF,16V,20%,X6S,CH6223MEA01',
 VOLTAGE='16V',
 PART_NUMBER='CH6223MEA01',
 VALUE='22UF',
 PRIM_FILE='./archive_libs/logical/q_cap/chips/chips.prt';

PART_NAME
 PC416_3 'Q_CAP_C0805-22UF,16V,20%,X6S,CH6223MEA01':;

SECTION_NUMBER 1
 '@T6G_MB_LIB.T6G(SCH_1):PAGE194_I60@PURE_QUANTA.Q_CAP(CHIPS)':
 C_PATH='@t6g_mb_lib.t6g(sch_1):page194_i60@pure_quanta.q_cap(chips)',
 P_PATH='@t6g_mb_lib.t6g(sch_1):page219_i60@pure_quanta.q_cap(chips)',
 PATH='I60',
 DRAWING='@T6G_MB_LIB.T6G(SCH_1):PAGE194',
 TOLERANCE='20%',
 MATERIAL='X6S',
 PHYS_PAGE='219',
 XY='(5700,5225)',
 ROT='0',
 VER='1',
 PACK_TYPE='C0805',
 LOCATION='PC416_3',
 CDS_LIB='pure_quanta',
 CDS_PART_NAME='Q_CAP_C0805-22UF,16V,20%,X6S,CH6223MEA01',
 VOLTAGE='16V',
 PART_NUMBER='CH6223MEA01',
 VALUE='22UF',
 PRIM_FILE='./archive_libs/logical/q_cap/chips/chips.prt';

PART_NAME
 PC417_3 'Q_CAP_C0805-22UF,4V,20%,X6S,CH622KMEA03':;

SECTION_NUMBER 1
 '@T6G_MB_LIB.T6G(SCH_1):PAGE194_I64@PURE_QUANTA.Q_CAP(CHIPS)':
 C_PATH='@t6g_mb_lib.t6g(sch_1):page194_i64@pure_quanta.q_cap(chips)',
 P_PATH='@t6g_mb_lib.t6g(sch_1):page219_i64@pure_quanta.q_cap(chips)',
 PATH='I64',
 DRAWING='@T6G_MB_LIB.T6G(SCH_1):PAGE194',
 TOLERANCE='20%',
 MATERIAL='X6S',
 PHYS_PAGE='219',
 XY='(8175,4100)',
 ROT='0',
 VER='1',
 PACK_TYPE='C0805',
 LOCATION='PC417_3',
 CDS_LIB='pure_quanta',
 CDS_PART_NAME='Q_CAP_C0805-22UF,4V,20%,X6S,CH622KMEA03',
 VOLTAGE='4V',
 PART_NUMBER='CH622KMEA03',
 VALUE='22UF',
 PRIM_FILE='./archive_libs/logical/q_cap/chips/chips.prt';

PART_NAME
 PC418_4 'Q_CAP_C0805-22UF,4V,20%,X6S,CH622KMEA03':;

SECTION_NUMBER 1
 '@T6G_MB_LIB.T6G(SCH_1):PAGE194_I65@PURE_QUANTA.Q_CAP(CHIPS)':
 C_PATH='@t6g_mb_lib.t6g(sch_1):page194_i65@pure_quanta.q_cap(chips)',
 P_PATH='@t6g_mb_lib.t6g(sch_1):page219_i65@pure_quanta.q_cap(chips)',
 PATH='I65',
 DRAWING='@T6G_MB_LIB.T6G(SCH_1):PAGE194',
 TOLERANCE='20%',
 MATERIAL='X6S',
 PHYS_PAGE='219',
 XY='(8325,1275)',
 ROT='0',
 VER='1',
 PACK_TYPE='C0805',
 LOCATION='PC418_4',
 CDS_LIB='pure_quanta',
 CDS_PART_NAME='Q_CAP_C0805-22UF,4V,20%,X6S,CH622KMEA03',
 VOLTAGE='4V',
 PART_NUMBER='CH622KMEA03',
 VALUE='22UF',
 PRIM_FILE='./archive_libs/logical/q_cap/chips/chips.prt';

PART_NAME
 PC419_3 'Q_CAP_C0805-22UF,4V,20%,X6S,CH622KMEA03':;

SECTION_NUMBER 1
 '@T6G_MB_LIB.T6G(SCH_1):PAGE194_I70@PURE_QUANTA.Q_CAP(CHIPS)':
 C_PATH='@t6g_mb_lib.t6g(sch_1):page194_i70@pure_quanta.q_cap(chips)',
 P_PATH='@t6g_mb_lib.t6g(sch_1):page219_i70@pure_quanta.q_cap(chips)',
 PATH='I70',
 DRAWING='@T6G_MB_LIB.T6G(SCH_1):PAGE194',
 TOLERANCE='20%',
 MATERIAL='X6S',
 PHYS_PAGE='219',
 XY='(8600,4100)',
 ROT='0',
 VER='1',
 PACK_TYPE='C0805',
 LOCATION='PC419_3',
 CDS_LIB='pure_quanta',
 CDS_PART_NAME='Q_CAP_C0805-22UF,4V,20%,X6S,CH622KMEA03',
 VOLTAGE='4V',
 PART_NUMBER='CH622KMEA03',
 VALUE='22UF',
 PRIM_FILE='./archive_libs/logical/q_cap/chips/chips.prt';

PART_NAME
 PC420_4 'Q_CAP_C0805-22UF,4V,20%,X6S,CH622KMEA03':;

SECTION_NUMBER 1
 '@T6G_MB_LIB.T6G(SCH_1):PAGE194_I67@PURE_QUANTA.Q_CAP(CHIPS)':
 C_PATH='@t6g_mb_lib.t6g(sch_1):page194_i67@pure_quanta.q_cap(chips)',
 P_PATH='@t6g_mb_lib.t6g(sch_1):page219_i67@pure_quanta.q_cap(chips)',
 PATH='I67',
 DRAWING='@T6G_MB_LIB.T6G(SCH_1):PAGE194',
 TOLERANCE='20%',
 MATERIAL='X6S',
 PHYS_PAGE='219',
 XY='(8750,1275)',
 ROT='0',
 VER='1',
 PACK_TYPE='C0805',
 LOCATION='PC420_4',
 CDS_LIB='pure_quanta',
 CDS_PART_NAME='Q_CAP_C0805-22UF,4V,20%,X6S,CH622KMEA03',
 VOLTAGE='4V',
 PART_NUMBER='CH622KMEA03',
 VALUE='22UF',
 PRIM_FILE='./archive_libs/logical/q_cap/chips/chips.prt';

PART_NAME
 PC421 'Q_CAP_C0402-2.2UF,10V,10%,X6S,CH5222KEB01':;

SECTION_NUMBER 1
 '@T6G_MB_LIB.T6G(SCH_1):PAGE195_I27@PURE_QUANTA.Q_CAP(CHIPS)':
 C_PATH='@t6g_mb_lib.t6g(sch_1):page195_i27@pure_quanta.q_cap(chips)',
 P_PATH='@t6g_mb_lib.t6g(sch_1):page220_i27@pure_quanta.q_cap(chips)',
 PATH='I27',
 DRAWING='@T6G_MB_LIB.T6G(SCH_1):PAGE195',
 TOLERANCE='10%',
 MATERIAL='X6S',
 PHYS_PAGE='220',
 XY='(1675,5275)',
 ROT='0',
 VER='1',
 PACK_TYPE='C0402',
 LOCATION='PC421',
 CDS_LIB='pure_quanta',
 CDS_PART_NAME='Q_CAP_C0402-2.2UF,10V,10%,X6S,CH5222KEB01',
 VOLTAGE='10V',
 PART_NUMBER='CH5222KEB01',
 VALUE='2.2UF',
 PRIM_FILE='./archive_libs/logical/q_cap/chips/chips.prt';

PART_NAME
 PC422_5 'Q_CAP_0402-0.1UF,25V,10%,X7R,CH4104K1B00':;

SECTION_NUMBER 1
 '@T6G_MB_LIB.T6G(SCH_1):PAGE195_I10@PURE_QUANTA.Q_CAP(CHIPS)':
 C_PATH='@t6g_mb_lib.t6g(sch_1):page195_i10@pure_quanta.q_cap(chips)',
 P_PATH='@t6g_mb_lib.t6g(sch_1):page220_i10@pure_quanta.q_cap(chips)',
 PATH='I10',
 DRAWING='@T6G_MB_LIB.T6G(SCH_1):PAGE195',
 TOLERANCE='10%',
 MATERIAL='X7R',
 PHYS_PAGE='220',
 XY='(725,4475)',
 ROT='0',
 VER='1',
 PACK_TYPE='0402',
 LOCATION='PC422_5',
 CDS_LIB='pure_quanta',
 CDS_PART_NAME='Q_CAP_0402-0.1UF,25V,10%,X7R,CH4104K1B00',
 VOLTAGE='25V',
 PART_NUMBER='CH4104K1B00',
 VALUE='0.1UF',
 PRIM_FILE='./archive_libs/logical/q_cap/chips/chips.prt';

PART_NAME
 PC423_C1P1_5 'Q_CAP_C0402-2.2UF,10V,10%,X6S,CH5222KEB01':;

SECTION_NUMBER 1
 '@T6G_MB_LIB.T6G(SCH_1):PAGE195_I31@PURE_QUANTA.Q_CAP(CHIPS)':
 C_PATH='@t6g_mb_lib.t6g(sch_1):page195_i31@pure_quanta.q_cap(chips)',
 P_PATH='@t6g_mb_lib.t6g(sch_1):page220_i31@pure_quanta.q_cap(chips)',
 PATH='I31',
 DRAWING='@T6G_MB_LIB.T6G(SCH_1):PAGE195',
 TOLERANCE='10%',
 MATERIAL='X6S',
 PHYS_PAGE='220',
 XY='(2025,5850)',
 ROT='0',
 VER='1',
 PACK_TYPE='C0402',
 LOCATION='PC423_C1P1_5',
 CDS_LIB='pure_quanta',
 CDS_PART_NAME='Q_CAP_C0402-2.2UF,10V,10%,X6S,CH5222KEB01',
 VOLTAGE='10V',
 PART_NUMBER='CH5222KEB01',
 VALUE='2.2UF',
 PRIM_FILE='./archive_libs/logical/q_cap/chips/chips.prt';

PART_NAME
 PC424_5 'Q_CAP_C0402-1UF,25V,10%,X6S,CH5104KEB02':;

SECTION_NUMBER 1
 '@T6G_MB_LIB.T6G(SCH_1):PAGE195_I55@PURE_QUANTA.Q_CAP(CHIPS)':
 C_PATH='@t6g_mb_lib.t6g(sch_1):page195_i55@pure_quanta.q_cap(chips)',
 P_PATH='@t6g_mb_lib.t6g(sch_1):page220_i55@pure_quanta.q_cap(chips)',
 PATH='I55',
 DRAWING='@T6G_MB_LIB.T6G(SCH_1):PAGE195',
 TOLERANCE='10%',
 MATERIAL='X6S',
 PHYS_PAGE='220',
 XY='(4425,5750)',
 ROT='0',
 VER='1',
 PACK_TYPE='C0402',
 LOCATION='PC424_5',
 CDS_LIB='pure_quanta',
 CDS_PART_NAME='Q_CAP_C0402-1UF,25V,10%,X6S,CH5104KEB02',
 VOLTAGE='25V',
 PART_NUMBER='CH5104KEB02',
 VALUE='1UF',
 PRIM_FILE='./archive_libs/logical/q_cap/chips/chips.prt';

PART_NAME
 PC425_5 'Q_CAP_0402-0.1UF,25V,10%,X7R,CH4104K1B00':;

SECTION_NUMBER 1
 '@T6G_MB_LIB.T6G(SCH_1):PAGE195_I54@PURE_QUANTA.Q_CAP(CHIPS)':
 C_PATH='@t6g_mb_lib.t6g(sch_1):page195_i54@pure_quanta.q_cap(chips)',
 P_PATH='@t6g_mb_lib.t6g(sch_1):page220_i54@pure_quanta.q_cap(chips)',
 PATH='I54',
 DRAWING='@T6G_MB_LIB.T6G(SCH_1):PAGE195',
 TOLERANCE='10%',
 MATERIAL='X7R',
 PHYS_PAGE='220',
 XY='(4000,5750)',
 ROT='0',
 VER='1',
 PACK_TYPE='0402',
 LOCATION='PC425_5',
 CDS_LIB='pure_quanta',
 CDS_PART_NAME='Q_CAP_0402-0.1UF,25V,10%,X7R,CH4104K1B00',
 VOLTAGE='25V',
 PART_NUMBER='CH4104K1B00',
 VALUE='0.1UF',
 PRIM_FILE='./archive_libs/logical/q_cap/chips/chips.prt';

PART_NAME
 PC426_5 'Q_CAP_C0805-22UF,16V,20%,X6S,CH6223MEA01':;

SECTION_NUMBER 1
 '@T6G_MB_LIB.T6G(SCH_1):PAGE195_I56@PURE_QUANTA.Q_CAP(CHIPS)':
 C_PATH='@t6g_mb_lib.t6g(sch_1):page195_i56@pure_quanta.q_cap(chips)',
 P_PATH='@t6g_mb_lib.t6g(sch_1):page220_i56@pure_quanta.q_cap(chips)',
 PATH='I56',
 DRAWING='@T6G_MB_LIB.T6G(SCH_1):PAGE195',
 TOLERANCE='20%',
 MATERIAL='X6S',
 PHYS_PAGE='220',
 XY='(4825,5750)',
 ROT='0',
 VER='1',
 PACK_TYPE='C0805',
 LOCATION='PC426_5',
 CDS_LIB='pure_quanta',
 CDS_PART_NAME='Q_CAP_C0805-22UF,16V,20%,X6S,CH6223MEA01',
 VOLTAGE='16V',
 PART_NUMBER='CH6223MEA01',
 VALUE='22UF',
 PRIM_FILE='./archive_libs/logical/q_cap/chips/chips.prt';

PART_NAME
 PC427_5 'Q_CAP_C0805-22UF,16V,20%,X6S,CH6223MEA01':;

SECTION_NUMBER 1
 '@T6G_MB_LIB.T6G(SCH_1):PAGE195_I60@PURE_QUANTA.Q_CAP(CHIPS)':
 C_PATH='@t6g_mb_lib.t6g(sch_1):page195_i60@pure_quanta.q_cap(chips)',
 P_PATH='@t6g_mb_lib.t6g(sch_1):page220_i60@pure_quanta.q_cap(chips)',
 PATH='I60',
 DRAWING='@T6G_MB_LIB.T6G(SCH_1):PAGE195',
 TOLERANCE='20%',
 MATERIAL='X6S',
 PHYS_PAGE='220',
 XY='(5225,5750)',
 ROT='0',
 VER='1',
 PACK_TYPE='C0805',
 LOCATION='PC427_5',
 CDS_LIB='pure_quanta',
 CDS_PART_NAME='Q_CAP_C0805-22UF,16V,20%,X6S,CH6223MEA01',
 VOLTAGE='16V',
 PART_NUMBER='CH6223MEA01',
 VALUE='22UF',
 PRIM_FILE='./archive_libs/logical/q_cap/chips/chips.prt';

PART_NAME
 PC428 'Q_CAP_0402-0.22UF,16V,10%,X7R,CH4223K1B00':;

SECTION_NUMBER 1
 '@T6G_MB_LIB.T6G(SCH_1):PAGE195_I57@PURE_QUANTA.Q_CAP(CHIPS)':
 C_PATH='@t6g_mb_lib.t6g(sch_1):page195_i57@pure_quanta.q_cap(chips)',
 P_PATH='@t6g_mb_lib.t6g(sch_1):page220_i57@pure_quanta.q_cap(chips)',
 PATH='I57',
 DRAWING='@T6G_MB_LIB.T6G(SCH_1):PAGE195',
 TOLERANCE='10%',
 MATERIAL='X7R',
 PHYS_PAGE='220',
 XY='(5400,5075)',
 ROT='0',
 VER='1',
 PACK_TYPE='0402',
 LOCATION='PC428',
 CDS_LIB='pure_quanta',
 CDS_PART_NAME='Q_CAP_0402-0.22UF,16V,10%,X7R,CH4223K1B00',
 VOLTAGE='16V',
 PART_NUMBER='CH4223K1B00',
 VALUE='0.22UF',
 PRIM_FILE='./archive_libs/logical/q_cap/chips/chips.prt';

PART_NAME
 PC429_5 'Q_CAP_C0805-22UF,16V,20%,X6S,CH6223MEA01':;

SECTION_NUMBER 1
 '@T6G_MB_LIB.T6G(SCH_1):PAGE195_I61@PURE_QUANTA.Q_CAP(CHIPS)':
 C_PATH='@t6g_mb_lib.t6g(sch_1):page195_i61@pure_quanta.q_cap(chips)',
 P_PATH='@t6g_mb_lib.t6g(sch_1):page220_i61@pure_quanta.q_cap(chips)',
 PATH='I61',
 DRAWING='@T6G_MB_LIB.T6G(SCH_1):PAGE195',
 TOLERANCE='20%',
 MATERIAL='X6S',
 PHYS_PAGE='220',
 XY='(5600,5750)',
 ROT='0',
 VER='1',
 PACK_TYPE='C0805',
 LOCATION='PC429_5',
 CDS_LIB='pure_quanta',
 CDS_PART_NAME='Q_CAP_C0805-22UF,16V,20%,X6S,CH6223MEA01',
 VOLTAGE='16V',
 PART_NUMBER='CH6223MEA01',
 VALUE='22UF',
 PRIM_FILE='./archive_libs/logical/q_cap/chips/chips.prt';

PART_NAME
 PC430_5 'Q_CAP_C0805-22UF,4V,20%,X6S,CH622KMEA03':;

SECTION_NUMBER 1
 '@T6G_MB_LIB.T6G(SCH_1):PAGE195_I70@PURE_QUANTA.Q_CAP(CHIPS)':
 C_PATH='@t6g_mb_lib.t6g(sch_1):page195_i70@pure_quanta.q_cap(chips)',
 P_PATH='@t6g_mb_lib.t6g(sch_1):page220_i70@pure_quanta.q_cap(chips)',
 PATH='I70',
 DRAWING='@T6G_MB_LIB.T6G(SCH_1):PAGE195',
 TOLERANCE='20%',
 MATERIAL='X6S',
 PHYS_PAGE='220',
 XY='(8100,4650)',
 ROT='0',
 VER='1',
 PACK_TYPE='C0805',
 LOCATION='PC430_5',
 CDS_LIB='pure_quanta',
 CDS_PART_NAME='Q_CAP_C0805-22UF,4V,20%,X6S,CH622KMEA03',
 VOLTAGE='4V',
 PART_NUMBER='CH622KMEA03',
 VALUE='22UF',
 PRIM_FILE='./archive_libs/logical/q_cap/chips/chips.prt';

PART_NAME
 PC431_5 'Q_CAP_C0805-22UF,4V,20%,X6S,CH622KMEA03':;

SECTION_NUMBER 1
 '@T6G_MB_LIB.T6G(SCH_1):PAGE195_I71@PURE_QUANTA.Q_CAP(CHIPS)':
 C_PATH='@t6g_mb_lib.t6g(sch_1):page195_i71@pure_quanta.q_cap(chips)',
 P_PATH='@t6g_mb_lib.t6g(sch_1):page220_i71@pure_quanta.q_cap(chips)',
 PATH='I71',
 DRAWING='@T6G_MB_LIB.T6G(SCH_1):PAGE195',
 TOLERANCE='20%',
 MATERIAL='X6S',
 PHYS_PAGE='220',
 XY='(8525,4650)',
 ROT='0',
 VER='1',
 PACK_TYPE='C0805',
 LOCATION='PC431_5',
 CDS_LIB='pure_quanta',
 CDS_PART_NAME='Q_CAP_C0805-22UF,4V,20%,X6S,CH622KMEA03',
 VOLTAGE='4V',
 PART_NUMBER='CH622KMEA03',
 VALUE='22UF',
 PRIM_FILE='./archive_libs/logical/q_cap/chips/chips.prt';

PART_NAME
 PC432 'Q_CAP_C0402-2.2UF,10V,10%,X6S,CH5222KEB01':;

SECTION_NUMBER 1
 '@T6G_MB_LIB.T6G(SCH_1):PAGE197_I12@PURE_QUANTA.Q_CAP(CHIPS)':
 C_PATH='@t6g_mb_lib.t6g(sch_1):page197_i12@pure_quanta.q_cap(chips)',
 P_PATH='@t6g_mb_lib.t6g(sch_1):page222_i12@pure_quanta.q_cap(chips)',
 PATH='I12',
 DRAWING='@T6G_MB_LIB.T6G(SCH_1):PAGE197',
 TOLERANCE='10%',
 MATERIAL='X6S',
 PHYS_PAGE='222',
 XY='(975,2650)',
 ROT='0',
 VER='1',
 PACK_TYPE='C0402',
 LOCATION='PC432',
 CDS_LIB='pure_quanta',
 CDS_PART_NAME='Q_CAP_C0402-2.2UF,10V,10%,X6S,CH5222KEB01',
 VOLTAGE='10V',
 PART_NUMBER='CH5222KEB01',
 VALUE='2.2UF',
 PRIM_FILE='./archive_libs/logical/q_cap/chips/chips.prt';

PART_NAME
 PC433 'Q_CAP_C0402-2.2UF,10V,10%,X6S,CH5222KEB01':;

SECTION_NUMBER 1
 '@T6G_MB_LIB.T6G(SCH_1):PAGE197_I34@PURE_QUANTA.Q_CAP(CHIPS)':
 C_PATH='@t6g_mb_lib.t6g(sch_1):page197_i34@pure_quanta.q_cap(chips)',
 P_PATH='@t6g_mb_lib.t6g(sch_1):page222_i34@pure_quanta.q_cap(chips)',
 PATH='I34',
 DRAWING='@T6G_MB_LIB.T6G(SCH_1):PAGE197',
 TOLERANCE='10%',
 MATERIAL='X6S',
 PHYS_PAGE='222',
 XY='(1075,5275)',
 ROT='0',
 VER='1',
 PACK_TYPE='C0402',
 LOCATION='PC433',
 CDS_LIB='pure_quanta',
 CDS_PART_NAME='Q_CAP_C0402-2.2UF,10V,10%,X6S,CH5222KEB01',
 VOLTAGE='10V',
 PART_NUMBER='CH5222KEB01',
 VALUE='2.2UF',
 PRIM_FILE='./archive_libs/logical/q_cap/chips/chips.prt';

PART_NAME
 PC434_IOP1_2 'Q_CAP_C0402-2.2UF,10V,10%,X6S,CH5222KEB01':;

SECTION_NUMBER 1
 '@T6G_MB_LIB.T6G(SCH_1):PAGE197_I16@PURE_QUANTA.Q_CAP(CHIPS)':
 C_PATH='@t6g_mb_lib.t6g(sch_1):page197_i16@pure_quanta.q_cap(chips)',
 P_PATH='@t6g_mb_lib.t6g(sch_1):page222_i16@pure_quanta.q_cap(chips)',
 PATH='I16',
 DRAWING='@T6G_MB_LIB.T6G(SCH_1):PAGE197',
 TOLERANCE='10%',
 MATERIAL='X6S',
 PHYS_PAGE='222',
 XY='(1325,3225)',
 ROT='0',
 VER='1',
 PACK_TYPE='C0402',
 LOCATION='PC434_IOP1_2',
 CDS_LIB='pure_quanta',
 CDS_PART_NAME='Q_CAP_C0402-2.2UF,10V,10%,X6S,CH5222KEB01',
 VOLTAGE='10V',
 PART_NUMBER='CH5222KEB01',
 VALUE='2.2UF',
 PRIM_FILE='./archive_libs/logical/q_cap/chips/chips.prt';

PART_NAME
 PC435_7 'Q_CAP_0402-0.1UF,25V,10%,X7R,CH4104K1B00':;

SECTION_NUMBER 1
 '@T6G_MB_LIB.T6G(SCH_1):PAGE197_I4@PURE_QUANTA.Q_CAP(CHIPS)':
 C_PATH='@t6g_mb_lib.t6g(sch_1):page197_i4@pure_quanta.q_cap(chips)',
 P_PATH='@t6g_mb_lib.t6g(sch_1):page222_i4@pure_quanta.q_cap(chips)',
 PATH='I4',
 DRAWING='@T6G_MB_LIB.T6G(SCH_1):PAGE197',
 TOLERANCE='10%',
 MATERIAL='X7R',
 PHYS_PAGE='222',
 XY='(100,4625)',
 ROT='0',
 VER='1',
 PACK_TYPE='0402',
 LOCATION='PC435_7',
 CDS_LIB='pure_quanta',
 CDS_PART_NAME='Q_CAP_0402-0.1UF,25V,10%,X7R,CH4104K1B00',
 VOLTAGE='25V',
 PART_NUMBER='CH4104K1B00',
 VALUE='0.1UF',
 PRIM_FILE='./archive_libs/logical/q_cap/chips/chips.prt';

PART_NAME
 PC436_8 'Q_CAP_0402-0.1UF,25V,10%,X7R,CH4104K1B00':;

SECTION_NUMBER 1
 '@T6G_MB_LIB.T6G(SCH_1):PAGE197_I3@PURE_QUANTA.Q_CAP(CHIPS)':
 C_PATH='@t6g_mb_lib.t6g(sch_1):page197_i3@pure_quanta.q_cap(chips)',
 P_PATH='@t6g_mb_lib.t6g(sch_1):page222_i3@pure_quanta.q_cap(chips)',
 PATH='I3',
 DRAWING='@T6G_MB_LIB.T6G(SCH_1):PAGE197',
 TOLERANCE='10%',
 MATERIAL='X7R',
 PHYS_PAGE='222',
 XY='(100,1875)',
 ROT='0',
 VER='1',
 PACK_TYPE='0402',
 LOCATION='PC436_8',
 CDS_LIB='pure_quanta',
 CDS_PART_NAME='Q_CAP_0402-0.1UF,25V,10%,X7R,CH4104K1B00',
 VOLTAGE='25V',
 PART_NUMBER='CH4104K1B00',
 VALUE='0.1UF',
 PRIM_FILE='./archive_libs/logical/q_cap/chips/chips.prt';

PART_NAME
 PC437_IOP1_1 'Q_CAP_C0402-2.2UF,10V,10%,X6S,CH5222KEB01':;

SECTION_NUMBER 1
 '@T6G_MB_LIB.T6G(SCH_1):PAGE197_I38@PURE_QUANTA.Q_CAP(CHIPS)':
 C_PATH='@t6g_mb_lib.t6g(sch_1):page197_i38@pure_quanta.q_cap(chips)',
 P_PATH='@t6g_mb_lib.t6g(sch_1):page222_i38@pure_quanta.q_cap(chips)',
 PATH='I38',
 DRAWING='@T6G_MB_LIB.T6G(SCH_1):PAGE197',
 TOLERANCE='10%',
 MATERIAL='X6S',
 PHYS_PAGE='222',
 XY='(1425,5850)',
 ROT='0',
 VER='1',
 PACK_TYPE='C0402',
 LOCATION='PC437_IOP1_1',
 CDS_LIB='pure_quanta',
 CDS_PART_NAME='Q_CAP_C0402-2.2UF,10V,10%,X6S,CH5222KEB01',
 VOLTAGE='10V',
 PART_NUMBER='CH5222KEB01',
 VALUE='2.2UF',
 PRIM_FILE='./archive_libs/logical/q_cap/chips/chips.prt';

PART_NAME
 PC438 'Q_CAP_0402-0.1UF,25V,10%,X7R,CH4104K1B00':;

SECTION_NUMBER 1
 '@T6G_MB_LIB.T6G(SCH_1):PAGE197_I74@PURE_QUANTA.Q_CAP(CHIPS)':
 C_PATH='@t6g_mb_lib.t6g(sch_1):page197_i74@pure_quanta.q_cap(chips)',
 P_PATH='@t6g_mb_lib.t6g(sch_1):page222_i74@pure_quanta.q_cap(chips)',
 PATH='I74',
 DRAWING='@T6G_MB_LIB.T6G(SCH_1):PAGE197',
 TOLERANCE='10%',
 MATERIAL='X7R',
 PHYS_PAGE='222',
 XY='(5850,5950)',
 ROT='0',
 VER='1',
 PACK_TYPE='0402',
 LOCATION='PC438',
 CDS_LIB='pure_quanta',
 CDS_PART_NAME='Q_CAP_0402-0.1UF,25V,10%,X7R,CH4104K1B00',
 VOLTAGE='25V',
 PART_NUMBER='CH4104K1B00',
 VALUE='0.1UF',
 PRIM_FILE='./archive_libs/logical/q_cap/chips/chips.prt';

PART_NAME
 PC438_1 'Q_CAP_0402-0.1UF,25V,10%,X7R,CH4104K1B00':;

SECTION_NUMBER 1
 '@T6G_MB_LIB.T6G(SCH_1):PAGE197_I41@PURE_QUANTA.Q_CAP(CHIPS)':
 C_PATH='@t6g_mb_lib.t6g(sch_1):page197_i41@pure_quanta.q_cap(chips)',
 P_PATH='@t6g_mb_lib.t6g(sch_1):page222_i41@pure_quanta.q_cap(chips)',
 PATH='I41',
 DRAWING='@T6G_MB_LIB.T6G(SCH_1):PAGE197',
 TOLERANCE='10%',
 MATERIAL='X7R',
 PHYS_PAGE='222',
 XY='(3325,5925)',
 ROT='0',
 VER='1',
 PACK_TYPE='0402',
 LOCATION='PC438_1',
 CDS_LIB='pure_quanta',
 CDS_PART_NAME='Q_CAP_0402-0.1UF,25V,10%,X7R,CH4104K1B00',
 VOLTAGE='25V',
 PART_NUMBER='CH4104K1B00',
 VALUE='0.1UF',
 PRIM_FILE='./archive_libs/logical/q_cap/chips/chips.prt';

PART_NAME
 PC439_2 'Q_CAP_0402-0.1UF,25V,10%,X7R,CH4104K1B00':;

SECTION_NUMBER 1
 '@T6G_MB_LIB.T6G(SCH_1):PAGE197_I21@PURE_QUANTA.Q_CAP(CHIPS)':
 C_PATH='@t6g_mb_lib.t6g(sch_1):page197_i21@pure_quanta.q_cap(chips)',
 P_PATH='@t6g_mb_lib.t6g(sch_1):page222_i21@pure_quanta.q_cap(chips)',
 PATH='I21',
 DRAWING='@T6G_MB_LIB.T6G(SCH_1):PAGE197',
 TOLERANCE='10%',
 MATERIAL='X7R',
 PHYS_PAGE='222',
 XY='(3475,3175)',
 ROT='0',
 VER='1',
 PACK_TYPE='0402',
 LOCATION='PC439_2',
 CDS_LIB='pure_quanta',
 CDS_PART_NAME='Q_CAP_0402-0.1UF,25V,10%,X7R,CH4104K1B00',
 VOLTAGE='25V',
 PART_NUMBER='CH4104K1B00',
 VALUE='0.1UF',
 PRIM_FILE='./archive_libs/logical/q_cap/chips/chips.prt';

PART_NAME
 PC440_1 'Q_CAP_C0402-1UF,25V,10%,X6S,CH5104KEB02':;

SECTION_NUMBER 1
 '@T6G_MB_LIB.T6G(SCH_1):PAGE197_I42@PURE_QUANTA.Q_CAP(CHIPS)':
 C_PATH='@t6g_mb_lib.t6g(sch_1):page197_i42@pure_quanta.q_cap(chips)',
 P_PATH='@t6g_mb_lib.t6g(sch_1):page222_i42@pure_quanta.q_cap(chips)',
 PATH='I42',
 DRAWING='@T6G_MB_LIB.T6G(SCH_1):PAGE197',
 TOLERANCE='10%',
 MATERIAL='X6S',
 PHYS_PAGE='222',
 XY='(3675,5900)',
 ROT='0',
 VER='1',
 PACK_TYPE='C0402',
 LOCATION='PC440_1',
 CDS_LIB='pure_quanta',
 CDS_PART_NAME='Q_CAP_C0402-1UF,25V,10%,X6S,CH5104KEB02',
 VOLTAGE='25V',
 PART_NUMBER='CH5104KEB02',
 VALUE='1UF',
 PRIM_FILE='./archive_libs/logical/q_cap/chips/chips.prt';

PART_NAME
 PC441_2 'Q_CAP_C0402-1UF,25V,10%,X6S,CH5104KEB02':;

SECTION_NUMBER 1
 '@T6G_MB_LIB.T6G(SCH_1):PAGE197_I23@PURE_QUANTA.Q_CAP(CHIPS)':
 C_PATH='@t6g_mb_lib.t6g(sch_1):page197_i23@pure_quanta.q_cap(chips)',
 P_PATH='@t6g_mb_lib.t6g(sch_1):page222_i23@pure_quanta.q_cap(chips)',
 PATH='I23',
 DRAWING='@T6G_MB_LIB.T6G(SCH_1):PAGE197',
 TOLERANCE='10%',
 MATERIAL='X6S',
 PHYS_PAGE='222',
 XY='(3975,3175)',
 ROT='0',
 VER='1',
 PACK_TYPE='C0402',
 LOCATION='PC441_2',
 CDS_LIB='pure_quanta',
 CDS_PART_NAME='Q_CAP_C0402-1UF,25V,10%,X6S,CH5104KEB02',
 VOLTAGE='25V',
 PART_NUMBER='CH5104KEB02',
 VALUE='1UF',
 PRIM_FILE='./archive_libs/logical/q_cap/chips/chips.prt';

PART_NAME
 PC442_1 'Q_CAP_C0805-22UF,16V,20%,X6S,CH6223MEA01':;

SECTION_NUMBER 1
 '@T6G_MB_LIB.T6G(SCH_1):PAGE197_I44@PURE_QUANTA.Q_CAP(CHIPS)':
 C_PATH='@t6g_mb_lib.t6g(sch_1):page197_i44@pure_quanta.q_cap(chips)',
 P_PATH='@t6g_mb_lib.t6g(sch_1):page222_i44@pure_quanta.q_cap(chips)',
 PATH='I44',
 DRAWING='@T6G_MB_LIB.T6G(SCH_1):PAGE197',
 TOLERANCE='20%',
 MATERIAL='X6S',
 PHYS_PAGE='222',
 XY='(4000,5900)',
 ROT='0',
 VER='1',
 PACK_TYPE='C0805',
 LOCATION='PC442_1',
 CDS_LIB='pure_quanta',
 CDS_PART_NAME='Q_CAP_C0805-22UF,16V,20%,X6S,CH6223MEA01',
 VOLTAGE='16V',
 PART_NUMBER='CH6223MEA01',
 VALUE='22UF',
 PRIM_FILE='./archive_libs/logical/q_cap/chips/chips.prt';

PART_NAME
 PC443_2 'Q_CAP_C0805-22UF,16V,20%,X6S,CH6223MEA01':;

SECTION_NUMBER 1
 '@T6G_MB_LIB.T6G(SCH_1):PAGE197_I48@PURE_QUANTA.Q_CAP(CHIPS)':
 C_PATH='@t6g_mb_lib.t6g(sch_1):page197_i48@pure_quanta.q_cap(chips)',
 P_PATH='@t6g_mb_lib.t6g(sch_1):page222_i48@pure_quanta.q_cap(chips)',
 PATH='I48',
 DRAWING='@T6G_MB_LIB.T6G(SCH_1):PAGE197',
 TOLERANCE='20%',
 MATERIAL='X6S',
 PHYS_PAGE='222',
 XY='(4375,3175)',
 ROT='0',
 VER='1',
 PACK_TYPE='C0805',
 LOCATION='PC443_2',
 CDS_LIB='pure_quanta',
 CDS_PART_NAME='Q_CAP_C0805-22UF,16V,20%,X6S,CH6223MEA01',
 VOLTAGE='16V',
 PART_NUMBER='CH6223MEA01',
 VALUE='22UF',
 PRIM_FILE='./archive_libs/logical/q_cap/chips/chips.prt';

PART_NAME
 PC444_1 'Q_CAP_C0805-22UF,16V,20%,X6S,CH6223MEA01':;

SECTION_NUMBER 1
 '@T6G_MB_LIB.T6G(SCH_1):PAGE197_I66@PURE_QUANTA.Q_CAP(CHIPS)':
 C_PATH='@t6g_mb_lib.t6g(sch_1):page197_i66@pure_quanta.q_cap(chips)',
 P_PATH='@t6g_mb_lib.t6g(sch_1):page222_i66@pure_quanta.q_cap(chips)',
 PATH='I66',
 DRAWING='@T6G_MB_LIB.T6G(SCH_1):PAGE197',
 TOLERANCE='20%',
 MATERIAL='X6S',
 PHYS_PAGE='222',
 XY='(4250,5900)',
 ROT='0',
 VER='1',
 PACK_TYPE='C0805',
 LOCATION='PC444_1',
 CDS_LIB='pure_quanta',
 CDS_PART_NAME='Q_CAP_C0805-22UF,16V,20%,X6S,CH6223MEA01',
 VOLTAGE='16V',
 PART_NUMBER='CH6223MEA01',
 VALUE='22UF',
 PRIM_FILE='./archive_libs/logical/q_cap/chips/chips.prt';

PART_NAME
 PC445 'Q_CAP_0402-0.22UF,16V,10%,X7R,CH4223K1B00':;

SECTION_NUMBER 1
 '@T6G_MB_LIB.T6G(SCH_1):PAGE197_I47@PURE_QUANTA.Q_CAP(CHIPS)':
 C_PATH='@t6g_mb_lib.t6g(sch_1):page197_i47@pure_quanta.q_cap(chips)',
 P_PATH='@t6g_mb_lib.t6g(sch_1):page222_i47@pure_quanta.q_cap(chips)',
 PATH='I47',
 DRAWING='@T6G_MB_LIB.T6G(SCH_1):PAGE197',
 TOLERANCE='10%',
 MATERIAL='X7R',
 PHYS_PAGE='222',
 XY='(4650,2475)',
 ROT='0',
 VER='1',
 PACK_TYPE='0402',
 LOCATION='PC445',
 CDS_LIB='pure_quanta',
 CDS_PART_NAME='Q_CAP_0402-0.22UF,16V,10%,X7R,CH4223K1B00',
 VOLTAGE='16V',
 PART_NUMBER='CH4223K1B00',
 VALUE='0.22UF',
 PRIM_FILE='./archive_libs/logical/q_cap/chips/chips.prt';

PART_NAME
 PC446_2 'Q_CAP_C0805-22UF,16V,20%,X6S,CH6223MEA01':;

SECTION_NUMBER 1
 '@T6G_MB_LIB.T6G(SCH_1):PAGE197_I49@PURE_QUANTA.Q_CAP(CHIPS)':
 C_PATH='@t6g_mb_lib.t6g(sch_1):page197_i49@pure_quanta.q_cap(chips)',
 P_PATH='@t6g_mb_lib.t6g(sch_1):page222_i49@pure_quanta.q_cap(chips)',
 PATH='I49',
 DRAWING='@T6G_MB_LIB.T6G(SCH_1):PAGE197',
 TOLERANCE='20%',
 MATERIAL='X6S',
 PHYS_PAGE='222',
 XY='(4775,3175)',
 ROT='0',
 VER='1',
 PACK_TYPE='C0805',
 LOCATION='PC446_2',
 CDS_LIB='pure_quanta',
 CDS_PART_NAME='Q_CAP_C0805-22UF,16V,20%,X6S,CH6223MEA01',
 VOLTAGE='16V',
 PART_NUMBER='CH6223MEA01',
 VALUE='22UF',
 PRIM_FILE='./archive_libs/logical/q_cap/chips/chips.prt';

PART_NAME
 PC447 'Q_CAP_0402-0.22UF,16V,10%,X7R,CH4223K1B00':;

SECTION_NUMBER 1
 '@T6G_MB_LIB.T6G(SCH_1):PAGE197_I65@PURE_QUANTA.Q_CAP(CHIPS)':
 C_PATH='@t6g_mb_lib.t6g(sch_1):page197_i65@pure_quanta.q_cap(chips)',
 P_PATH='@t6g_mb_lib.t6g(sch_1):page222_i65@pure_quanta.q_cap(chips)',
 PATH='I65',
 DRAWING='@T6G_MB_LIB.T6G(SCH_1):PAGE197',
 TOLERANCE='10%',
 MATERIAL='X7R',
 PHYS_PAGE='222',
 XY='(5000,5225)',
 ROT='0',
 VER='1',
 PACK_TYPE='0402',
 LOCATION='PC447',
 CDS_LIB='pure_quanta',
 CDS_PART_NAME='Q_CAP_0402-0.22UF,16V,10%,X7R,CH4223K1B00',
 VOLTAGE='16V',
 PART_NUMBER='CH4223K1B00',
 VALUE='0.22UF',
 PRIM_FILE='./archive_libs/logical/q_cap/chips/chips.prt';

PART_NAME
 PC448_1 'Q_CAP_C0805-22UF,16V,20%,X6S,CH6223MEA01':;

SECTION_NUMBER 1
 '@T6G_MB_LIB.T6G(SCH_1):PAGE197_I69@PURE_QUANTA.Q_CAP(CHIPS)':
 C_PATH='@t6g_mb_lib.t6g(sch_1):page197_i69@pure_quanta.q_cap(chips)',
 P_PATH='@t6g_mb_lib.t6g(sch_1):page222_i69@pure_quanta.q_cap(chips)',
 PATH='I69',
 DRAWING='@T6G_MB_LIB.T6G(SCH_1):PAGE197',
 TOLERANCE='20%',
 MATERIAL='X6S',
 PHYS_PAGE='222',
 XY='(4775,5925)',
 ROT='0',
 VER='1',
 PACK_TYPE='C0805',
 LOCATION='PC448_1',
 CDS_LIB='pure_quanta',
 CDS_PART_NAME='Q_CAP_C0805-22UF,16V,20%,X6S,CH6223MEA01',
 VOLTAGE='16V',
 PART_NUMBER='CH6223MEA01',
 VALUE='22UF',
 PRIM_FILE='./archive_libs/logical/q_cap/chips/chips.prt';

PART_NAME
 PC449_2 'Q_CAP_C0805-22UF,16V,20%,X6S,CH6223MEA01':;

SECTION_NUMBER 1
 '@T6G_MB_LIB.T6G(SCH_1):PAGE197_I52@PURE_QUANTA.Q_CAP(CHIPS)':
 C_PATH='@t6g_mb_lib.t6g(sch_1):page197_i52@pure_quanta.q_cap(chips)',
 P_PATH='@t6g_mb_lib.t6g(sch_1):page222_i52@pure_quanta.q_cap(chips)',
 PATH='I52',
 DRAWING='@T6G_MB_LIB.T6G(SCH_1):PAGE197',
 TOLERANCE='20%',
 MATERIAL='X6S',
 PHYS_PAGE='222',
 XY='(5250,3175)',
 ROT='0',
 VER='1',
 PACK_TYPE='C0805',
 LOCATION='PC449_2',
 CDS_LIB='pure_quanta',
 CDS_PART_NAME='Q_CAP_C0805-22UF,16V,20%,X6S,CH6223MEA01',
 VOLTAGE='16V',
 PART_NUMBER='CH6223MEA01',
 VALUE='22UF',
 PRIM_FILE='./archive_libs/logical/q_cap/chips/chips.prt';

PART_NAME
 PC450 'Q_CAPP_SMLF-470UF,2.5V,20%,SPCAP,CH747LM8825':;

SECTION_NUMBER 1
 '@T6G_MB_LIB.T6G(SCH_1):PAGE197_I58@PURE_QUANTA.Q_CAPP(CHIPS)':
 C_PATH='@t6g_mb_lib.t6g(sch_1):page197_i58@pure_quanta.q_capp(chips)',
 P_PATH='@t6g_mb_lib.t6g(sch_1):page222_i58@pure_quanta.q_capp(chips)',
 PATH='I58',
 DRAWING='@T6G_MB_LIB.T6G(SCH_1):PAGE197',
 TOLERANCE='20%',
 MATERIAL='SPCAP',
 PHYS_PAGE='222',
 XY='(7000,3275)',
 ROT='0',
 VER='1',
 PACK_TYPE='SMLF',
 LOCATION='PC450',
 CDS_LIB='pure_quanta',
 CDS_PART_NAME='Q_CAPP_SMLF-470UF,2.5V,20%,SPCAP,CH747LM8825',
 VOLTAGE='2.5V',
 PART_NUMBER='CH747LM8825',
 VALUE='470UF',
 PRIM_FILE='./archive_libs/logical/q_capp/chips/chips.prt';

PART_NAME
 PC451 'Q_CAP_C0402-100NF,50V,10%,X7R,CH4106K1B01':;

SECTION_NUMBER 1
 '@T6G_MB_LIB.T6G(SCH_1):PAGE197_I77@PURE_QUANTA.Q_CAP(CHIPS)':
 C_PATH='@t6g_mb_lib.t6g(sch_1):page197_i77@pure_quanta.q_cap(chips)',
 P_PATH='@t6g_mb_lib.t6g(sch_1):page222_i77@pure_quanta.q_cap(chips)',
 PATH='I77',
 DRAWING='@T6G_MB_LIB.T6G(SCH_1):PAGE197',
 TOLERANCE='10%',
 MATERIAL='X7R',
 PHYS_PAGE='222',
 XY='(7175,4800)',
 ROT='0',
 VER='1',
 PACK_TYPE='C0402',
 LOCATION='PC451',
 CDS_LIB='pure_quanta',
 CDS_PART_NAME='Q_CAP_C0402-100NF,50V,10%,X7R,CH4106K1B01',
 VOLTAGE='50V',
 PART_NUMBER='CH4106K1B01',
 VALUE='100NF',
 PRIM_FILE='./archive_libs/logical/q_cap/chips/chips.prt';

PART_NAME
 PC452 'Q_CAPP_SMLF-470UF,2.5V,20%,SPCAP,CH747LM8825':;

SECTION_NUMBER 1
 '@T6G_MB_LIB.T6G(SCH_1):PAGE197_I59@PURE_QUANTA.Q_CAPP(CHIPS)':
 C_PATH='@t6g_mb_lib.t6g(sch_1):page197_i59@pure_quanta.q_capp(chips)',
 P_PATH='@t6g_mb_lib.t6g(sch_1):page222_i59@pure_quanta.q_capp(chips)',
 PATH='I59',
 DRAWING='@T6G_MB_LIB.T6G(SCH_1):PAGE197',
 TOLERANCE='20%',
 MATERIAL='SPCAP',
 PHYS_PAGE='222',
 XY='(7400,3275)',
 ROT='0',
 VER='1',
 PACK_TYPE='SMLF',
 LOCATION='PC452',
 CDS_LIB='pure_quanta',
 CDS_PART_NAME='Q_CAPP_SMLF-470UF,2.5V,20%,SPCAP,CH747LM8825',
 VOLTAGE='2.5V',
 PART_NUMBER='CH747LM8825',
 VALUE='470UF',
 PRIM_FILE='./archive_libs/logical/q_capp/chips/chips.prt';

PART_NAME
 PC454 'Q_CAPP_SMLF-270UF,16V,20%,OSCON,CC72703MZ11':;

SECTION_NUMBER 1
 '@T6G_MB_LIB.T6G(SCH_1):PAGE197_I85@PURE_QUANTA.Q_CAPP(CHIPS)':
 C_PATH='@t6g_mb_lib.t6g(sch_1):page197_i85@pure_quanta.q_capp(chips)',
 P_PATH='@t6g_mb_lib.t6g(sch_1):page222_i85@pure_quanta.q_capp(chips)',
 PATH='I85',
 DRAWING='@T6G_MB_LIB.T6G(SCH_1):PAGE197',
 TOLERANCE='20%',
 MATERIAL='OSCON',
 PHYS_PAGE='222',
 XY='(5075,5925)',
 ROT='0',
 VER='1',
 PACK_TYPE='SMLF',
 LOCATION='PC454',
 CDS_LIB='pure_quanta',
 CDS_PART_NAME='Q_CAPP_SMLF-270UF,16V,20%,OSCON,CC72703MZ11',
 VOLTAGE='16V',
 PART_NUMBER='CC72703MZ11',
 VALUE='270UF',
 PRIM_FILE='./archive_libs/logical/q_capp/chips/chips.prt';

PART_NAME
 PC455 'Q_CAPP_SMLF-470UF,2.5V,20%,EMPTY,CH747LM8825':;

SECTION_NUMBER 1
 '@T6G_MB_LIB.T6G(SCH_1):PAGE197_I62@PURE_QUANTA.Q_CAPP(CHIPS)':
 C_PATH='@t6g_mb_lib.t6g(sch_1):page197_i62@pure_quanta.q_capp(chips)',
 P_PATH='@t6g_mb_lib.t6g(sch_1):page222_i62@pure_quanta.q_capp(chips)',
 PATH='I62',
 DRAWING='@T6G_MB_LIB.T6G(SCH_1):PAGE197',
 TOLERANCE='20%',
 MATERIAL='EMPTY',
 PHYS_PAGE='222',
 XY='(7800,3275)',
 ROT='0',
 VER='1',
 PACK_TYPE='SMLF',
 LOCATION='PC455',
 CDS_LIB='pure_quanta',
 CDS_PART_NAME='Q_CAPP_SMLF-470UF,2.5V,20%,EMPTY,CH747LM8825',
 VOLTAGE='2.5V',
 PART_NUMBER='CH747LM8825',
 VALUE='470UF',
 PRIM_FILE='./archive_libs/logical/q_capp/chips/chips.prt';

PART_NAME
 PC456_1 'Q_CAP_C0805-22UF,4V,20%,X6S,CH622KMEA03':;

SECTION_NUMBER 1
 '@T6G_MB_LIB.T6G(SCH_1):PAGE197_I78@PURE_QUANTA.Q_CAP(CHIPS)':
 C_PATH='@t6g_mb_lib.t6g(sch_1):page197_i78@pure_quanta.q_cap(chips)',
 P_PATH='@t6g_mb_lib.t6g(sch_1):page222_i78@pure_quanta.q_cap(chips)',
 PATH='I78',
 DRAWING='@T6G_MB_LIB.T6G(SCH_1):PAGE197',
 TOLERANCE='20%',
 MATERIAL='X6S',
 PHYS_PAGE='222',
 XY='(7500,4800)',
 ROT='0',
 VER='1',
 PACK_TYPE='C0805',
 LOCATION='PC456_1',
 CDS_LIB='pure_quanta',
 CDS_PART_NAME='Q_CAP_C0805-22UF,4V,20%,X6S,CH622KMEA03',
 VOLTAGE='4V',
 PART_NUMBER='CH622KMEA03',
 VALUE='22UF',
 PRIM_FILE='./archive_libs/logical/q_cap/chips/chips.prt';

PART_NAME
 PC458_2 'Q_CAP_C0805-22UF,4V,20%,X6S,CH622KMEA03':;

SECTION_NUMBER 1
 '@T6G_MB_LIB.T6G(SCH_1):PAGE197_I55@PURE_QUANTA.Q_CAP(CHIPS)':
 C_PATH='@t6g_mb_lib.t6g(sch_1):page197_i55@pure_quanta.q_cap(chips)',
 P_PATH='@t6g_mb_lib.t6g(sch_1):page222_i55@pure_quanta.q_cap(chips)',
 PATH='I55',
 DRAWING='@T6G_MB_LIB.T6G(SCH_1):PAGE197',
 TOLERANCE='20%',
 MATERIAL='X6S',
 PHYS_PAGE='222',
 XY='(7475,2050)',
 ROT='0',
 VER='1',
 PACK_TYPE='C0805',
 LOCATION='PC458_2',
 CDS_LIB='pure_quanta',
 CDS_PART_NAME='Q_CAP_C0805-22UF,4V,20%,X6S,CH622KMEA03',
 VOLTAGE='4V',
 PART_NUMBER='CH622KMEA03',
 VALUE='22UF',
 PRIM_FILE='./archive_libs/logical/q_cap/chips/chips.prt';

PART_NAME
 PC459_1 'Q_CAP_C0805-22UF,4V,20%,X6S,CH622KMEA03':;

SECTION_NUMBER 1
 '@T6G_MB_LIB.T6G(SCH_1):PAGE197_I79@PURE_QUANTA.Q_CAP(CHIPS)':
 C_PATH='@t6g_mb_lib.t6g(sch_1):page197_i79@pure_quanta.q_cap(chips)',
 P_PATH='@t6g_mb_lib.t6g(sch_1):page222_i79@pure_quanta.q_cap(chips)',
 PATH='I79',
 DRAWING='@T6G_MB_LIB.T6G(SCH_1):PAGE197',
 TOLERANCE='20%',
 MATERIAL='X6S',
 PHYS_PAGE='222',
 XY='(7950,4800)',
 ROT='0',
 VER='1',
 PACK_TYPE='C0805',
 LOCATION='PC459_1',
 CDS_LIB='pure_quanta',
 CDS_PART_NAME='Q_CAP_C0805-22UF,4V,20%,X6S,CH622KMEA03',
 VOLTAGE='4V',
 PART_NUMBER='CH622KMEA03',
 VALUE='22UF',
 PRIM_FILE='./archive_libs/logical/q_cap/chips/chips.prt';

PART_NAME
 PC460_2 'Q_CAP_C0805-22UF,4V,20%,X6S,CH622KMEA03':;

SECTION_NUMBER 1
 '@T6G_MB_LIB.T6G(SCH_1):PAGE197_I57@PURE_QUANTA.Q_CAP(CHIPS)':
 C_PATH='@t6g_mb_lib.t6g(sch_1):page197_i57@pure_quanta.q_cap(chips)',
 P_PATH='@t6g_mb_lib.t6g(sch_1):page222_i57@pure_quanta.q_cap(chips)',
 PATH='I57',
 DRAWING='@T6G_MB_LIB.T6G(SCH_1):PAGE197',
 TOLERANCE='20%',
 MATERIAL='X6S',
 PHYS_PAGE='222',
 XY='(7900,2050)',
 ROT='0',
 VER='1',
 PACK_TYPE='C0805',
 LOCATION='PC460_2',
 CDS_LIB='pure_quanta',
 CDS_PART_NAME='Q_CAP_C0805-22UF,4V,20%,X6S,CH622KMEA03',
 VOLTAGE='4V',
 PART_NUMBER='CH622KMEA03',
 VALUE='22UF',
 PRIM_FILE='./archive_libs/logical/q_cap/chips/chips.prt';

PART_NAME
 PC462 'Q_CAP_0402-0.1UF,25V,10%,X7R,CH4104K1B00':;

SECTION_NUMBER 1
 '@T6G_MB_LIB.T6G(SCH_1):PAGE168_I23@PURE_QUANTA.Q_CAP(CHIPS)':
 C_PATH='@t6g_mb_lib.t6g(sch_1):page168_i23@pure_quanta.q_cap(chips)',
 P_PATH='@t6g_mb_lib.t6g(sch_1):page193_i23@pure_quanta.q_cap(chips)',
 PATH='I23',
 DRAWING='@T6G_MB_LIB.T6G(SCH_1):PAGE168',
 TOLERANCE='10%',
 MATERIAL='X7R',
 PHYS_PAGE='193',
 XY='(-6050,1025)',
 ROT='0',
 VER='1',
 PACK_TYPE='0402',
 LOCATION='PC462',
 CDS_LIB='pure_quanta',
 CDS_PART_NAME='Q_CAP_0402-0.1UF,25V,10%,X7R,CH4104K1B00',
 VOLTAGE='25V',
 PART_NUMBER='CH4104K1B00',
 VALUE='0.1UF',
 PRIM_FILE='./archive_libs/logical/q_cap/chips/chips.prt';

PART_NAME
 PC463 'Q_CAP_0402-3300PF,50V,10%,X7R,TMP_QCH2336K1B12':;

SECTION_NUMBER 1
 '@T6G_MB_LIB.T6G(SCH_1):PAGE168_I62@PURE_QUANTA.Q_CAP(CHIPS)':
 C_PATH='@t6g_mb_lib.t6g(sch_1):page168_i62@pure_quanta.q_cap(chips)',
 P_PATH='@t6g_mb_lib.t6g(sch_1):page193_i62@pure_quanta.q_cap(chips)',
 PATH='I62',
 DRAWING='@T6G_MB_LIB.T6G(SCH_1):PAGE168',
 TOLERANCE='10%',
 MATERIAL='X7R',
 PHYS_PAGE='193',
 XY='(-5325,4325)',
 ROT='0',
 VER='1',
 PACK_TYPE='0402',
 LOCATION='PC463',
 CDS_LIB='pure_quanta',
 CDS_PART_NAME='Q_CAP_0402-3300PF,50V,10%,X7R,TMP_QCH2336K1B12',
 VOLTAGE='50V',
 PART_NUMBER='TMP_QCH2336K1B12',
 VALUE='3300PF',
 PRIM_FILE='./archive_libs/logical/q_cap/chips/chips.prt';

PART_NAME
 PC464 'Q_CAP_0402-3300PF,50V,10%,X7R,TMP_QCH2336K1B12':;

SECTION_NUMBER 1
 '@T6G_MB_LIB.T6G(SCH_1):PAGE168_I60@PURE_QUANTA.Q_CAP(CHIPS)':
 C_PATH='@t6g_mb_lib.t6g(sch_1):page168_i60@pure_quanta.q_cap(chips)',
 P_PATH='@t6g_mb_lib.t6g(sch_1):page193_i60@pure_quanta.q_cap(chips)',
 PATH='I60',
 DRAWING='@T6G_MB_LIB.T6G(SCH_1):PAGE168',
 TOLERANCE='10%',
 MATERIAL='X7R',
 PHYS_PAGE='193',
 XY='(-5250,3225)',
 ROT='0',
 VER='1',
 PACK_TYPE='0402',
 LOCATION='PC464',
 CDS_LIB='pure_quanta',
 CDS_PART_NAME='Q_CAP_0402-3300PF,50V,10%,X7R,TMP_QCH2336K1B12',
 VOLTAGE='50V',
 PART_NUMBER='TMP_QCH2336K1B12',
 VALUE='3300PF',
 PRIM_FILE='./archive_libs/logical/q_cap/chips/chips.prt';

PART_NAME
 PC466 'Q_CAP_0402-1UF,6.3V,10%,X7R,CH5101K1B01':;

SECTION_NUMBER 1
 '@T6G_MB_LIB.T6G(SCH_1):PAGE168_I52@PURE_QUANTA.Q_CAP(CHIPS)':
 C_PATH='@t6g_mb_lib.t6g(sch_1):page168_i52@pure_quanta.q_cap(chips)',
 P_PATH='@t6g_mb_lib.t6g(sch_1):page193_i52@pure_quanta.q_cap(chips)',
 PATH='I52',
 DRAWING='@T6G_MB_LIB.T6G(SCH_1):PAGE168',
 TOLERANCE='10%',
 MATERIAL='X7R',
 PHYS_PAGE='193',
 XY='(-5250,2125)',
 ROT='0',
 VER='2',
 PACK_TYPE='0402',
 LOCATION='PC466',
 CDS_LIB='pure_quanta',
 CDS_PART_NAME='Q_CAP_0402-1UF,6.3V,10%,X7R,CH5101K1B01',
 VOLTAGE='6.3V',
 PART_NUMBER='CH5101K1B01',
 VALUE='1UF',
 PRIM_FILE='./archive_libs/logical/q_cap/chips/chips.prt';

PART_NAME
 PC469 'Q_CAP_0402-470PF,50V,10%,X7R,TMP_QCH14706KB18':;

SECTION_NUMBER 1
 '@T6G_MB_LIB.T6G(SCH_1):PAGE168_I95@PURE_QUANTA.Q_CAP(CHIPS)':
 C_PATH='@t6g_mb_lib.t6g(sch_1):page168_i95@pure_quanta.q_cap(chips)',
 P_PATH='@t6g_mb_lib.t6g(sch_1):page193_i95@pure_quanta.q_cap(chips)',
 PATH='I95',
 DRAWING='@T6G_MB_LIB.T6G(SCH_1):PAGE168',
 TOLERANCE='10%',
 MATERIAL='X7R',
 PHYS_PAGE='193',
 XY='(-2950,1100)',
 ROT='0',
 VER='1',
 PACK_TYPE='0402',
 LOCATION='PC469',
 CDS_LIB='pure_quanta',
 CDS_PART_NAME='Q_CAP_0402-470PF,50V,10%,X7R,TMP_QCH14706KB18',
 VOLTAGE='50V',
 PART_NUMBER='TMP_QCH14706KB18',
 VALUE='470PF',
 PRIM_FILE='./archive_libs/logical/q_cap/chips/chips.prt';

PART_NAME
 PC470 'Q_CAP_C0402-10UF,6.3V,20%,X6S,CH6101MEB03':;

SECTION_NUMBER 1
 '@T6G_MB_LIB.T6G(SCH_1):PAGE168_I129@PURE_QUANTA.Q_CAP(CHIPS)':
 C_PATH='@t6g_mb_lib.t6g(sch_1):page168_i129@pure_quanta.q_cap(chips)',
 P_PATH='@t6g_mb_lib.t6g(sch_1):page193_i129@pure_quanta.q_cap(chips)',
 PATH='I129',
 DRAWING='@T6G_MB_LIB.T6G(SCH_1):PAGE168',
 TOLERANCE='20%',
 MATERIAL='X6S',
 PHYS_PAGE='193',
 XY='(-2500,6050)',
 ROT='0',
 VER='1',
 PACK_TYPE='C0402',
 LOCATION='PC470',
 CDS_LIB='pure_quanta',
 CDS_PART_NAME='Q_CAP_C0402-10UF,6.3V,20%,X6S,CH6101MEB03',
 VOLTAGE='6.3V',
 PART_NUMBER='CH6101MEB03',
 VALUE='10UF',
 PRIM_FILE='./archive_libs/logical/q_cap/chips/chips.prt';

PART_NAME
 PC471 'Q_CAP_C0402-1UF,16V,10%,X6S,CH5103KEB01':;

SECTION_NUMBER 1
 '@T6G_MB_LIB.T6G(SCH_1):PAGE168_I131@PURE_QUANTA.Q_CAP(CHIPS)':
 C_PATH='@t6g_mb_lib.t6g(sch_1):page168_i131@pure_quanta.q_cap(chips)',
 P_PATH='@t6g_mb_lib.t6g(sch_1):page193_i131@pure_quanta.q_cap(chips)',
 PATH='I131',
 DRAWING='@T6G_MB_LIB.T6G(SCH_1):PAGE168',
 TOLERANCE='10%',
 MATERIAL='X6S',
 PHYS_PAGE='193',
 XY='(-2475,6525)',
 ROT='0',
 VER='1',
 PACK_TYPE='C0402',
 LOCATION='PC471',
 CDS_LIB='pure_quanta',
 CDS_PART_NAME='Q_CAP_C0402-1UF,16V,10%,X6S,CH5103KEB01',
 VOLTAGE='16V',
 PART_NUMBER='CH5103KEB01',
 VALUE='1UF',
 PRIM_FILE='./archive_libs/logical/q_cap/chips/chips.prt';

PART_NAME
 PC472 'Q_CAP_0402-470PF,50V,10%,X7R,TMP_QCH14706KB18':;

SECTION_NUMBER 1
 '@T6G_MB_LIB.T6G(SCH_1):PAGE168_I98@PURE_QUANTA.Q_CAP(CHIPS)':
 C_PATH='@t6g_mb_lib.t6g(sch_1):page168_i98@pure_quanta.q_cap(chips)',
 P_PATH='@t6g_mb_lib.t6g(sch_1):page193_i98@pure_quanta.q_cap(chips)',
 PATH='I98',
 DRAWING='@T6G_MB_LIB.T6G(SCH_1):PAGE168',
 TOLERANCE='10%',
 MATERIAL='X7R',
 PHYS_PAGE='193',
 XY='(-2325,1425)',
 ROT='0',
 VER='1',
 PACK_TYPE='0402',
 LOCATION='PC472',
 CDS_LIB='pure_quanta',
 CDS_PART_NAME='Q_CAP_0402-470PF,50V,10%,X7R,TMP_QCH14706KB18',
 VOLTAGE='50V',
 PART_NUMBER='TMP_QCH14706KB18',
 VALUE='470PF',
 PRIM_FILE='./archive_libs/logical/q_cap/chips/chips.prt';

PART_NAME
 PC473 'Q_CAPP_SMLF-100UF,16V,20%,OSCON,CC71003MZ30':;

SECTION_NUMBER 1
 '@T6G_MB_LIB.T6G(SCH_1):PAGE478_I88@PURE_QUANTA.Q_CAPP(CHIPS)':
 C_PATH='@t6g_mb_lib.t6g(sch_1):page478_i88@pure_quanta.q_capp(chips)',
 P_PATH='@t6g_mb_lib.t6g(sch_1):page365_i88@pure_quanta.q_capp(chips)',
 PATH='I88',
 DRAWING='@T6G_MB_LIB.T6G(SCH_1):PAGE478',
 TOLERANCE='20%',
 MATERIAL='OSCON',
 PHYS_PAGE='365',
 XY='(-2250,2225)',
 ROT='0',
 VER='1',
 PACK_TYPE='SMLF',
 LOCATION='PC473',
 CDS_LIB='pure_quanta',
 CDS_PART_NAME='Q_CAPP_SMLF-100UF,16V,20%,OSCON,CC71003MZ30',
 VOLTAGE='16V',
 PART_NUMBER='CC71003MZ30',
 VALUE='100UF',
 PRIM_FILE='./archive_libs/logical/q_capp/chips/chips.prt';

PART_NAME
 PC473_1 'Q_CAP_0402-0.1UF,25V,10%,X7R,CH4104K1B00':;

SECTION_NUMBER 1
 '@T6G_MB_LIB.T6G(SCH_1):PAGE169_I22@PURE_QUANTA.Q_CAP(CHIPS)':
 C_PATH='@t6g_mb_lib.t6g(sch_1):page169_i22@pure_quanta.q_cap(chips)',
 P_PATH='@t6g_mb_lib.t6g(sch_1):page194_i22@pure_quanta.q_cap(chips)',
 PATH='I22',
 DRAWING='@T6G_MB_LIB.T6G(SCH_1):PAGE169',
 TOLERANCE='10%',
 MATERIAL='X7R',
 PHYS_PAGE='194',
 XY='(-8025,4075)',
 ROT='0',
 VER='1',
 PACK_TYPE='0402',
 LOCATION='PC473_1',
 CDS_LIB='pure_quanta',
 CDS_PART_NAME='Q_CAP_0402-0.1UF,25V,10%,X7R,CH4104K1B00',
 VOLTAGE='25V',
 PART_NUMBER='CH4104K1B00',
 VALUE='0.1UF',
 PRIM_FILE='./archive_libs/logical/q_cap/chips/chips.prt';

PART_NAME
 PC474_2 'Q_CAP_0402-0.1UF,25V,10%,X7R,CH4104K1B00':;

SECTION_NUMBER 1
 '@T6G_MB_LIB.T6G(SCH_1):PAGE169_I8@PURE_QUANTA.Q_CAP(CHIPS)':
 C_PATH='@t6g_mb_lib.t6g(sch_1):page169_i8@pure_quanta.q_cap(chips)',
 P_PATH='@t6g_mb_lib.t6g(sch_1):page194_i8@pure_quanta.q_cap(chips)',
 PATH='I8',
 DRAWING='@T6G_MB_LIB.T6G(SCH_1):PAGE169',
 TOLERANCE='10%',
 MATERIAL='X7R',
 PHYS_PAGE='194',
 XY='(-8000,1325)',
 ROT='0',
 VER='1',
 PACK_TYPE='0402',
 LOCATION='PC474_2',
 CDS_LIB='pure_quanta',
 CDS_PART_NAME='Q_CAP_0402-0.1UF,25V,10%,X7R,CH4104K1B00',
 VOLTAGE='25V',
 PART_NUMBER='CH4104K1B00',
 VALUE='0.1UF',
 PRIM_FILE='./archive_libs/logical/q_cap/chips/chips.prt';

PART_NAME
 PC475 'Q_CAP_C0402-2.2UF,10V,10%,X6S,CH5222KEB01':;

SECTION_NUMBER 1
 '@T6G_MB_LIB.T6G(SCH_1):PAGE169_I45@PURE_QUANTA.Q_CAP(CHIPS)':
 C_PATH='@t6g_mb_lib.t6g(sch_1):page169_i45@pure_quanta.q_cap(chips)',
 P_PATH='@t6g_mb_lib.t6g(sch_1):page194_i45@pure_quanta.q_cap(chips)',
 PATH='I45',
 DRAWING='@T6G_MB_LIB.T6G(SCH_1):PAGE169',
 TOLERANCE='10%',
 MATERIAL='X6S',
 PHYS_PAGE='194',
 XY='(-7975,4700)',
 ROT='0',
 VER='1',
 PACK_TYPE='C0402',
 LOCATION='PC475',
 CDS_LIB='pure_quanta',
 CDS_PART_NAME='Q_CAP_C0402-2.2UF,10V,10%,X6S,CH5222KEB01',
 VOLTAGE='10V',
 PART_NUMBER='CH5222KEB01',
 VALUE='2.2UF',
 PRIM_FILE='./archive_libs/logical/q_cap/chips/chips.prt';

PART_NAME
 PC476 'Q_CAP_C0402-2.2UF,10V,10%,X6S,CH5222KEB01':;

SECTION_NUMBER 1
 '@T6G_MB_LIB.T6G(SCH_1):PAGE169_I14@PURE_QUANTA.Q_CAP(CHIPS)':
 C_PATH='@t6g_mb_lib.t6g(sch_1):page169_i14@pure_quanta.q_cap(chips)',
 P_PATH='@t6g_mb_lib.t6g(sch_1):page194_i14@pure_quanta.q_cap(chips)',
 PATH='I14',
 DRAWING='@T6G_MB_LIB.T6G(SCH_1):PAGE169',
 TOLERANCE='10%',
 MATERIAL='X6S',
 PHYS_PAGE='194',
 XY='(-7650,1950)',
 ROT='0',
 VER='1',
 PACK_TYPE='C0402',
 LOCATION='PC476',
 CDS_LIB='pure_quanta',
 CDS_PART_NAME='Q_CAP_C0402-2.2UF,10V,10%,X6S,CH5222KEB01',
 VOLTAGE='10V',
 PART_NUMBER='CH5222KEB01',
 VALUE='2.2UF',
 PRIM_FILE='./archive_libs/logical/q_cap/chips/chips.prt';

PART_NAME
 PC477_C0P0_1 'Q_CAP_C0402-2.2UF,10V,10%,X6S,CH5222KEB01':;

SECTION_NUMBER 1
 '@T6G_MB_LIB.T6G(SCH_1):PAGE169_I51@PURE_QUANTA.Q_CAP(CHIPS)':
 C_PATH='@t6g_mb_lib.t6g(sch_1):page169_i51@pure_quanta.q_cap(chips)',
 P_PATH='@t6g_mb_lib.t6g(sch_1):page194_i51@pure_quanta.q_cap(chips)',
 PATH='I51',
 DRAWING='@T6G_MB_LIB.T6G(SCH_1):PAGE169',
 TOLERANCE='10%',
 MATERIAL='X6S',
 PHYS_PAGE='194',
 XY='(-7625,5200)',
 ROT='0',
 VER='1',
 PACK_TYPE='C0402',
 LOCATION='PC477_C0P0_1',
 CDS_LIB='pure_quanta',
 CDS_PART_NAME='Q_CAP_C0402-2.2UF,10V,10%,X6S,CH5222KEB01',
 VOLTAGE='10V',
 PART_NUMBER='CH5222KEB01',
 VALUE='2.2UF',
 PRIM_FILE='./archive_libs/logical/q_cap/chips/chips.prt';

PART_NAME
 PC478_C0P0_2 'Q_CAP_C0402-2.2UF,10V,10%,X6S,CH5222KEB01':;

SECTION_NUMBER 1
 '@T6G_MB_LIB.T6G(SCH_1):PAGE169_I19@PURE_QUANTA.Q_CAP(CHIPS)':
 C_PATH='@t6g_mb_lib.t6g(sch_1):page169_i19@pure_quanta.q_cap(chips)',
 P_PATH='@t6g_mb_lib.t6g(sch_1):page194_i19@pure_quanta.q_cap(chips)',
 PATH='I19',
 DRAWING='@T6G_MB_LIB.T6G(SCH_1):PAGE169',
 TOLERANCE='10%',
 MATERIAL='X6S',
 PHYS_PAGE='194',
 XY='(-7300,2475)',
 ROT='0',
 VER='1',
 PACK_TYPE='C0402',
 LOCATION='PC478_C0P0_2',
 CDS_LIB='pure_quanta',
 CDS_PART_NAME='Q_CAP_C0402-2.2UF,10V,10%,X6S,CH5222KEB01',
 VOLTAGE='10V',
 PART_NUMBER='CH5222KEB01',
 VALUE='2.2UF',
 PRIM_FILE='./archive_libs/logical/q_cap/chips/chips.prt';

PART_NAME
 PC479 'Q_CAP_0402-0.1UF,25V,10%,X7R,CH4104K1B00':;

SECTION_NUMBER 1
 '@T6G_MB_LIB.T6G(SCH_1):PAGE169_I85@PURE_QUANTA.Q_CAP(CHIPS)':
 C_PATH='@t6g_mb_lib.t6g(sch_1):page169_i85@pure_quanta.q_cap(chips)',
 P_PATH='@t6g_mb_lib.t6g(sch_1):page194_i85@pure_quanta.q_cap(chips)',
 PATH='I85',
 DRAWING='@T6G_MB_LIB.T6G(SCH_1):PAGE169',
 TOLERANCE='10%',
 MATERIAL='X7R',
 PHYS_PAGE='194',
 XY='(-2700,5250)',
 ROT='0',
 VER='1',
 PACK_TYPE='0402',
 LOCATION='PC479',
 CDS_LIB='pure_quanta',
 CDS_PART_NAME='Q_CAP_0402-0.1UF,25V,10%,X7R,CH4104K1B00',
 VOLTAGE='25V',
 PART_NUMBER='CH4104K1B00',
 VALUE='0.1UF',
 PRIM_FILE='./archive_libs/logical/q_cap/chips/chips.prt';

PART_NAME
 PC479_1 'Q_CAP_0402-0.1UF,25V,10%,X7R,CH4104K1B00':;

SECTION_NUMBER 1
 '@T6G_MB_LIB.T6G(SCH_1):PAGE169_I52@PURE_QUANTA.Q_CAP(CHIPS)':
 C_PATH='@t6g_mb_lib.t6g(sch_1):page169_i52@pure_quanta.q_cap(chips)',
 P_PATH='@t6g_mb_lib.t6g(sch_1):page194_i52@pure_quanta.q_cap(chips)',
 PATH='I52',
 DRAWING='@T6G_MB_LIB.T6G(SCH_1):PAGE169',
 TOLERANCE='10%',
 MATERIAL='X7R',
 PHYS_PAGE='194',
 XY='(-5550,5225)',
 ROT='0',
 VER='1',
 PACK_TYPE='0402',
 LOCATION='PC479_1',
 CDS_LIB='pure_quanta',
 CDS_PART_NAME='Q_CAP_0402-0.1UF,25V,10%,X7R,CH4104K1B00',
 VOLTAGE='25V',
 PART_NUMBER='CH4104K1B00',
 VALUE='0.1UF',
 PRIM_FILE='./archive_libs/logical/q_cap/chips/chips.prt';

PART_NAME
 PC480_2 'Q_CAP_C0402-1UF,25V,10%,X6S,CH5104KEB02':;

SECTION_NUMBER 1
 '@T6G_MB_LIB.T6G(SCH_1):PAGE169_I34@PURE_QUANTA.Q_CAP(CHIPS)':
 C_PATH='@t6g_mb_lib.t6g(sch_1):page169_i34@pure_quanta.q_cap(chips)',
 P_PATH='@t6g_mb_lib.t6g(sch_1):page194_i34@pure_quanta.q_cap(chips)',
 PATH='I34',
 DRAWING='@T6G_MB_LIB.T6G(SCH_1):PAGE169',
 TOLERANCE='10%',
 MATERIAL='X6S',
 PHYS_PAGE='194',
 XY='(-5225,2475)',
 ROT='0',
 VER='1',
 PACK_TYPE='C0402',
 LOCATION='PC480_2',
 CDS_LIB='pure_quanta',
 CDS_PART_NAME='Q_CAP_C0402-1UF,25V,10%,X6S,CH5104KEB02',
 VOLTAGE='25V',
 PART_NUMBER='CH5104KEB02',
 VALUE='1UF',
 PRIM_FILE='./archive_libs/logical/q_cap/chips/chips.prt';

PART_NAME
 PC481_1 'Q_CAP_C0402-1UF,25V,10%,X6S,CH5104KEB02':;

SECTION_NUMBER 1
 '@T6G_MB_LIB.T6G(SCH_1):PAGE169_I53@PURE_QUANTA.Q_CAP(CHIPS)':
 C_PATH='@t6g_mb_lib.t6g(sch_1):page169_i53@pure_quanta.q_cap(chips)',
 P_PATH='@t6g_mb_lib.t6g(sch_1):page194_i53@pure_quanta.q_cap(chips)',
 PATH='I53',
 DRAWING='@T6G_MB_LIB.T6G(SCH_1):PAGE169',
 TOLERANCE='10%',
 MATERIAL='X6S',
 PHYS_PAGE='194',
 XY='(-5225,5225)',
 ROT='0',
 VER='1',
 PACK_TYPE='C0402',
 LOCATION='PC481_1',
 CDS_LIB='pure_quanta',
 CDS_PART_NAME='Q_CAP_C0402-1UF,25V,10%,X6S,CH5104KEB02',
 VOLTAGE='25V',
 PART_NUMBER='CH5104KEB02',
 VALUE='1UF',
 PRIM_FILE='./archive_libs/logical/q_cap/chips/chips.prt';

PART_NAME
 PC482_2 'Q_CAP_0402-0.1UF,25V,10%,X7R,CH4104K1B00':;

SECTION_NUMBER 1
 '@T6G_MB_LIB.T6G(SCH_1):PAGE169_I33@PURE_QUANTA.Q_CAP(CHIPS)':
 C_PATH='@t6g_mb_lib.t6g(sch_1):page169_i33@pure_quanta.q_cap(chips)',
 P_PATH='@t6g_mb_lib.t6g(sch_1):page194_i33@pure_quanta.q_cap(chips)',
 PATH='I33',
 DRAWING='@T6G_MB_LIB.T6G(SCH_1):PAGE169',
 TOLERANCE='10%',
 MATERIAL='X7R',
 PHYS_PAGE='194',
 XY='(-5550,2475)',
 ROT='0',
 VER='1',
 PACK_TYPE='0402',
 LOCATION='PC482_2',
 CDS_LIB='pure_quanta',
 CDS_PART_NAME='Q_CAP_0402-0.1UF,25V,10%,X7R,CH4104K1B00',
 VOLTAGE='25V',
 PART_NUMBER='CH4104K1B00',
 VALUE='0.1UF',
 PRIM_FILE='./archive_libs/logical/q_cap/chips/chips.prt';

PART_NAME
 PC483_1 'Q_CAP_C0805-22UF,16V,20%,X6S,CH6223MEA01':;

SECTION_NUMBER 1
 '@T6G_MB_LIB.T6G(SCH_1):PAGE169_I57@PURE_QUANTA.Q_CAP(CHIPS)':
 C_PATH='@t6g_mb_lib.t6g(sch_1):page169_i57@pure_quanta.q_cap(chips)',
 P_PATH='@t6g_mb_lib.t6g(sch_1):page194_i57@pure_quanta.q_cap(chips)',
 PATH='I57',
 DRAWING='@T6G_MB_LIB.T6G(SCH_1):PAGE169',
 TOLERANCE='20%',
 MATERIAL='X6S',
 PHYS_PAGE='194',
 XY='(-4900,5225)',
 ROT='0',
 VER='1',
 PACK_TYPE='C0805',
 LOCATION='PC483_1',
 CDS_LIB='pure_quanta',
 CDS_PART_NAME='Q_CAP_C0805-22UF,16V,20%,X6S,CH6223MEA01',
 VOLTAGE='16V',
 PART_NUMBER='CH6223MEA01',
 VALUE='22UF',
 PRIM_FILE='./archive_libs/logical/q_cap/chips/chips.prt';

PART_NAME
 PC484_2 'Q_CAP_C0805-22UF,16V,20%,X6S,CH6223MEA01':;

SECTION_NUMBER 1
 '@T6G_MB_LIB.T6G(SCH_1):PAGE169_I36@PURE_QUANTA.Q_CAP(CHIPS)':
 C_PATH='@t6g_mb_lib.t6g(sch_1):page169_i36@pure_quanta.q_cap(chips)',
 P_PATH='@t6g_mb_lib.t6g(sch_1):page194_i36@pure_quanta.q_cap(chips)',
 PATH='I36',
 DRAWING='@T6G_MB_LIB.T6G(SCH_1):PAGE169',
 TOLERANCE='20%',
 MATERIAL='X6S',
 PHYS_PAGE='194',
 XY='(-4900,2475)',
 ROT='0',
 VER='1',
 PACK_TYPE='C0805',
 LOCATION='PC484_2',
 CDS_LIB='pure_quanta',
 CDS_PART_NAME='Q_CAP_C0805-22UF,16V,20%,X6S,CH6223MEA01',
 VOLTAGE='16V',
 PART_NUMBER='CH6223MEA01',
 VALUE='22UF',
 PRIM_FILE='./archive_libs/logical/q_cap/chips/chips.prt';

PART_NAME
 PC485_1 'Q_CAP_C0805-22UF,16V,20%,X6S,CH6223MEA01':;

SECTION_NUMBER 1
 '@T6G_MB_LIB.T6G(SCH_1):PAGE169_I58@PURE_QUANTA.Q_CAP(CHIPS)':
 C_PATH='@t6g_mb_lib.t6g(sch_1):page169_i58@pure_quanta.q_cap(chips)',
 P_PATH='@t6g_mb_lib.t6g(sch_1):page194_i58@pure_quanta.q_cap(chips)',
 PATH='I58',
 DRAWING='@T6G_MB_LIB.T6G(SCH_1):PAGE169',
 TOLERANCE='20%',
 MATERIAL='X6S',
 PHYS_PAGE='194',
 XY='(-4575,5225)',
 ROT='0',
 VER='1',
 PACK_TYPE='C0805',
 LOCATION='PC485_1',
 CDS_LIB='pure_quanta',
 CDS_PART_NAME='Q_CAP_C0805-22UF,16V,20%,X6S,CH6223MEA01',
 VOLTAGE='16V',
 PART_NUMBER='CH6223MEA01',
 VALUE='22UF',
 PRIM_FILE='./archive_libs/logical/q_cap/chips/chips.prt';

PART_NAME
 PC486_2 'Q_CAP_C0805-22UF,16V,20%,X6S,CH6223MEA01':;

SECTION_NUMBER 1
 '@T6G_MB_LIB.T6G(SCH_1):PAGE169_I37@PURE_QUANTA.Q_CAP(CHIPS)':
 C_PATH='@t6g_mb_lib.t6g(sch_1):page169_i37@pure_quanta.q_cap(chips)',
 P_PATH='@t6g_mb_lib.t6g(sch_1):page194_i37@pure_quanta.q_cap(chips)',
 PATH='I37',
 DRAWING='@T6G_MB_LIB.T6G(SCH_1):PAGE169',
 TOLERANCE='20%',
 MATERIAL='X6S',
 PHYS_PAGE='194',
 XY='(-4575,2475)',
 ROT='0',
 VER='1',
 PACK_TYPE='C0805',
 LOCATION='PC486_2',
 CDS_LIB='pure_quanta',
 CDS_PART_NAME='Q_CAP_C0805-22UF,16V,20%,X6S,CH6223MEA01',
 VOLTAGE='16V',
 PART_NUMBER='CH6223MEA01',
 VALUE='22UF',
 PRIM_FILE='./archive_libs/logical/q_cap/chips/chips.prt';

PART_NAME
 PC487_1 'Q_CAP_C0805-22UF,16V,20%,X6S,CH6223MEA01':;

SECTION_NUMBER 1
 '@T6G_MB_LIB.T6G(SCH_1):PAGE169_I59@PURE_QUANTA.Q_CAP(CHIPS)':
 C_PATH='@t6g_mb_lib.t6g(sch_1):page169_i59@pure_quanta.q_cap(chips)',
 P_PATH='@t6g_mb_lib.t6g(sch_1):page194_i59@pure_quanta.q_cap(chips)',
 PATH='I59',
 DRAWING='@T6G_MB_LIB.T6G(SCH_1):PAGE169',
 TOLERANCE='20%',
 MATERIAL='X6S',
 PHYS_PAGE='194',
 XY='(-4275,5225)',
 ROT='0',
 VER='1',
 PACK_TYPE='C0805',
 LOCATION='PC487_1',
 CDS_LIB='pure_quanta',
 CDS_PART_NAME='Q_CAP_C0805-22UF,16V,20%,X6S,CH6223MEA01',
 VOLTAGE='16V',
 PART_NUMBER='CH6223MEA01',
 VALUE='22UF',
 PRIM_FILE='./archive_libs/logical/q_cap/chips/chips.prt';

PART_NAME
 PC488_2 'Q_CAP_C0805-22UF,16V,20%,X6S,CH6223MEA01':;

SECTION_NUMBER 1
 '@T6G_MB_LIB.T6G(SCH_1):PAGE169_I39@PURE_QUANTA.Q_CAP(CHIPS)':
 C_PATH='@t6g_mb_lib.t6g(sch_1):page169_i39@pure_quanta.q_cap(chips)',
 P_PATH='@t6g_mb_lib.t6g(sch_1):page194_i39@pure_quanta.q_cap(chips)',
 PATH='I39',
 DRAWING='@T6G_MB_LIB.T6G(SCH_1):PAGE169',
 TOLERANCE='20%',
 MATERIAL='X6S',
 PHYS_PAGE='194',
 XY='(-4275,2475)',
 ROT='0',
 VER='1',
 PACK_TYPE='C0805',
 LOCATION='PC488_2',
 CDS_LIB='pure_quanta',
 CDS_PART_NAME='Q_CAP_C0805-22UF,16V,20%,X6S,CH6223MEA01',
 VOLTAGE='16V',
 PART_NUMBER='CH6223MEA01',
 VALUE='22UF',
 PRIM_FILE='./archive_libs/logical/q_cap/chips/chips.prt';

PART_NAME
 PC489 'Q_CAP_0402-0.22UF,16V,10%,X7R,CH4223K1B00':;

SECTION_NUMBER 1
 '@T6G_MB_LIB.T6G(SCH_1):PAGE169_I76@PURE_QUANTA.Q_CAP(CHIPS)':
 C_PATH='@t6g_mb_lib.t6g(sch_1):page169_i76@pure_quanta.q_cap(chips)',
 P_PATH='@t6g_mb_lib.t6g(sch_1):page194_i76@pure_quanta.q_cap(chips)',
 PATH='I76',
 DRAWING='@T6G_MB_LIB.T6G(SCH_1):PAGE169',
 TOLERANCE='10%',
 MATERIAL='X7R',
 PHYS_PAGE='194',
 XY='(-4000,4575)',
 ROT='0',
 VER='1',
 PACK_TYPE='0402',
 LOCATION='PC489',
 CDS_LIB='pure_quanta',
 CDS_PART_NAME='Q_CAP_0402-0.22UF,16V,10%,X7R,CH4223K1B00',
 VOLTAGE='16V',
 PART_NUMBER='CH4223K1B00',
 VALUE='0.22UF',
 PRIM_FILE='./archive_libs/logical/q_cap/chips/chips.prt';

PART_NAME
 PC490 'Q_CAP_0402-0.22UF,16V,10%,X7R,CH4223K1B00':;

SECTION_NUMBER 1
 '@T6G_MB_LIB.T6G(SCH_1):PAGE169_I61@PURE_QUANTA.Q_CAP(CHIPS)':
 C_PATH='@t6g_mb_lib.t6g(sch_1):page169_i61@pure_quanta.q_cap(chips)',
 P_PATH='@t6g_mb_lib.t6g(sch_1):page194_i61@pure_quanta.q_cap(chips)',
 PATH='I61',
 DRAWING='@T6G_MB_LIB.T6G(SCH_1):PAGE169',
 TOLERANCE='10%',
 MATERIAL='X7R',
 PHYS_PAGE='194',
 XY='(-3750,1825)',
 ROT='0',
 VER='1',
 PACK_TYPE='0402',
 LOCATION='PC490',
 CDS_LIB='pure_quanta',
 CDS_PART_NAME='Q_CAP_0402-0.22UF,16V,10%,X7R,CH4223K1B00',
 VOLTAGE='16V',
 PART_NUMBER='CH4223K1B00',
 VALUE='0.22UF',
 PRIM_FILE='./archive_libs/logical/q_cap/chips/chips.prt';

PART_NAME
 PC491 'Q_CAPP_THLF-270UF,16V,20%,OSCON,CC72703MD38':;

SECTION_NUMBER 1
 '@T6G_MB_LIB.T6G(SCH_1):PAGE169_I79@PURE_QUANTA.Q_CAPP(CHIPS)':
 C_PATH='@t6g_mb_lib.t6g(sch_1):page169_i79@pure_quanta.q_capp(chips)',
 P_PATH='@t6g_mb_lib.t6g(sch_1):page194_i79@pure_quanta.q_capp(chips)',
 PATH='I79',
 DRAWING='@T6G_MB_LIB.T6G(SCH_1):PAGE169',
 TOLERANCE='20%',
 MATERIAL='OSCON',
 PHYS_PAGE='194',
 XY='(-3950,5225)',
 ROT='0',
 VER='1',
 PACK_TYPE='THLF',
 LOCATION='PC491',
 CDS_LIB='pure_quanta',
 CDS_PART_NAME='Q_CAPP_THLF-270UF,16V,20%,OSCON,CC72703MD38',
 VOLTAGE='16V',
 PART_NUMBER='CC72703MD38',
 VALUE='270UF',
 PRIM_FILE='./archive_libs/logical/q_capp/chips/chips.prt';

PART_NAME
 PC492 'Q_CAPP_THLF-270UF,16V,20%,OSCON,CC72703MD38':;

SECTION_NUMBER 1
 '@T6G_MB_LIB.T6G(SCH_1):PAGE169_I81@PURE_QUANTA.Q_CAPP(CHIPS)':
 C_PATH='@t6g_mb_lib.t6g(sch_1):page169_i81@pure_quanta.q_capp(chips)',
 P_PATH='@t6g_mb_lib.t6g(sch_1):page194_i81@pure_quanta.q_capp(chips)',
 PATH='I81',
 DRAWING='@T6G_MB_LIB.T6G(SCH_1):PAGE169',
 TOLERANCE='20%',
 MATERIAL='OSCON',
 PHYS_PAGE='194',
 XY='(-3525,5225)',
 ROT='0',
 VER='1',
 PACK_TYPE='THLF',
 LOCATION='PC492',
 CDS_LIB='pure_quanta',
 CDS_PART_NAME='Q_CAPP_THLF-270UF,16V,20%,OSCON,CC72703MD38',
 VOLTAGE='16V',
 PART_NUMBER='CC72703MD38',
 VALUE='270UF',
 PRIM_FILE='./archive_libs/logical/q_capp/chips/chips.prt';

PART_NAME
 PC494 'Q_CAPP_SMLF-220UF,4V,20%,SPCAP,CH122KM8801':;

SECTION_NUMBER 1
 '@T6G_MB_LIB.T6G(SCH_1):PAGE169_I65@PURE_QUANTA.Q_CAPP(CHIPS)':
 C_PATH='@t6g_mb_lib.t6g(sch_1):page169_i65@pure_quanta.q_capp(chips)',
 P_PATH='@t6g_mb_lib.t6g(sch_1):page194_i65@pure_quanta.q_capp(chips)',
 PATH='I65',
 DRAWING='@T6G_MB_LIB.T6G(SCH_1):PAGE169',
 TOLERANCE='20%',
 MATERIAL='SPCAP',
 PHYS_PAGE='194',
 XY='(-2825,2800)',
 ROT='0',
 VER='1',
 PACK_TYPE='SMLF',
 LOCATION='PC494',
 CDS_LIB='pure_quanta',
 CDS_PART_NAME='Q_CAPP_SMLF-220UF,4V,20%,SPCAP,CH122KM8801',
 VOLTAGE='4V',
 PART_NUMBER='CH122KM8801',
 VALUE='220UF',
 PRIM_FILE='./archive_libs/logical/q_capp/chips/chips.prt';

PART_NAME
 PC495 'Q_CAPP_SMLF-220UF,4V,20%,SPCAP,CH122KM8801':;

SECTION_NUMBER 1
 '@T6G_MB_LIB.T6G(SCH_1):PAGE169_I66@PURE_QUANTA.Q_CAPP(CHIPS)':
 C_PATH='@t6g_mb_lib.t6g(sch_1):page169_i66@pure_quanta.q_capp(chips)',
 P_PATH='@t6g_mb_lib.t6g(sch_1):page194_i66@pure_quanta.q_capp(chips)',
 PATH='I66',
 DRAWING='@T6G_MB_LIB.T6G(SCH_1):PAGE169',
 TOLERANCE='20%',
 MATERIAL='SPCAP',
 PHYS_PAGE='194',
 XY='(-2500,2800)',
 ROT='0',
 VER='1',
 PACK_TYPE='SMLF',
 LOCATION='PC495',
 CDS_LIB='pure_quanta',
 CDS_PART_NAME='Q_CAPP_SMLF-220UF,4V,20%,SPCAP,CH122KM8801',
 VOLTAGE='4V',
 PART_NUMBER='CH122KM8801',
 VALUE='220UF',
 PRIM_FILE='./archive_libs/logical/q_capp/chips/chips.prt';

PART_NAME
 PC496 'Q_CAPP_SMLF-220UF,4V,20%,SPCAP,CH122KM8801':;

SECTION_NUMBER 1
 '@T6G_MB_LIB.T6G(SCH_1):PAGE169_I67@PURE_QUANTA.Q_CAPP(CHIPS)':
 C_PATH='@t6g_mb_lib.t6g(sch_1):page169_i67@pure_quanta.q_capp(chips)',
 P_PATH='@t6g_mb_lib.t6g(sch_1):page194_i67@pure_quanta.q_capp(chips)',
 PATH='I67',
 DRAWING='@T6G_MB_LIB.T6G(SCH_1):PAGE169',
 TOLERANCE='20%',
 MATERIAL='SPCAP',
 PHYS_PAGE='194',
 XY='(-2175,2800)',
 ROT='0',
 VER='1',
 PACK_TYPE='SMLF',
 LOCATION='PC496',
 CDS_LIB='pure_quanta',
 CDS_PART_NAME='Q_CAPP_SMLF-220UF,4V,20%,SPCAP,CH122KM8801',
 VOLTAGE='4V',
 PART_NUMBER='CH122KM8801',
 VALUE='220UF',
 PRIM_FILE='./archive_libs/logical/q_capp/chips/chips.prt';

PART_NAME
 PC497 'Q_CAP_0402-0.1UF,25V,10%,X7R,CH4104K1B00':;

SECTION_NUMBER 1
 '@T6G_MB_LIB.T6G(SCH_1):PAGE169_I87@PURE_QUANTA.Q_CAP(CHIPS)':
 C_PATH='@t6g_mb_lib.t6g(sch_1):page169_i87@pure_quanta.q_cap(chips)',
 P_PATH='@t6g_mb_lib.t6g(sch_1):page194_i87@pure_quanta.q_cap(chips)',
 PATH='I87',
 DRAWING='@T6G_MB_LIB.T6G(SCH_1):PAGE169',
 TOLERANCE='10%',
 MATERIAL='X7R',
 PHYS_PAGE='194',
 XY='(-2000,4175)',
 ROT='0',
 VER='1',
 PACK_TYPE='0402',
 LOCATION='PC497',
 CDS_LIB='pure_quanta',
 CDS_PART_NAME='Q_CAP_0402-0.1UF,25V,10%,X7R,CH4104K1B00',
 VOLTAGE='25V',
 PART_NUMBER='CH4104K1B00',
 VALUE='0.1UF',
 PRIM_FILE='./archive_libs/logical/q_cap/chips/chips.prt';

PART_NAME
 PC498 'Q_CAPP_SMLF-220UF,4V,20%,SPCAP,CH122KM8801':;

SECTION_NUMBER 1
 '@T6G_MB_LIB.T6G(SCH_1):PAGE169_I73@PURE_QUANTA.Q_CAPP(CHIPS)':
 C_PATH='@t6g_mb_lib.t6g(sch_1):page169_i73@pure_quanta.q_capp(chips)',
 P_PATH='@t6g_mb_lib.t6g(sch_1):page194_i73@pure_quanta.q_capp(chips)',
 PATH='I73',
 DRAWING='@T6G_MB_LIB.T6G(SCH_1):PAGE169',
 TOLERANCE='20%',
 MATERIAL='SPCAP',
 PHYS_PAGE='194',
 XY='(-1900,2800)',
 ROT='0',
 VER='1',
 PACK_TYPE='SMLF',
 LOCATION='PC498',
 CDS_LIB='pure_quanta',
 CDS_PART_NAME='Q_CAPP_SMLF-220UF,4V,20%,SPCAP,CH122KM8801',
 VOLTAGE='4V',
 PART_NUMBER='CH122KM8801',
 VALUE='220UF',
 PRIM_FILE='./archive_libs/logical/q_capp/chips/chips.prt';

PART_NAME
 PC499_2 'Q_CAP_C0805-22UF,4V,20%,X6S,CH622KMEA03':;

SECTION_NUMBER 1
 '@T6G_MB_LIB.T6G(SCH_1):PAGE169_I68@PURE_QUANTA.Q_CAP(CHIPS)':
 C_PATH='@t6g_mb_lib.t6g(sch_1):page169_i68@pure_quanta.q_cap(chips)',
 P_PATH='@t6g_mb_lib.t6g(sch_1):page194_i68@pure_quanta.q_cap(chips)',
 PATH='I68',
 DRAWING='@T6G_MB_LIB.T6G(SCH_1):PAGE169',
 TOLERANCE='20%',
 MATERIAL='X6S',
 PHYS_PAGE='194',
 XY='(-1725,1425)',
 ROT='0',
 VER='1',
 PACK_TYPE='C0805',
 LOCATION='PC499_2',
 CDS_LIB='pure_quanta',
 CDS_PART_NAME='Q_CAP_C0805-22UF,4V,20%,X6S,CH622KMEA03',
 VOLTAGE='4V',
 PART_NUMBER='CH622KMEA03',
 VALUE='22UF',
 PRIM_FILE='./archive_libs/logical/q_cap/chips/chips.prt';

PART_NAME
 PC500_1 'Q_CAP_C0805-22UF,4V,20%,X6S,CH622KMEA03':;

SECTION_NUMBER 1
 '@T6G_MB_LIB.T6G(SCH_1):PAGE169_I88@PURE_QUANTA.Q_CAP(CHIPS)':
 C_PATH='@t6g_mb_lib.t6g(sch_1):page169_i88@pure_quanta.q_cap(chips)',
 P_PATH='@t6g_mb_lib.t6g(sch_1):page194_i88@pure_quanta.q_cap(chips)',
 PATH='I88',
 DRAWING='@T6G_MB_LIB.T6G(SCH_1):PAGE169',
 TOLERANCE='20%',
 MATERIAL='X6S',
 PHYS_PAGE='194',
 XY='(-1625,4175)',
 ROT='0',
 VER='1',
 PACK_TYPE='C0805',
 LOCATION='PC500_1',
 CDS_LIB='pure_quanta',
 CDS_PART_NAME='Q_CAP_C0805-22UF,4V,20%,X6S,CH622KMEA03',
 VOLTAGE='4V',
 PART_NUMBER='CH622KMEA03',
 VALUE='22UF',
 PRIM_FILE='./archive_libs/logical/q_cap/chips/chips.prt';

PART_NAME
 PC501_2 'Q_CAP_C0805-22UF,4V,20%,X6S,CH622KMEA03':;

SECTION_NUMBER 1
 '@T6G_MB_LIB.T6G(SCH_1):PAGE169_I70@PURE_QUANTA.Q_CAP(CHIPS)':
 C_PATH='@t6g_mb_lib.t6g(sch_1):page169_i70@pure_quanta.q_cap(chips)',
 P_PATH='@t6g_mb_lib.t6g(sch_1):page194_i70@pure_quanta.q_cap(chips)',
 PATH='I70',
 DRAWING='@T6G_MB_LIB.T6G(SCH_1):PAGE169',
 TOLERANCE='20%',
 MATERIAL='X6S',
 PHYS_PAGE='194',
 XY='(-1300,1425)',
 ROT='0',
 VER='1',
 PACK_TYPE='C0805',
 LOCATION='PC501_2',
 CDS_LIB='pure_quanta',
 CDS_PART_NAME='Q_CAP_C0805-22UF,4V,20%,X6S,CH622KMEA03',
 VOLTAGE='4V',
 PART_NUMBER='CH622KMEA03',
 VALUE='22UF',
 PRIM_FILE='./archive_libs/logical/q_cap/chips/chips.prt';

PART_NAME
 PC502_1 'Q_CAP_C0805-22UF,4V,20%,X6S,CH622KMEA03':;

SECTION_NUMBER 1
 '@T6G_MB_LIB.T6G(SCH_1):PAGE169_I89@PURE_QUANTA.Q_CAP(CHIPS)':
 C_PATH='@t6g_mb_lib.t6g(sch_1):page169_i89@pure_quanta.q_cap(chips)',
 P_PATH='@t6g_mb_lib.t6g(sch_1):page194_i89@pure_quanta.q_cap(chips)',
 PATH='I89',
 DRAWING='@T6G_MB_LIB.T6G(SCH_1):PAGE169',
 TOLERANCE='20%',
 MATERIAL='X6S',
 PHYS_PAGE='194',
 XY='(-1175,4175)',
 ROT='0',
 VER='1',
 PACK_TYPE='C0805',
 LOCATION='PC502_1',
 CDS_LIB='pure_quanta',
 CDS_PART_NAME='Q_CAP_C0805-22UF,4V,20%,X6S,CH622KMEA03',
 VOLTAGE='4V',
 PART_NUMBER='CH622KMEA03',
 VALUE='22UF',
 PRIM_FILE='./archive_libs/logical/q_cap/chips/chips.prt';

PART_NAME
 PC503_1 'Q_CAP_0402-0.1UF,25V,10%,X7R,CH4104K1B00':;

SECTION_NUMBER 1
 '@T6G_MB_LIB.T6G(SCH_1):PAGE200_I34@PURE_QUANTA.Q_CAP(CHIPS)':
 C_PATH='@t6g_mb_lib.t6g(sch_1):page200_i34@pure_quanta.q_cap(chips)',
 P_PATH='@t6g_mb_lib.t6g(sch_1):page225_i34@pure_quanta.q_cap(chips)',
 PATH='I34',
 DRAWING='@T6G_MB_LIB.T6G(SCH_1):PAGE200',
 TOLERANCE='10%',
 MATERIAL='X7R',
 PHYS_PAGE='225',
 XY='(-7875,4350)',
 ROT='0',
 VER='1',
 PACK_TYPE='0402',
 LOCATION='PC503_1',
 CDS_LIB='pure_quanta',
 CDS_PART_NAME='Q_CAP_0402-0.1UF,25V,10%,X7R,CH4104K1B00',
 VOLTAGE='25V',
 PART_NUMBER='CH4104K1B00',
 VALUE='0.1UF',
 PRIM_FILE='./archive_libs/logical/q_cap/chips/chips.prt';

PART_NAME
 PC504_2 'Q_CAP_0402-0.1UF,25V,10%,X7R,CH4104K1B00':;

SECTION_NUMBER 1
 '@T6G_MB_LIB.T6G(SCH_1):PAGE200_I8@PURE_QUANTA.Q_CAP(CHIPS)':
 C_PATH='@t6g_mb_lib.t6g(sch_1):page200_i8@pure_quanta.q_cap(chips)',
 P_PATH='@t6g_mb_lib.t6g(sch_1):page225_i8@pure_quanta.q_cap(chips)',
 PATH='I8',
 DRAWING='@T6G_MB_LIB.T6G(SCH_1):PAGE200',
 TOLERANCE='10%',
 MATERIAL='X7R',
 PHYS_PAGE='225',
 XY='(-7825,1425)',
 ROT='0',
 VER='1',
 PACK_TYPE='0402',
 LOCATION='PC504_2',
 CDS_LIB='pure_quanta',
 CDS_PART_NAME='Q_CAP_0402-0.1UF,25V,10%,X7R,CH4104K1B00',
 VOLTAGE='25V',
 PART_NUMBER='CH4104K1B00',
 VALUE='0.1UF',
 PRIM_FILE='./archive_libs/logical/q_cap/chips/chips.prt';

PART_NAME
 PC505 'Q_CAP_C0402-2.2UF,10V,10%,X6S,CH5222KEB01':;

SECTION_NUMBER 1
 '@T6G_MB_LIB.T6G(SCH_1):PAGE200_I36@PURE_QUANTA.Q_CAP(CHIPS)':
 C_PATH='@t6g_mb_lib.t6g(sch_1):page200_i36@pure_quanta.q_cap(chips)',
 P_PATH='@t6g_mb_lib.t6g(sch_1):page225_i36@pure_quanta.q_cap(chips)',
 PATH='I36',
 DRAWING='@T6G_MB_LIB.T6G(SCH_1):PAGE200',
 TOLERANCE='10%',
 MATERIAL='X6S',
 PHYS_PAGE='225',
 XY='(-7775,4950)',
 ROT='0',
 VER='1',
 PACK_TYPE='C0402',
 LOCATION='PC505',
 CDS_LIB='pure_quanta',
 CDS_PART_NAME='Q_CAP_C0402-2.2UF,10V,10%,X6S,CH5222KEB01',
 VOLTAGE='10V',
 PART_NUMBER='CH5222KEB01',
 VALUE='2.2UF',
 PRIM_FILE='./archive_libs/logical/q_cap/chips/chips.prt';

PART_NAME
 PC506 'Q_CAP_C0402-2.2UF,10V,10%,X6S,CH5222KEB01':;

SECTION_NUMBER 1
 '@T6G_MB_LIB.T6G(SCH_1):PAGE200_I10@PURE_QUANTA.Q_CAP(CHIPS)':
 C_PATH='@t6g_mb_lib.t6g(sch_1):page200_i10@pure_quanta.q_cap(chips)',
 P_PATH='@t6g_mb_lib.t6g(sch_1):page225_i10@pure_quanta.q_cap(chips)',
 PATH='I10',
 DRAWING='@T6G_MB_LIB.T6G(SCH_1):PAGE200',
 TOLERANCE='10%',
 MATERIAL='X6S',
 PHYS_PAGE='225',
 XY='(-7775,2025)',
 ROT='0',
 VER='1',
 PACK_TYPE='C0402',
 LOCATION='PC506',
 CDS_LIB='pure_quanta',
 CDS_PART_NAME='Q_CAP_C0402-2.2UF,10V,10%,X6S,CH5222KEB01',
 VOLTAGE='10V',
 PART_NUMBER='CH5222KEB01',
 VALUE='2.2UF',
 PRIM_FILE='./archive_libs/logical/q_cap/chips/chips.prt';

PART_NAME
 PC507_11P1_1 'Q_CAP_C0402-2.2UF,10V,10%,X6S,CH5222KEB01':;

SECTION_NUMBER 1
 '@T6G_MB_LIB.T6G(SCH_1):PAGE200_I43@PURE_QUANTA.Q_CAP(CHIPS)':
 C_PATH='@t6g_mb_lib.t6g(sch_1):page200_i43@pure_quanta.q_cap(chips)',
 P_PATH='@t6g_mb_lib.t6g(sch_1):page225_i43@pure_quanta.q_cap(chips)',
 PATH='I43',
 DRAWING='@T6G_MB_LIB.T6G(SCH_1):PAGE200',
 TOLERANCE='10%',
 MATERIAL='X6S',
 PHYS_PAGE='225',
 XY='(-7425,5525)',
 ROT='0',
 VER='1',
 PACK_TYPE='C0402',
 LOCATION='PC507_11P1_1',
 CDS_LIB='pure_quanta',
 CDS_PART_NAME='Q_CAP_C0402-2.2UF,10V,10%,X6S,CH5222KEB01',
 VOLTAGE='10V',
 PART_NUMBER='CH5222KEB01',
 VALUE='2.2UF',
 PRIM_FILE='./archive_libs/logical/q_cap/chips/chips.prt';

PART_NAME
 PC508_11P1_2 'Q_CAP_C0402-2.2UF,10V,10%,X6S,CH5222KEB01':;

SECTION_NUMBER 1
 '@T6G_MB_LIB.T6G(SCH_1):PAGE200_I17@PURE_QUANTA.Q_CAP(CHIPS)':
 C_PATH='@t6g_mb_lib.t6g(sch_1):page200_i17@pure_quanta.q_cap(chips)',
 P_PATH='@t6g_mb_lib.t6g(sch_1):page225_i17@pure_quanta.q_cap(chips)',
 PATH='I17',
 DRAWING='@T6G_MB_LIB.T6G(SCH_1):PAGE200',
 TOLERANCE='10%',
 MATERIAL='X6S',
 PHYS_PAGE='225',
 XY='(-7425,2600)',
 ROT='0',
 VER='1',
 PACK_TYPE='C0402',
 LOCATION='PC508_11P1_2',
 CDS_LIB='pure_quanta',
 CDS_PART_NAME='Q_CAP_C0402-2.2UF,10V,10%,X6S,CH5222KEB01',
 VOLTAGE='10V',
 PART_NUMBER='CH5222KEB01',
 VALUE='2.2UF',
 PRIM_FILE='./archive_libs/logical/q_cap/chips/chips.prt';

PART_NAME
 PC509_1 'Q_CAP_0402-0.1UF,25V,10%,X7R,CH4104K1B00':;

SECTION_NUMBER 1
 '@T6G_MB_LIB.T6G(SCH_1):PAGE200_I48@PURE_QUANTA.Q_CAP(CHIPS)':
 C_PATH='@t6g_mb_lib.t6g(sch_1):page200_i48@pure_quanta.q_cap(chips)',
 P_PATH='@t6g_mb_lib.t6g(sch_1):page225_i48@pure_quanta.q_cap(chips)',
 PATH='I48',
 DRAWING='@T6G_MB_LIB.T6G(SCH_1):PAGE200',
 TOLERANCE='10%',
 MATERIAL='X7R',
 PHYS_PAGE='225',
 XY='(-5100,5525)',
 ROT='0',
 VER='1',
 PACK_TYPE='0402',
 LOCATION='PC509_1',
 CDS_LIB='pure_quanta',
 CDS_PART_NAME='Q_CAP_0402-0.1UF,25V,10%,X7R,CH4104K1B00',
 VOLTAGE='25V',
 PART_NUMBER='CH4104K1B00',
 VALUE='0.1UF',
 PRIM_FILE='./archive_libs/logical/q_cap/chips/chips.prt';

PART_NAME
 PC510_2 'Q_CAP_0402-0.1UF,25V,10%,X7R,CH4104K1B00':;

SECTION_NUMBER 1
 '@T6G_MB_LIB.T6G(SCH_1):PAGE200_I29@PURE_QUANTA.Q_CAP(CHIPS)':
 C_PATH='@t6g_mb_lib.t6g(sch_1):page200_i29@pure_quanta.q_cap(chips)',
 P_PATH='@t6g_mb_lib.t6g(sch_1):page225_i29@pure_quanta.q_cap(chips)',
 PATH='I29',
 DRAWING='@T6G_MB_LIB.T6G(SCH_1):PAGE200',
 TOLERANCE='10%',
 MATERIAL='X7R',
 PHYS_PAGE='225',
 XY='(-5000,2600)',
 ROT='0',
 VER='1',
 PACK_TYPE='0402',
 LOCATION='PC510_2',
 CDS_LIB='pure_quanta',
 CDS_PART_NAME='Q_CAP_0402-0.1UF,25V,10%,X7R,CH4104K1B00',
 VOLTAGE='25V',
 PART_NUMBER='CH4104K1B00',
 VALUE='0.1UF',
 PRIM_FILE='./archive_libs/logical/q_cap/chips/chips.prt';

PART_NAME
 PC511 'Q_CAP_0402-0.1UF,25V,10%,X7R,CH4104K1B00':;

SECTION_NUMBER 1
 '@T6G_MB_LIB.T6G(SCH_1):PAGE200_I85@PURE_QUANTA.Q_CAP(CHIPS)':
 C_PATH='@t6g_mb_lib.t6g(sch_1):page200_i85@pure_quanta.q_cap(chips)',
 P_PATH='@t6g_mb_lib.t6g(sch_1):page225_i85@pure_quanta.q_cap(chips)',
 PATH='I85',
 DRAWING='@T6G_MB_LIB.T6G(SCH_1):PAGE200',
 TOLERANCE='10%',
 MATERIAL='X7R',
 PHYS_PAGE='225',
 XY='(-2500,5550)',
 ROT='0',
 VER='1',
 PACK_TYPE='0402',
 LOCATION='PC511',
 CDS_LIB='pure_quanta',
 CDS_PART_NAME='Q_CAP_0402-0.1UF,25V,10%,X7R,CH4104K1B00',
 VOLTAGE='25V',
 PART_NUMBER='CH4104K1B00',
 VALUE='0.1UF',
 PRIM_FILE='./archive_libs/logical/q_cap/chips/chips.prt';

PART_NAME
 PC511_1 'Q_CAP_C0402-1UF,25V,10%,X6S,CH5104KEB02':;

SECTION_NUMBER 1
 '@T6G_MB_LIB.T6G(SCH_1):PAGE200_I45@PURE_QUANTA.Q_CAP(CHIPS)':
 C_PATH='@t6g_mb_lib.t6g(sch_1):page200_i45@pure_quanta.q_cap(chips)',
 P_PATH='@t6g_mb_lib.t6g(sch_1):page225_i45@pure_quanta.q_cap(chips)',
 PATH='I45',
 DRAWING='@T6G_MB_LIB.T6G(SCH_1):PAGE200',
 TOLERANCE='10%',
 MATERIAL='X6S',
 PHYS_PAGE='225',
 XY='(-5425,5525)',
 ROT='0',
 VER='1',
 PACK_TYPE='C0402',
 LOCATION='PC511_1',
 CDS_LIB='pure_quanta',
 CDS_PART_NAME='Q_CAP_C0402-1UF,25V,10%,X6S,CH5104KEB02',
 VOLTAGE='25V',
 PART_NUMBER='CH5104KEB02',
 VALUE='1UF',
 PRIM_FILE='./archive_libs/logical/q_cap/chips/chips.prt';

PART_NAME
 PC512_2 'Q_CAP_C0402-1UF,25V,10%,X6S,CH5104KEB02':;

SECTION_NUMBER 1
 '@T6G_MB_LIB.T6G(SCH_1):PAGE200_I91@PURE_QUANTA.Q_CAP(CHIPS)':
 C_PATH='@t6g_mb_lib.t6g(sch_1):page200_i91@pure_quanta.q_cap(chips)',
 P_PATH='@t6g_mb_lib.t6g(sch_1):page225_i91@pure_quanta.q_cap(chips)',
 PATH='I91',
 DRAWING='@T6G_MB_LIB.T6G(SCH_1):PAGE200',
 TOLERANCE='10%',
 MATERIAL='X6S',
 PHYS_PAGE='225',
 XY='(-5325,2600)',
 ROT='0',
 VER='1',
 PACK_TYPE='C0402',
 LOCATION='PC512_2',
 CDS_LIB='pure_quanta',
 CDS_PART_NAME='Q_CAP_C0402-1UF,25V,10%,X6S,CH5104KEB02',
 VOLTAGE='25V',
 PART_NUMBER='CH5104KEB02',
 VALUE='1UF',
 PRIM_FILE='./archive_libs/logical/q_cap/chips/chips.prt';

PART_NAME
 PC513_1 'Q_CAP_C0805-22UF,16V,20%,X6S,CH6223MEA01':;

SECTION_NUMBER 1
 '@T6G_MB_LIB.T6G(SCH_1):PAGE200_I49@PURE_QUANTA.Q_CAP(CHIPS)':
 C_PATH='@t6g_mb_lib.t6g(sch_1):page200_i49@pure_quanta.q_cap(chips)',
 P_PATH='@t6g_mb_lib.t6g(sch_1):page225_i49@pure_quanta.q_cap(chips)',
 PATH='I49',
 DRAWING='@T6G_MB_LIB.T6G(SCH_1):PAGE200',
 TOLERANCE='20%',
 MATERIAL='X6S',
 PHYS_PAGE='225',
 XY='(-4775,5525)',
 ROT='0',
 VER='1',
 PACK_TYPE='C0805',
 LOCATION='PC513_1',
 CDS_LIB='pure_quanta',
 CDS_PART_NAME='Q_CAP_C0805-22UF,16V,20%,X6S,CH6223MEA01',
 VOLTAGE='16V',
 PART_NUMBER='CH6223MEA01',
 VALUE='22UF',
 PRIM_FILE='./archive_libs/logical/q_cap/chips/chips.prt';

PART_NAME
 PC514 'Q_CAP_0402-0.1UF,25V,10%,EMPTY,CH4104K1B00':;

SECTION_NUMBER 1
 '@T6G_MB_LIB.T6G(SCH_1):PAGE477_I5@PURE_QUANTA.Q_CAP(CHIPS)':
 C_PATH='@t6g_mb_lib.t6g(sch_1):page477_i5@pure_quanta.q_cap(chips)',
 P_PATH='@t6g_mb_lib.t6g(sch_1):page364_i5@pure_quanta.q_cap(chips)',
 PATH='I5',
 DRAWING='@T6G_MB_LIB.T6G(SCH_1):PAGE477',
 TOLERANCE='10%',
 MATERIAL='EMPTY',
 PHYS_PAGE='364',
 XY='(-5875,400)',
 ROT='0',
 VER='1',
 PACK_TYPE='0402',
 LOCATION='PC514',
 CDS_LIB='pure_quanta',
 CDS_PART_NAME='Q_CAP_0402-0.1UF,25V,10%,EMPTY,CH4104K1B00',
 VOLTAGE='25V',
 PART_NUMBER='CH4104K1B00',
 VALUE='0.1UF',
 PRIM_FILE='./archive_libs/logical/q_cap/chips/chips.prt';

PART_NAME
 PC514_2 'Q_CAP_C0805-22UF,16V,20%,X6S,CH6223MEA01':;

SECTION_NUMBER 1
 '@T6G_MB_LIB.T6G(SCH_1):PAGE200_I30@PURE_QUANTA.Q_CAP(CHIPS)':
 C_PATH='@t6g_mb_lib.t6g(sch_1):page200_i30@pure_quanta.q_cap(chips)',
 P_PATH='@t6g_mb_lib.t6g(sch_1):page225_i30@pure_quanta.q_cap(chips)',
 PATH='I30',
 DRAWING='@T6G_MB_LIB.T6G(SCH_1):PAGE200',
 TOLERANCE='20%',
 MATERIAL='X6S',
 PHYS_PAGE='225',
 XY='(-4675,2600)',
 ROT='0',
 VER='1',
 PACK_TYPE='C0805',
 LOCATION='PC514_2',
 CDS_LIB='pure_quanta',
 CDS_PART_NAME='Q_CAP_C0805-22UF,16V,20%,X6S,CH6223MEA01',
 VOLTAGE='16V',
 PART_NUMBER='CH6223MEA01',
 VALUE='22UF',
 PRIM_FILE='./archive_libs/logical/q_cap/chips/chips.prt';

PART_NAME
 PC515_1 'Q_CAP_C0805-22UF,16V,20%,X6S,CH6223MEA01':;

SECTION_NUMBER 1
 '@T6G_MB_LIB.T6G(SCH_1):PAGE200_I50@PURE_QUANTA.Q_CAP(CHIPS)':
 C_PATH='@t6g_mb_lib.t6g(sch_1):page200_i50@pure_quanta.q_cap(chips)',
 P_PATH='@t6g_mb_lib.t6g(sch_1):page225_i50@pure_quanta.q_cap(chips)',
 PATH='I50',
 DRAWING='@T6G_MB_LIB.T6G(SCH_1):PAGE200',
 TOLERANCE='20%',
 MATERIAL='X6S',
 PHYS_PAGE='225',
 XY='(-4450,5525)',
 ROT='0',
 VER='1',
 PACK_TYPE='C0805',
 LOCATION='PC515_1',
 CDS_LIB='pure_quanta',
 CDS_PART_NAME='Q_CAP_C0805-22UF,16V,20%,X6S,CH6223MEA01',
 VOLTAGE='16V',
 PART_NUMBER='CH6223MEA01',
 VALUE='22UF',
 PRIM_FILE='./archive_libs/logical/q_cap/chips/chips.prt';

PART_NAME
 PC516_2 'Q_CAP_C0805-22UF,16V,20%,X6S,CH6223MEA01':;

SECTION_NUMBER 1
 '@T6G_MB_LIB.T6G(SCH_1):PAGE200_I31@PURE_QUANTA.Q_CAP(CHIPS)':
 C_PATH='@t6g_mb_lib.t6g(sch_1):page200_i31@pure_quanta.q_cap(chips)',
 P_PATH='@t6g_mb_lib.t6g(sch_1):page225_i31@pure_quanta.q_cap(chips)',
 PATH='I31',
 DRAWING='@T6G_MB_LIB.T6G(SCH_1):PAGE200',
 TOLERANCE='20%',
 MATERIAL='X6S',
 PHYS_PAGE='225',
 XY='(-4375,2600)',
 ROT='0',
 VER='1',
 PACK_TYPE='C0805',
 LOCATION='PC516_2',
 CDS_LIB='pure_quanta',
 CDS_PART_NAME='Q_CAP_C0805-22UF,16V,20%,X6S,CH6223MEA01',
 VOLTAGE='16V',
 PART_NUMBER='CH6223MEA01',
 VALUE='22UF',
 PRIM_FILE='./archive_libs/logical/q_cap/chips/chips.prt';

PART_NAME
 PC517_1 'Q_CAP_C0805-22UF,16V,20%,X6S,CH6223MEA01':;

SECTION_NUMBER 1
 '@T6G_MB_LIB.T6G(SCH_1):PAGE200_I51@PURE_QUANTA.Q_CAP(CHIPS)':
 C_PATH='@t6g_mb_lib.t6g(sch_1):page200_i51@pure_quanta.q_cap(chips)',
 P_PATH='@t6g_mb_lib.t6g(sch_1):page225_i51@pure_quanta.q_cap(chips)',
 PATH='I51',
 DRAWING='@T6G_MB_LIB.T6G(SCH_1):PAGE200',
 TOLERANCE='20%',
 MATERIAL='X6S',
 PHYS_PAGE='225',
 XY='(-4250,5525)',
 ROT='0',
 VER='1',
 PACK_TYPE='C0805',
 LOCATION='PC517_1',
 CDS_LIB='pure_quanta',
 CDS_PART_NAME='Q_CAP_C0805-22UF,16V,20%,X6S,CH6223MEA01',
 VOLTAGE='16V',
 PART_NUMBER='CH6223MEA01',
 VALUE='22UF',
 PRIM_FILE='./archive_libs/logical/q_cap/chips/chips.prt';

PART_NAME
 PC518_2 'Q_CAP_C0805-22UF,16V,20%,X6S,CH6223MEA01':;

SECTION_NUMBER 1
 '@T6G_MB_LIB.T6G(SCH_1):PAGE200_I52@PURE_QUANTA.Q_CAP(CHIPS)':
 C_PATH='@t6g_mb_lib.t6g(sch_1):page200_i52@pure_quanta.q_cap(chips)',
 P_PATH='@t6g_mb_lib.t6g(sch_1):page225_i52@pure_quanta.q_cap(chips)',
 PATH='I52',
 DRAWING='@T6G_MB_LIB.T6G(SCH_1):PAGE200',
 TOLERANCE='20%',
 MATERIAL='X6S',
 PHYS_PAGE='225',
 XY='(-4050,2600)',
 ROT='0',
 VER='1',
 PACK_TYPE='C0805',
 LOCATION='PC518_2',
 CDS_LIB='pure_quanta',
 CDS_PART_NAME='Q_CAP_C0805-22UF,16V,20%,X6S,CH6223MEA01',
 VOLTAGE='16V',
 PART_NUMBER='CH6223MEA01',
 VALUE='22UF',
 PRIM_FILE='./archive_libs/logical/q_cap/chips/chips.prt';

PART_NAME
 PC519 'Q_CAP_0402-0.22UF,16V,10%,X7R,CH4223K1B00':;

SECTION_NUMBER 1
 '@T6G_MB_LIB.T6G(SCH_1):PAGE200_I76@PURE_QUANTA.Q_CAP(CHIPS)':
 C_PATH='@t6g_mb_lib.t6g(sch_1):page200_i76@pure_quanta.q_cap(chips)',
 P_PATH='@t6g_mb_lib.t6g(sch_1):page225_i76@pure_quanta.q_cap(chips)',
 PATH='I76',
 DRAWING='@T6G_MB_LIB.T6G(SCH_1):PAGE200',
 TOLERANCE='10%',
 MATERIAL='X7R',
 PHYS_PAGE='225',
 XY='(-3875,4850)',
 ROT='0',
 VER='1',
 PACK_TYPE='0402',
 LOCATION='PC519',
 CDS_LIB='pure_quanta',
 CDS_PART_NAME='Q_CAP_0402-0.22UF,16V,10%,X7R,CH4223K1B00',
 VOLTAGE='16V',
 PART_NUMBER='CH4223K1B00',
 VALUE='0.22UF',
 PRIM_FILE='./archive_libs/logical/q_cap/chips/chips.prt';

PART_NAME
 PC520 'Q_CAP_0402-0.22UF,16V,10%,X7R,CH4223K1B00':;

SECTION_NUMBER 1
 '@T6G_MB_LIB.T6G(SCH_1):PAGE200_I54@PURE_QUANTA.Q_CAP(CHIPS)':
 C_PATH='@t6g_mb_lib.t6g(sch_1):page200_i54@pure_quanta.q_cap(chips)',
 P_PATH='@t6g_mb_lib.t6g(sch_1):page225_i54@pure_quanta.q_cap(chips)',
 PATH='I54',
 DRAWING='@T6G_MB_LIB.T6G(SCH_1):PAGE200',
 TOLERANCE='10%',
 MATERIAL='X7R',
 PHYS_PAGE='225',
 XY='(-3775,1925)',
 ROT='0',
 VER='1',
 PACK_TYPE='0402',
 LOCATION='PC520',
 CDS_LIB='pure_quanta',
 CDS_PART_NAME='Q_CAP_0402-0.22UF,16V,10%,X7R,CH4223K1B00',
 VOLTAGE='16V',
 PART_NUMBER='CH4223K1B00',
 VALUE='0.22UF',
 PRIM_FILE='./archive_libs/logical/q_cap/chips/chips.prt';

PART_NAME
 PC521_1 'Q_CAP_C0805-22UF,16V,20%,X6S,CH6223MEA01':;

SECTION_NUMBER 1
 '@T6G_MB_LIB.T6G(SCH_1):PAGE200_I80@PURE_QUANTA.Q_CAP(CHIPS)':
 C_PATH='@t6g_mb_lib.t6g(sch_1):page200_i80@pure_quanta.q_cap(chips)',
 P_PATH='@t6g_mb_lib.t6g(sch_1):page225_i80@pure_quanta.q_cap(chips)',
 PATH='I80',
 DRAWING='@T6G_MB_LIB.T6G(SCH_1):PAGE200',
 TOLERANCE='20%',
 MATERIAL='X6S',
 PHYS_PAGE='225',
 XY='(-4050,5525)',
 ROT='0',
 VER='1',
 PACK_TYPE='C0805',
 LOCATION='PC521_1',
 CDS_LIB='pure_quanta',
 CDS_PART_NAME='Q_CAP_C0805-22UF,16V,20%,X6S,CH6223MEA01',
 VOLTAGE='16V',
 PART_NUMBER='CH6223MEA01',
 VALUE='22UF',
 PRIM_FILE='./archive_libs/logical/q_cap/chips/chips.prt';

PART_NAME
 PC522 'Q_CAPP_THLF-270UF,16V,20%,OSCON,CC72703MD38':;

SECTION_NUMBER 1
 '@T6G_MB_LIB.T6G(SCH_1):PAGE200_I81@PURE_QUANTA.Q_CAPP(CHIPS)':
 C_PATH='@t6g_mb_lib.t6g(sch_1):page200_i81@pure_quanta.q_capp(chips)',
 P_PATH='@t6g_mb_lib.t6g(sch_1):page225_i81@pure_quanta.q_capp(chips)',
 PATH='I81',
 DRAWING='@T6G_MB_LIB.T6G(SCH_1):PAGE200',
 TOLERANCE='20%',
 MATERIAL='OSCON',
 PHYS_PAGE='225',
 XY='(-3350,5525)',
 ROT='0',
 VER='1',
 PACK_TYPE='THLF',
 LOCATION='PC522',
 CDS_LIB='pure_quanta',
 CDS_PART_NAME='Q_CAPP_THLF-270UF,16V,20%,OSCON,CC72703MD38',
 VOLTAGE='16V',
 PART_NUMBER='CC72703MD38',
 VALUE='270UF',
 PRIM_FILE='./archive_libs/logical/q_capp/chips/chips.prt';

PART_NAME
 PC523 'Q_CAP_0402-470PF,50V,10%,X7R,TMP_QCH14706KB18':;

SECTION_NUMBER 1
 '@T6G_MB_LIB.T6G(SCH_1):PAGE477_I51@PURE_QUANTA.Q_CAP(CHIPS)':
 C_PATH='@t6g_mb_lib.t6g(sch_1):page477_i51@pure_quanta.q_cap(chips)',
 P_PATH='@t6g_mb_lib.t6g(sch_1):page364_i51@pure_quanta.q_cap(chips)',
 PATH='I51',
 DRAWING='@T6G_MB_LIB.T6G(SCH_1):PAGE477',
 TOLERANCE='10%',
 MATERIAL='X7R',
 PHYS_PAGE='364',
 XY='(-2500,775)',
 ROT='0',
 VER='1',
 PACK_TYPE='0402',
 LOCATION='PC523',
 CDS_LIB='pure_quanta',
 CDS_PART_NAME='Q_CAP_0402-470PF,50V,10%,X7R,TMP_QCH14706KB18',
 VOLTAGE='50V',
 PART_NUMBER='TMP_QCH14706KB18',
 VALUE='470PF',
 PRIM_FILE='./archive_libs/logical/q_cap/chips/chips.prt';

PART_NAME
 PC523_2 'Q_CAP_C0805-22UF,4V,20%,X6S,CH622KMEA03':;

SECTION_NUMBER 1
 '@T6G_MB_LIB.T6G(SCH_1):PAGE200_I56@PURE_QUANTA.Q_CAP(CHIPS)':
 C_PATH='@t6g_mb_lib.t6g(sch_1):page200_i56@pure_quanta.q_cap(chips)',
 P_PATH='@t6g_mb_lib.t6g(sch_1):page225_i56@pure_quanta.q_cap(chips)',
 PATH='I56',
 DRAWING='@T6G_MB_LIB.T6G(SCH_1):PAGE200',
 TOLERANCE='20%',
 MATERIAL='X6S',
 PHYS_PAGE='225',
 XY='(-2375,1525)',
 ROT='0',
 VER='1',
 PACK_TYPE='C0805',
 LOCATION='PC523_2',
 CDS_LIB='pure_quanta',
 CDS_PART_NAME='Q_CAP_C0805-22UF,4V,20%,X6S,CH622KMEA03',
 VOLTAGE='4V',
 PART_NUMBER='CH622KMEA03',
 VALUE='22UF',
 PRIM_FILE='./archive_libs/logical/q_cap/chips/chips.prt';

PART_NAME
 PC524 'Q_CAP_C0402-100NF,50V,10%,X7R,CH4106K1B01':;

SECTION_NUMBER 1
 '@T6G_MB_LIB.T6G(SCH_1):PAGE200_I82@PURE_QUANTA.Q_CAP(CHIPS)':
 C_PATH='@t6g_mb_lib.t6g(sch_1):page200_i82@pure_quanta.q_cap(chips)',
 P_PATH='@t6g_mb_lib.t6g(sch_1):page225_i82@pure_quanta.q_cap(chips)',
 PATH='I82',
 DRAWING='@T6G_MB_LIB.T6G(SCH_1):PAGE200',
 TOLERANCE='10%',
 MATERIAL='X7R',
 PHYS_PAGE='225',
 XY='(-2300,4450)',
 ROT='0',
 VER='1',
 PACK_TYPE='C0402',
 LOCATION='PC524',
 CDS_LIB='pure_quanta',
 CDS_PART_NAME='Q_CAP_C0402-100NF,50V,10%,X7R,CH4106K1B01',
 VOLTAGE='50V',
 PART_NUMBER='CH4106K1B01',
 VALUE='100NF',
 PRIM_FILE='./archive_libs/logical/q_cap/chips/chips.prt';

PART_NAME
 PC525 'Q_CAPP_SMLF-470UF,2.5V,20%,SPCAP,CH747LM8825':;

SECTION_NUMBER 1
 '@T6G_MB_LIB.T6G(SCH_1):PAGE200_I62@PURE_QUANTA.Q_CAPP(CHIPS)':
 C_PATH='@t6g_mb_lib.t6g(sch_1):page200_i62@pure_quanta.q_capp(chips)',
 P_PATH='@t6g_mb_lib.t6g(sch_1):page225_i62@pure_quanta.q_capp(chips)',
 PATH='I62',
 DRAWING='@T6G_MB_LIB.T6G(SCH_1):PAGE200',
 TOLERANCE='20%',
 MATERIAL='SPCAP',
 PHYS_PAGE='225',
 XY='(-2875,2775)',
 ROT='0',
 VER='1',
 PACK_TYPE='SMLF',
 LOCATION='PC525',
 CDS_LIB='pure_quanta',
 CDS_PART_NAME='Q_CAPP_SMLF-470UF,2.5V,20%,SPCAP,CH747LM8825',
 VOLTAGE='2.5V',
 PART_NUMBER='CH747LM8825',
 VALUE='470UF',
 PRIM_FILE='./archive_libs/logical/q_capp/chips/chips.prt';

PART_NAME
 PC526_1 'Q_CAP_C0805-22UF,4V,20%,X6S,CH622KMEA03':;

SECTION_NUMBER 1
 '@T6G_MB_LIB.T6G(SCH_1):PAGE200_I87@PURE_QUANTA.Q_CAP(CHIPS)':
 C_PATH='@t6g_mb_lib.t6g(sch_1):page200_i87@pure_quanta.q_cap(chips)',
 P_PATH='@t6g_mb_lib.t6g(sch_1):page225_i87@pure_quanta.q_cap(chips)',
 PATH='I87',
 DRAWING='@T6G_MB_LIB.T6G(SCH_1):PAGE200',
 TOLERANCE='20%',
 MATERIAL='X6S',
 PHYS_PAGE='225',
 XY='(-1975,4450)',
 ROT='0',
 VER='1',
 PACK_TYPE='C0805',
 LOCATION='PC526_1',
 CDS_LIB='pure_quanta',
 CDS_PART_NAME='Q_CAP_C0805-22UF,4V,20%,X6S,CH622KMEA03',
 VOLTAGE='4V',
 PART_NUMBER='CH622KMEA03',
 VALUE='22UF',
 PRIM_FILE='./archive_libs/logical/q_cap/chips/chips.prt';

PART_NAME
 PC527_2 'Q_CAP_C0805-22UF,4V,20%,X6S,CH622KMEA03':;

SECTION_NUMBER 1
 '@T6G_MB_LIB.T6G(SCH_1):PAGE200_I67@PURE_QUANTA.Q_CAP(CHIPS)':
 C_PATH='@t6g_mb_lib.t6g(sch_1):page200_i67@pure_quanta.q_cap(chips)',
 P_PATH='@t6g_mb_lib.t6g(sch_1):page225_i67@pure_quanta.q_cap(chips)',
 PATH='I67',
 DRAWING='@T6G_MB_LIB.T6G(SCH_1):PAGE200',
 TOLERANCE='20%',
 MATERIAL='X6S',
 PHYS_PAGE='225',
 XY='(-1950,1525)',
 ROT='0',
 VER='1',
 PACK_TYPE='C0805',
 LOCATION='PC527_2',
 CDS_LIB='pure_quanta',
 CDS_PART_NAME='Q_CAP_C0805-22UF,4V,20%,X6S,CH622KMEA03',
 VOLTAGE='4V',
 PART_NUMBER='CH622KMEA03',
 VALUE='22UF',
 PRIM_FILE='./archive_libs/logical/q_cap/chips/chips.prt';

PART_NAME
 PC528 'Q_CAPP_SMLF-470UF,2.5V,20%,SPCAP,CH747LM8825':;

SECTION_NUMBER 1
 '@T6G_MB_LIB.T6G(SCH_1):PAGE200_I63@PURE_QUANTA.Q_CAPP(CHIPS)':
 C_PATH='@t6g_mb_lib.t6g(sch_1):page200_i63@pure_quanta.q_capp(chips)',
 P_PATH='@t6g_mb_lib.t6g(sch_1):page225_i63@pure_quanta.q_capp(chips)',
 PATH='I63',
 DRAWING='@T6G_MB_LIB.T6G(SCH_1):PAGE200',
 TOLERANCE='20%',
 MATERIAL='SPCAP',
 PHYS_PAGE='225',
 XY='(-2550,2775)',
 ROT='0',
 VER='1',
 PACK_TYPE='SMLF',
 LOCATION='PC528',
 CDS_LIB='pure_quanta',
 CDS_PART_NAME='Q_CAPP_SMLF-470UF,2.5V,20%,SPCAP,CH747LM8825',
 VOLTAGE='2.5V',
 PART_NUMBER='CH747LM8825',
 VALUE='470UF',
 PRIM_FILE='./archive_libs/logical/q_capp/chips/chips.prt';

PART_NAME
 PC529_1 'Q_CAP_C0805-22UF,4V,20%,X6S,CH622KMEA03':;

SECTION_NUMBER 1
 '@T6G_MB_LIB.T6G(SCH_1):PAGE200_I88@PURE_QUANTA.Q_CAP(CHIPS)':
 C_PATH='@t6g_mb_lib.t6g(sch_1):page200_i88@pure_quanta.q_cap(chips)',
 P_PATH='@t6g_mb_lib.t6g(sch_1):page225_i88@pure_quanta.q_cap(chips)',
 PATH='I88',
 DRAWING='@T6G_MB_LIB.T6G(SCH_1):PAGE200',
 TOLERANCE='20%',
 MATERIAL='X6S',
 PHYS_PAGE='225',
 XY='(-1550,4450)',
 ROT='0',
 VER='1',
 PACK_TYPE='C0805',
 LOCATION='PC529_1',
 CDS_LIB='pure_quanta',
 CDS_PART_NAME='Q_CAP_C0805-22UF,4V,20%,X6S,CH622KMEA03',
 VOLTAGE='4V',
 PART_NUMBER='CH622KMEA03',
 VALUE='22UF',
 PRIM_FILE='./archive_libs/logical/q_cap/chips/chips.prt';

PART_NAME
 PC530 'Q_CAPP_SMLF-390UF,2.5V,20%,ALUM,CC7390JMZ13':;

SECTION_NUMBER 1
 '@T6G_MB_LIB.T6G(SCH_1):PAGE200_I69@PURE_QUANTA.Q_CAPP(CHIPS)':
 C_PATH='@t6g_mb_lib.t6g(sch_1):page200_i69@pure_quanta.q_capp(chips)',
 P_PATH='@t6g_mb_lib.t6g(sch_1):page225_i69@pure_quanta.q_capp(chips)',
 PATH='I69',
 DRAWING='@T6G_MB_LIB.T6G(SCH_1):PAGE200',
 TOLERANCE='20%',
 MATERIAL='ALUM',
 PHYS_PAGE='225',
 XY='(-1775,2800)',
 ROT='0',
 VER='1',
 PACK_TYPE='SMLF',
 LOCATION='PC530',
 CDS_LIB='pure_quanta',
 CDS_PART_NAME='Q_CAPP_SMLF-390UF,2.5V,20%,ALUM,CC7390JMZ13',
 VOLTAGE='2.5V',
 PART_NUMBER='CC7390JMZ13',
 VALUE='390UF',
 PRIM_FILE='./archive_libs/logical/q_capp/chips/chips.prt';

PART_NAME
 PC531 'Q_CAPP_SMLF-390UF,2.5V,20%,ALUM,CC7390JMZ13':;

SECTION_NUMBER 1
 '@T6G_MB_LIB.T6G(SCH_1):PAGE200_I72@PURE_QUANTA.Q_CAPP(CHIPS)':
 C_PATH='@t6g_mb_lib.t6g(sch_1):page200_i72@pure_quanta.q_capp(chips)',
 P_PATH='@t6g_mb_lib.t6g(sch_1):page225_i72@pure_quanta.q_capp(chips)',
 PATH='I72',
 DRAWING='@T6G_MB_LIB.T6G(SCH_1):PAGE200',
 TOLERANCE='20%',
 MATERIAL='ALUM',
 PHYS_PAGE='225',
 XY='(-1450,2800)',
 ROT='0',
 VER='1',
 PACK_TYPE='SMLF',
 LOCATION='PC531',
 CDS_LIB='pure_quanta',
 CDS_PART_NAME='Q_CAPP_SMLF-390UF,2.5V,20%,ALUM,CC7390JMZ13',
 VOLTAGE='2.5V',
 PART_NUMBER='CC7390JMZ13',
 VALUE='390UF',
 PRIM_FILE='./archive_libs/logical/q_capp/chips/chips.prt';

PART_NAME
 PC532 'Q_CAPP_SMLF-390UF,2.5V,20%,ALUM,CC7390JMZ13':;

SECTION_NUMBER 1
 '@T6G_MB_LIB.T6G(SCH_1):PAGE200_I73@PURE_QUANTA.Q_CAPP(CHIPS)':
 C_PATH='@t6g_mb_lib.t6g(sch_1):page200_i73@pure_quanta.q_capp(chips)',
 P_PATH='@t6g_mb_lib.t6g(sch_1):page225_i73@pure_quanta.q_capp(chips)',
 PATH='I73',
 DRAWING='@T6G_MB_LIB.T6G(SCH_1):PAGE200',
 TOLERANCE='20%',
 MATERIAL='ALUM',
 PHYS_PAGE='225',
 XY='(-1125,2800)',
 ROT='0',
 VER='1',
 PACK_TYPE='SMLF',
 LOCATION='PC532',
 CDS_LIB='pure_quanta',
 CDS_PART_NAME='Q_CAPP_SMLF-390UF,2.5V,20%,ALUM,CC7390JMZ13',
 VOLTAGE='2.5V',
 PART_NUMBER='CC7390JMZ13',
 VALUE='390UF',
 PRIM_FILE='./archive_libs/logical/q_capp/chips/chips.prt';

PART_NAME
 PC534 'Q_CAPP_SMLF-470UF,2.5V,20%,SPCAP,CH747LM8818':;

SECTION_NUMBER 1
 '@T6G_MB_LIB.T6G(SCH_1):PAGE476_I239@PURE_QUANTA.Q_CAPP(CHIPS)':
 C_PATH='@t6g_mb_lib.t6g(sch_1):page476_i239@pure_quanta.q_capp(chips)',
 P_PATH='@t6g_mb_lib.t6g(sch_1):page363_i239@pure_quanta.q_capp(chips)',
 PATH='I239',
 DRAWING='@T6G_MB_LIB.T6G(SCH_1):PAGE476',
 TOLERANCE='20%',
 MATERIAL='SPCAP',
 PHYS_PAGE='363',
 XY='(175,-9500)',
 ROT='0',
 VER='1',
 PACK_TYPE='SMLF',
 LOCATION='PC534',
 CDS_LIB='pure_quanta',
 CDS_PART_NAME='Q_CAPP_SMLF-470UF,2.5V,20%,SPCAP,CH747LM8818',
 VOLTAGE='2.5V',
 PART_NUMBER='CH747LM8818',
 VALUE='470UF',
 PRIM_FILE='./archive_libs/logical/q_capp/chips/chips.prt';

PART_NAME
 PC544_3 'Q_CAP_0402-0.1UF,25V,10%,X7R,CH4104K1B00':;

SECTION_NUMBER 1
 '@T6G_MB_LIB.T6G(SCH_1):PAGE170_I27@PURE_QUANTA.Q_CAP(CHIPS)':
 C_PATH='@t6g_mb_lib.t6g(sch_1):page170_i27@pure_quanta.q_cap(chips)',
 P_PATH='@t6g_mb_lib.t6g(sch_1):page195_i27@pure_quanta.q_cap(chips)',
 PATH='I27',
 DRAWING='@T6G_MB_LIB.T6G(SCH_1):PAGE170',
 TOLERANCE='10%',
 MATERIAL='X7R',
 PHYS_PAGE='195',
 XY='(-7675,4525)',
 ROT='0',
 VER='1',
 PACK_TYPE='0402',
 LOCATION='PC544_3',
 CDS_LIB='pure_quanta',
 CDS_PART_NAME='Q_CAP_0402-0.1UF,25V,10%,X7R,CH4104K1B00',
 VOLTAGE='25V',
 PART_NUMBER='CH4104K1B00',
 VALUE='0.1UF',
 PRIM_FILE='./archive_libs/logical/q_cap/chips/chips.prt';

PART_NAME
 PC545_4 'Q_CAP_0402-0.1UF,25V,10%,X7R,CH4104K1B00':;

SECTION_NUMBER 1
 '@T6G_MB_LIB.T6G(SCH_1):PAGE170_I2@PURE_QUANTA.Q_CAP(CHIPS)':
 C_PATH='@t6g_mb_lib.t6g(sch_1):page170_i2@pure_quanta.q_cap(chips)',
 P_PATH='@t6g_mb_lib.t6g(sch_1):page195_i2@pure_quanta.q_cap(chips)',
 PATH='I2',
 DRAWING='@T6G_MB_LIB.T6G(SCH_1):PAGE170',
 TOLERANCE='10%',
 MATERIAL='X7R',
 PHYS_PAGE='195',
 XY='(-7600,1225)',
 ROT='0',
 VER='1',
 PACK_TYPE='0402',
 LOCATION='PC545_4',
 CDS_LIB='pure_quanta',
 CDS_PART_NAME='Q_CAP_0402-0.1UF,25V,10%,X7R,CH4104K1B00',
 VOLTAGE='25V',
 PART_NUMBER='CH4104K1B00',
 VALUE='0.1UF',
 PRIM_FILE='./archive_libs/logical/q_cap/chips/chips.prt';

PART_NAME
 PC546 'Q_CAP_C0402-2.2UF,10V,10%,X6S,CH5222KEB01':;

SECTION_NUMBER 1
 '@T6G_MB_LIB.T6G(SCH_1):PAGE170_I36@PURE_QUANTA.Q_CAP(CHIPS)':
 C_PATH='@t6g_mb_lib.t6g(sch_1):page170_i36@pure_quanta.q_cap(chips)',
 P_PATH='@t6g_mb_lib.t6g(sch_1):page195_i36@pure_quanta.q_cap(chips)',
 PATH='I36',
 DRAWING='@T6G_MB_LIB.T6G(SCH_1):PAGE170',
 TOLERANCE='10%',
 MATERIAL='X6S',
 PHYS_PAGE='195',
 XY='(-7350,5150)',
 ROT='0',
 VER='1',
 PACK_TYPE='C0402',
 LOCATION='PC546',
 CDS_LIB='pure_quanta',
 CDS_PART_NAME='Q_CAP_C0402-2.2UF,10V,10%,X6S,CH5222KEB01',
 VOLTAGE='10V',
 PART_NUMBER='CH5222KEB01',
 VALUE='2.2UF',
 PRIM_FILE='./archive_libs/logical/q_cap/chips/chips.prt';

PART_NAME
 PC547 'Q_CAP_C0402-2.2UF,10V,10%,X6S,CH5222KEB01':;

SECTION_NUMBER 1
 '@T6G_MB_LIB.T6G(SCH_1):PAGE170_I6@PURE_QUANTA.Q_CAP(CHIPS)':
 C_PATH='@t6g_mb_lib.t6g(sch_1):page170_i6@pure_quanta.q_cap(chips)',
 P_PATH='@t6g_mb_lib.t6g(sch_1):page195_i6@pure_quanta.q_cap(chips)',
 PATH='I6',
 DRAWING='@T6G_MB_LIB.T6G(SCH_1):PAGE170',
 TOLERANCE='10%',
 MATERIAL='X6S',
 PHYS_PAGE='195',
 XY='(-7250,1850)',
 ROT='0',
 VER='1',
 PACK_TYPE='C0402',
 LOCATION='PC547',
 CDS_LIB='pure_quanta',
 CDS_PART_NAME='Q_CAP_C0402-2.2UF,10V,10%,X6S,CH5222KEB01',
 VOLTAGE='10V',
 PART_NUMBER='CH5222KEB01',
 VALUE='2.2UF',
 PRIM_FILE='./archive_libs/logical/q_cap/chips/chips.prt';

PART_NAME
 PC548_C0P0_3 'Q_CAP_C0402-2.2UF,10V,10%,X6S,CH5222KEB01':;

SECTION_NUMBER 1
 '@T6G_MB_LIB.T6G(SCH_1):PAGE170_I40@PURE_QUANTA.Q_CAP(CHIPS)':
 C_PATH='@t6g_mb_lib.t6g(sch_1):page170_i40@pure_quanta.q_cap(chips)',
 P_PATH='@t6g_mb_lib.t6g(sch_1):page195_i40@pure_quanta.q_cap(chips)',
 PATH='I40',
 DRAWING='@T6G_MB_LIB.T6G(SCH_1):PAGE170',
 TOLERANCE='10%',
 MATERIAL='X6S',
 PHYS_PAGE='195',
 XY='(-7000,5650)',
 ROT='0',
 VER='1',
 PACK_TYPE='C0402',
 LOCATION='PC548_C0P0_3',
 CDS_LIB='pure_quanta',
 CDS_PART_NAME='Q_CAP_C0402-2.2UF,10V,10%,X6S,CH5222KEB01',
 VOLTAGE='10V',
 PART_NUMBER='CH5222KEB01',
 VALUE='2.2UF',
 PRIM_FILE='./archive_libs/logical/q_cap/chips/chips.prt';

PART_NAME
 PC549_C0P0_4 'Q_CAP_C0402-2.2UF,10V,10%,X6S,CH5222KEB01':;

SECTION_NUMBER 1
 '@T6G_MB_LIB.T6G(SCH_1):PAGE170_I15@PURE_QUANTA.Q_CAP(CHIPS)':
 C_PATH='@t6g_mb_lib.t6g(sch_1):page170_i15@pure_quanta.q_cap(chips)',
 P_PATH='@t6g_mb_lib.t6g(sch_1):page195_i15@pure_quanta.q_cap(chips)',
 PATH='I15',
 DRAWING='@T6G_MB_LIB.T6G(SCH_1):PAGE170',
 TOLERANCE='10%',
 MATERIAL='X6S',
 PHYS_PAGE='195',
 XY='(-6900,2425)',
 ROT='0',
 VER='1',
 PACK_TYPE='C0402',
 LOCATION='PC549_C0P0_4',
 CDS_LIB='pure_quanta',
 CDS_PART_NAME='Q_CAP_C0402-2.2UF,10V,10%,X6S,CH5222KEB01',
 VOLTAGE='10V',
 PART_NUMBER='CH5222KEB01',
 VALUE='2.2UF',
 PRIM_FILE='./archive_libs/logical/q_cap/chips/chips.prt';

PART_NAME
 PC550_3 'Q_CAP_C0402-1UF,25V,10%,X6S,CH5104KEB02':;

SECTION_NUMBER 1
 '@T6G_MB_LIB.T6G(SCH_1):PAGE170_I47@PURE_QUANTA.Q_CAP(CHIPS)':
 C_PATH='@t6g_mb_lib.t6g(sch_1):page170_i47@pure_quanta.q_cap(chips)',
 P_PATH='@t6g_mb_lib.t6g(sch_1):page195_i47@pure_quanta.q_cap(chips)',
 PATH='I47',
 DRAWING='@T6G_MB_LIB.T6G(SCH_1):PAGE170',
 TOLERANCE='10%',
 MATERIAL='X6S',
 PHYS_PAGE='195',
 XY='(-4875,5700)',
 ROT='0',
 VER='1',
 PACK_TYPE='C0402',
 LOCATION='PC550_3',
 CDS_LIB='pure_quanta',
 CDS_PART_NAME='Q_CAP_C0402-1UF,25V,10%,X6S,CH5104KEB02',
 VOLTAGE='25V',
 PART_NUMBER='CH5104KEB02',
 VALUE='1UF',
 PRIM_FILE='./archive_libs/logical/q_cap/chips/chips.prt';

PART_NAME
 PC551_4 'Q_CAP_0402-0.1UF,25V,10%,X7R,CH4104K1B00':;

SECTION_NUMBER 1
 '@T6G_MB_LIB.T6G(SCH_1):PAGE170_I21@PURE_QUANTA.Q_CAP(CHIPS)':
 C_PATH='@t6g_mb_lib.t6g(sch_1):page170_i21@pure_quanta.q_cap(chips)',
 P_PATH='@t6g_mb_lib.t6g(sch_1):page195_i21@pure_quanta.q_cap(chips)',
 PATH='I21',
 DRAWING='@T6G_MB_LIB.T6G(SCH_1):PAGE170',
 TOLERANCE='10%',
 MATERIAL='X7R',
 PHYS_PAGE='195',
 XY='(-5100,2400)',
 ROT='0',
 VER='1',
 PACK_TYPE='0402',
 LOCATION='PC551_4',
 CDS_LIB='pure_quanta',
 CDS_PART_NAME='Q_CAP_0402-0.1UF,25V,10%,X7R,CH4104K1B00',
 VOLTAGE='25V',
 PART_NUMBER='CH4104K1B00',
 VALUE='0.1UF',
 PRIM_FILE='./archive_libs/logical/q_cap/chips/chips.prt';

PART_NAME
 PC552_3 'Q_CAP_0402-0.1UF,25V,10%,X7R,CH4104K1B00':;

SECTION_NUMBER 1
 '@T6G_MB_LIB.T6G(SCH_1):PAGE170_I43@PURE_QUANTA.Q_CAP(CHIPS)':
 C_PATH='@t6g_mb_lib.t6g(sch_1):page170_i43@pure_quanta.q_cap(chips)',
 P_PATH='@t6g_mb_lib.t6g(sch_1):page195_i43@pure_quanta.q_cap(chips)',
 PATH='I43',
 DRAWING='@T6G_MB_LIB.T6G(SCH_1):PAGE170',
 TOLERANCE='10%',
 MATERIAL='X7R',
 PHYS_PAGE='195',
 XY='(-5225,5700)',
 ROT='0',
 VER='1',
 PACK_TYPE='0402',
 LOCATION='PC552_3',
 CDS_LIB='pure_quanta',
 CDS_PART_NAME='Q_CAP_0402-0.1UF,25V,10%,X7R,CH4104K1B00',
 VOLTAGE='25V',
 PART_NUMBER='CH4104K1B00',
 VALUE='0.1UF',
 PRIM_FILE='./archive_libs/logical/q_cap/chips/chips.prt';

PART_NAME
 PC553_4 'Q_CAP_C0402-1UF,25V,10%,X6S,CH5104KEB02':;

SECTION_NUMBER 1
 '@T6G_MB_LIB.T6G(SCH_1):PAGE170_I22@PURE_QUANTA.Q_CAP(CHIPS)':
 C_PATH='@t6g_mb_lib.t6g(sch_1):page170_i22@pure_quanta.q_cap(chips)',
 P_PATH='@t6g_mb_lib.t6g(sch_1):page195_i22@pure_quanta.q_cap(chips)',
 PATH='I22',
 DRAWING='@T6G_MB_LIB.T6G(SCH_1):PAGE170',
 TOLERANCE='10%',
 MATERIAL='X6S',
 PHYS_PAGE='195',
 XY='(-4725,2400)',
 ROT='0',
 VER='1',
 PACK_TYPE='C0402',
 LOCATION='PC553_4',
 CDS_LIB='pure_quanta',
 CDS_PART_NAME='Q_CAP_C0402-1UF,25V,10%,X6S,CH5104KEB02',
 VOLTAGE='25V',
 PART_NUMBER='CH5104KEB02',
 VALUE='1UF',
 PRIM_FILE='./archive_libs/logical/q_cap/chips/chips.prt';

PART_NAME
 PC554_3 'Q_CAP_C0805-22UF,16V,20%,X6S,CH6223MEA01':;

SECTION_NUMBER 1
 '@T6G_MB_LIB.T6G(SCH_1):PAGE170_I48@PURE_QUANTA.Q_CAP(CHIPS)':
 C_PATH='@t6g_mb_lib.t6g(sch_1):page170_i48@pure_quanta.q_cap(chips)',
 P_PATH='@t6g_mb_lib.t6g(sch_1):page195_i48@pure_quanta.q_cap(chips)',
 PATH='I48',
 DRAWING='@T6G_MB_LIB.T6G(SCH_1):PAGE170',
 TOLERANCE='20%',
 MATERIAL='X6S',
 PHYS_PAGE='195',
 XY='(-4550,5700)',
 ROT='0',
 VER='1',
 PACK_TYPE='C0805',
 LOCATION='PC554_3',
 CDS_LIB='pure_quanta',
 CDS_PART_NAME='Q_CAP_C0805-22UF,16V,20%,X6S,CH6223MEA01',
 VOLTAGE='16V',
 PART_NUMBER='CH6223MEA01',
 VALUE='22UF',
 PRIM_FILE='./archive_libs/logical/q_cap/chips/chips.prt';

PART_NAME
 PC555_4 'Q_CAP_C0805-22UF,16V,20%,X6S,CH6223MEA01':;

SECTION_NUMBER 1
 '@T6G_MB_LIB.T6G(SCH_1):PAGE170_I23@PURE_QUANTA.Q_CAP(CHIPS)':
 C_PATH='@t6g_mb_lib.t6g(sch_1):page170_i23@pure_quanta.q_cap(chips)',
 P_PATH='@t6g_mb_lib.t6g(sch_1):page195_i23@pure_quanta.q_cap(chips)',
 PATH='I23',
 DRAWING='@T6G_MB_LIB.T6G(SCH_1):PAGE170',
 TOLERANCE='20%',
 MATERIAL='X6S',
 PHYS_PAGE='195',
 XY='(-4400,2400)',
 ROT='0',
 VER='1',
 PACK_TYPE='C0805',
 LOCATION='PC555_4',
 CDS_LIB='pure_quanta',
 CDS_PART_NAME='Q_CAP_C0805-22UF,16V,20%,X6S,CH6223MEA01',
 VOLTAGE='16V',
 PART_NUMBER='CH6223MEA01',
 VALUE='22UF',
 PRIM_FILE='./archive_libs/logical/q_cap/chips/chips.prt';

PART_NAME
 PC556_3 'Q_CAP_C0805-22UF,16V,20%,X6S,CH6223MEA01':;

SECTION_NUMBER 1
 '@T6G_MB_LIB.T6G(SCH_1):PAGE170_I49@PURE_QUANTA.Q_CAP(CHIPS)':
 C_PATH='@t6g_mb_lib.t6g(sch_1):page170_i49@pure_quanta.q_cap(chips)',
 P_PATH='@t6g_mb_lib.t6g(sch_1):page195_i49@pure_quanta.q_cap(chips)',
 PATH='I49',
 DRAWING='@T6G_MB_LIB.T6G(SCH_1):PAGE170',
 TOLERANCE='20%',
 MATERIAL='X6S',
 PHYS_PAGE='195',
 XY='(-4225,5700)',
 ROT='0',
 VER='1',
 PACK_TYPE='C0805',
 LOCATION='PC556_3',
 CDS_LIB='pure_quanta',
 CDS_PART_NAME='Q_CAP_C0805-22UF,16V,20%,X6S,CH6223MEA01',
 VOLTAGE='16V',
 PART_NUMBER='CH6223MEA01',
 VALUE='22UF',
 PRIM_FILE='./archive_libs/logical/q_cap/chips/chips.prt';

PART_NAME
 PC557_4 'Q_CAP_C0805-22UF,16V,20%,X6S,CH6223MEA01':;

SECTION_NUMBER 1
 '@T6G_MB_LIB.T6G(SCH_1):PAGE170_I24@PURE_QUANTA.Q_CAP(CHIPS)':
 C_PATH='@t6g_mb_lib.t6g(sch_1):page170_i24@pure_quanta.q_cap(chips)',
 P_PATH='@t6g_mb_lib.t6g(sch_1):page195_i24@pure_quanta.q_cap(chips)',
 PATH='I24',
 DRAWING='@T6G_MB_LIB.T6G(SCH_1):PAGE170',
 TOLERANCE='20%',
 MATERIAL='X6S',
 PHYS_PAGE='195',
 XY='(-4075,2400)',
 ROT='0',
 VER='1',
 PACK_TYPE='C0805',
 LOCATION='PC557_4',
 CDS_LIB='pure_quanta',
 CDS_PART_NAME='Q_CAP_C0805-22UF,16V,20%,X6S,CH6223MEA01',
 VOLTAGE='16V',
 PART_NUMBER='CH6223MEA01',
 VALUE='22UF',
 PRIM_FILE='./archive_libs/logical/q_cap/chips/chips.prt';

PART_NAME
 PC558_3 'Q_CAP_C0805-22UF,16V,20%,X6S,CH6223MEA01':;

SECTION_NUMBER 1
 '@T6G_MB_LIB.T6G(SCH_1):PAGE170_I66@PURE_QUANTA.Q_CAP(CHIPS)':
 C_PATH='@t6g_mb_lib.t6g(sch_1):page170_i66@pure_quanta.q_cap(chips)',
 P_PATH='@t6g_mb_lib.t6g(sch_1):page195_i66@pure_quanta.q_cap(chips)',
 PATH='I66',
 DRAWING='@T6G_MB_LIB.T6G(SCH_1):PAGE170',
 TOLERANCE='20%',
 MATERIAL='X6S',
 PHYS_PAGE='195',
 XY='(-3925,5700)',
 ROT='0',
 VER='1',
 PACK_TYPE='C0805',
 LOCATION='PC558_3',
 CDS_LIB='pure_quanta',
 CDS_PART_NAME='Q_CAP_C0805-22UF,16V,20%,X6S,CH6223MEA01',
 VOLTAGE='16V',
 PART_NUMBER='CH6223MEA01',
 VALUE='22UF',
 PRIM_FILE='./archive_libs/logical/q_cap/chips/chips.prt';

PART_NAME
 PC559_4 'Q_CAP_C0805-22UF,16V,20%,X6S,CH6223MEA01':;

SECTION_NUMBER 1
 '@T6G_MB_LIB.T6G(SCH_1):PAGE170_I55@PURE_QUANTA.Q_CAP(CHIPS)':
 C_PATH='@t6g_mb_lib.t6g(sch_1):page170_i55@pure_quanta.q_cap(chips)',
 P_PATH='@t6g_mb_lib.t6g(sch_1):page195_i55@pure_quanta.q_cap(chips)',
 PATH='I55',
 DRAWING='@T6G_MB_LIB.T6G(SCH_1):PAGE170',
 TOLERANCE='20%',
 MATERIAL='X6S',
 PHYS_PAGE='195',
 XY='(-3700,2400)',
 ROT='0',
 VER='1',
 PACK_TYPE='C0805',
 LOCATION='PC559_4',
 CDS_LIB='pure_quanta',
 CDS_PART_NAME='Q_CAP_C0805-22UF,16V,20%,X6S,CH6223MEA01',
 VOLTAGE='16V',
 PART_NUMBER='CH6223MEA01',
 VALUE='22UF',
 PRIM_FILE='./archive_libs/logical/q_cap/chips/chips.prt';

PART_NAME
 PC560 'Q_CAP_0402-0.22UF,16V,10%,X7R,CH4223K1B00':;

SECTION_NUMBER 1
 '@T6G_MB_LIB.T6G(SCH_1):PAGE170_I63@PURE_QUANTA.Q_CAP(CHIPS)':
 C_PATH='@t6g_mb_lib.t6g(sch_1):page170_i63@pure_quanta.q_cap(chips)',
 P_PATH='@t6g_mb_lib.t6g(sch_1):page195_i63@pure_quanta.q_cap(chips)',
 PATH='I63',
 DRAWING='@T6G_MB_LIB.T6G(SCH_1):PAGE170',
 TOLERANCE='10%',
 MATERIAL='X7R',
 PHYS_PAGE='195',
 XY='(-3450,5025)',
 ROT='0',
 VER='1',
 PACK_TYPE='0402',
 LOCATION='PC560',
 CDS_LIB='pure_quanta',
 CDS_PART_NAME='Q_CAP_0402-0.22UF,16V,10%,X7R,CH4223K1B00',
 VOLTAGE='16V',
 PART_NUMBER='CH4223K1B00',
 VALUE='0.22UF',
 PRIM_FILE='./archive_libs/logical/q_cap/chips/chips.prt';

PART_NAME
 PC561 'Q_CAP_0402-0.22UF,16V,10%,X7R,CH4223K1B00':;

SECTION_NUMBER 1
 '@T6G_MB_LIB.T6G(SCH_1):PAGE170_I53@PURE_QUANTA.Q_CAP(CHIPS)':
 C_PATH='@t6g_mb_lib.t6g(sch_1):page170_i53@pure_quanta.q_cap(chips)',
 P_PATH='@t6g_mb_lib.t6g(sch_1):page195_i53@pure_quanta.q_cap(chips)',
 PATH='I53',
 DRAWING='@T6G_MB_LIB.T6G(SCH_1):PAGE170',
 TOLERANCE='10%',
 MATERIAL='X7R',
 PHYS_PAGE='195',
 XY='(-3400,1725)',
 ROT='0',
 VER='1',
 PACK_TYPE='0402',
 LOCATION='PC561',
 CDS_LIB='pure_quanta',
 CDS_PART_NAME='Q_CAP_0402-0.22UF,16V,10%,X7R,CH4223K1B00',
 VOLTAGE='16V',
 PART_NUMBER='CH4223K1B00',
 VALUE='0.22UF',
 PRIM_FILE='./archive_libs/logical/q_cap/chips/chips.prt';

PART_NAME
 PC562_3 'Q_CAP_C0805-22UF,4V,20%,X6S,CH622KMEA03':;

SECTION_NUMBER 1
 '@T6G_MB_LIB.T6G(SCH_1):PAGE170_I70@PURE_QUANTA.Q_CAP(CHIPS)':
 C_PATH='@t6g_mb_lib.t6g(sch_1):page170_i70@pure_quanta.q_cap(chips)',
 P_PATH='@t6g_mb_lib.t6g(sch_1):page195_i70@pure_quanta.q_cap(chips)',
 PATH='I70',
 DRAWING='@T6G_MB_LIB.T6G(SCH_1):PAGE170',
 TOLERANCE='20%',
 MATERIAL='X6S',
 PHYS_PAGE='195',
 XY='(-1400,4625)',
 ROT='0',
 VER='1',
 PACK_TYPE='C0805',
 LOCATION='PC562_3',
 CDS_LIB='pure_quanta',
 CDS_PART_NAME='Q_CAP_C0805-22UF,4V,20%,X6S,CH622KMEA03',
 VOLTAGE='4V',
 PART_NUMBER='CH622KMEA03',
 VALUE='22UF',
 PRIM_FILE='./archive_libs/logical/q_cap/chips/chips.prt';

PART_NAME
 PC563_4 'Q_CAP_C0805-22UF,4V,20%,X6S,CH622KMEA03':;

SECTION_NUMBER 1
 '@T6G_MB_LIB.T6G(SCH_1):PAGE170_I58@PURE_QUANTA.Q_CAP(CHIPS)':
 C_PATH='@t6g_mb_lib.t6g(sch_1):page170_i58@pure_quanta.q_cap(chips)',
 P_PATH='@t6g_mb_lib.t6g(sch_1):page195_i58@pure_quanta.q_cap(chips)',
 PATH='I58',
 DRAWING='@T6G_MB_LIB.T6G(SCH_1):PAGE170',
 TOLERANCE='20%',
 MATERIAL='X6S',
 PHYS_PAGE='195',
 XY='(-1300,1325)',
 ROT='0',
 VER='1',
 PACK_TYPE='C0805',
 LOCATION='PC563_4',
 CDS_LIB='pure_quanta',
 CDS_PART_NAME='Q_CAP_C0805-22UF,4V,20%,X6S,CH622KMEA03',
 VOLTAGE='4V',
 PART_NUMBER='CH622KMEA03',
 VALUE='22UF',
 PRIM_FILE='./archive_libs/logical/q_cap/chips/chips.prt';

PART_NAME
 PC564_3 'Q_CAP_C0805-22UF,4V,20%,X6S,CH622KMEA03':;

SECTION_NUMBER 1
 '@T6G_MB_LIB.T6G(SCH_1):PAGE170_I71@PURE_QUANTA.Q_CAP(CHIPS)':
 C_PATH='@t6g_mb_lib.t6g(sch_1):page170_i71@pure_quanta.q_cap(chips)',
 P_PATH='@t6g_mb_lib.t6g(sch_1):page195_i71@pure_quanta.q_cap(chips)',
 PATH='I71',
 DRAWING='@T6G_MB_LIB.T6G(SCH_1):PAGE170',
 TOLERANCE='20%',
 MATERIAL='X6S',
 PHYS_PAGE='195',
 XY='(-975,4625)',
 ROT='0',
 VER='1',
 PACK_TYPE='C0805',
 LOCATION='PC564_3',
 CDS_LIB='pure_quanta',
 CDS_PART_NAME='Q_CAP_C0805-22UF,4V,20%,X6S,CH622KMEA03',
 VOLTAGE='4V',
 PART_NUMBER='CH622KMEA03',
 VALUE='22UF',
 PRIM_FILE='./archive_libs/logical/q_cap/chips/chips.prt';

PART_NAME
 PC565_4 'Q_CAP_C0805-22UF,4V,20%,X6S,CH622KMEA03':;

SECTION_NUMBER 1
 '@T6G_MB_LIB.T6G(SCH_1):PAGE170_I60@PURE_QUANTA.Q_CAP(CHIPS)':
 C_PATH='@t6g_mb_lib.t6g(sch_1):page170_i60@pure_quanta.q_cap(chips)',
 P_PATH='@t6g_mb_lib.t6g(sch_1):page195_i60@pure_quanta.q_cap(chips)',
 PATH='I60',
 DRAWING='@T6G_MB_LIB.T6G(SCH_1):PAGE170',
 TOLERANCE='20%',
 MATERIAL='X6S',
 PHYS_PAGE='195',
 XY='(-800,1325)',
 ROT='0',
 VER='1',
 PACK_TYPE='C0805',
 LOCATION='PC565_4',
 CDS_LIB='pure_quanta',
 CDS_PART_NAME='Q_CAP_C0805-22UF,4V,20%,X6S,CH622KMEA03',
 VOLTAGE='4V',
 PART_NUMBER='CH622KMEA03',
 VALUE='22UF',
 PRIM_FILE='./archive_libs/logical/q_cap/chips/chips.prt';

PART_NAME
 PC566 'Q_CAPP_THLF-270UF,16V,20%,OSCON,CC72703MD38':;

SECTION_NUMBER 1
 '@T6G_MB_LIB.T6G(SCH_1):PAGE245_I30@PURE_QUANTA.Q_CAPP(CHIPS)':
 C_PATH='@t6g_mb_lib.t6g(sch_1):page245_i30@pure_quanta.q_capp(chips)',
 P_PATH='@t6g_mb_lib.t6g(sch_1):page190_i30@pure_quanta.q_capp(chips)',
 PATH='I30',
 DRAWING='@T6G_MB_LIB.T6G(SCH_1):PAGE245',
 TOLERANCE='20%',
 MATERIAL='OSCON',
 PHYS_PAGE='190',
 XY='(-3675,1100)',
 ROT='0',
 VER='1',
 PACK_TYPE='THLF',
 LOCATION='PC566',
 CDS_LIB='pure_quanta',
 CDS_PART_NAME='Q_CAPP_THLF-270UF,16V,20%,OSCON,CC72703MD38',
 VOLTAGE='16V',
 PART_NUMBER='CC72703MD38',
 VALUE='270UF',
 PRIM_FILE='./archive_libs/logical/q_capp/chips/chips.prt';

PART_NAME
 PC566_5 'Q_CAP_0402-0.1UF,25V,10%,X7R,CH4104K1B00':;

SECTION_NUMBER 1
 '@T6G_MB_LIB.T6G(SCH_1):PAGE171_I33@PURE_QUANTA.Q_CAP(CHIPS)':
 C_PATH='@t6g_mb_lib.t6g(sch_1):page171_i33@pure_quanta.q_cap(chips)',
 P_PATH='@t6g_mb_lib.t6g(sch_1):page196_i33@pure_quanta.q_cap(chips)',
 PATH='I33',
 DRAWING='@T6G_MB_LIB.T6G(SCH_1):PAGE171',
 TOLERANCE='10%',
 MATERIAL='X7R',
 PHYS_PAGE='196',
 XY='(-7525,4300)',
 ROT='0',
 VER='1',
 PACK_TYPE='0402',
 LOCATION='PC566_5',
 CDS_LIB='pure_quanta',
 CDS_PART_NAME='Q_CAP_0402-0.1UF,25V,10%,X7R,CH4104K1B00',
 VOLTAGE='25V',
 PART_NUMBER='CH4104K1B00',
 VALUE='0.1UF',
 PRIM_FILE='./archive_libs/logical/q_cap/chips/chips.prt';

PART_NAME
 PC567 'Q_CAP_C0402-2.2UF,10V,10%,X6S,CH5222KEB01':;

SECTION_NUMBER 1
 '@T6G_MB_LIB.T6G(SCH_1):PAGE171_I38@PURE_QUANTA.Q_CAP(CHIPS)':
 C_PATH='@t6g_mb_lib.t6g(sch_1):page171_i38@pure_quanta.q_cap(chips)',
 P_PATH='@t6g_mb_lib.t6g(sch_1):page196_i38@pure_quanta.q_cap(chips)',
 PATH='I38',
 DRAWING='@T6G_MB_LIB.T6G(SCH_1):PAGE171',
 TOLERANCE='10%',
 MATERIAL='X6S',
 PHYS_PAGE='196',
 XY='(-7200,4925)',
 ROT='0',
 VER='1',
 PACK_TYPE='C0402',
 LOCATION='PC567',
 CDS_LIB='pure_quanta',
 CDS_PART_NAME='Q_CAP_C0402-2.2UF,10V,10%,X6S,CH5222KEB01',
 VOLTAGE='10V',
 PART_NUMBER='CH5222KEB01',
 VALUE='2.2UF',
 PRIM_FILE='./archive_libs/logical/q_cap/chips/chips.prt';

PART_NAME
 PC568 'Q_CAP_C0402-0.22UF,25V,10%,X7R,CH4224K1B01':;

SECTION_NUMBER 1
 '@T6G_MB_LIB.T6G(SCH_1):PAGE245_I48@PURE_QUANTA.Q_CAP(CHIPS)':
 C_PATH='@t6g_mb_lib.t6g(sch_1):page245_i48@pure_quanta.q_cap(chips)',
 P_PATH='@t6g_mb_lib.t6g(sch_1):page190_i48@pure_quanta.q_cap(chips)',
 PATH='I48',
 DRAWING='@T6G_MB_LIB.T6G(SCH_1):PAGE245',
 TOLERANCE='10%',
 MATERIAL='X7R',
 PHYS_PAGE='190',
 XY='(725,-300)',
 ROT='0',
 VER='2',
 PACK_TYPE='C0402',
 LOCATION='PC568',
 CDS_LIB='pure_quanta',
 CDS_PART_NAME='Q_CAP_C0402-0.22UF,25V,10%,X7R,CH4224K1B01',
 VOLTAGE='25V',
 PART_NUMBER='CH4224K1B01',
 VALUE='0.22UF',
 PRIM_FILE='./archive_libs/logical/q_cap/chips/chips.prt';

PART_NAME
 PC568_C0P0_5 'Q_CAP_C0402-2.2UF,10V,10%,X6S,CH5222KEB01':;

SECTION_NUMBER 1
 '@T6G_MB_LIB.T6G(SCH_1):PAGE171_I42@PURE_QUANTA.Q_CAP(CHIPS)':
 C_PATH='@t6g_mb_lib.t6g(sch_1):page171_i42@pure_quanta.q_cap(chips)',
 P_PATH='@t6g_mb_lib.t6g(sch_1):page196_i42@pure_quanta.q_cap(chips)',
 PATH='I42',
 DRAWING='@T6G_MB_LIB.T6G(SCH_1):PAGE171',
 TOLERANCE='10%',
 MATERIAL='X6S',
 PHYS_PAGE='196',
 XY='(-6850,5425)',
 ROT='0',
 VER='1',
 PACK_TYPE='C0402',
 LOCATION='PC568_C0P0_5',
 CDS_LIB='pure_quanta',
 CDS_PART_NAME='Q_CAP_C0402-2.2UF,10V,10%,X6S,CH5222KEB01',
 VOLTAGE='10V',
 PART_NUMBER='CH5222KEB01',
 VALUE='2.2UF',
 PRIM_FILE='./archive_libs/logical/q_cap/chips/chips.prt';

PART_NAME
 PC569 'Q_CAP_0402-10PF,50V,1%,NPO,TMP_QCH0106F0B00':;

SECTION_NUMBER 1
 '@T6G_MB_LIB.T6G(SCH_1):PAGE245_I53@PURE_QUANTA.Q_CAP(CHIPS)':
 C_PATH='@t6g_mb_lib.t6g(sch_1):page245_i53@pure_quanta.q_cap(chips)',
 P_PATH='@t6g_mb_lib.t6g(sch_1):page190_i53@pure_quanta.q_cap(chips)',
 PATH='I53',
 DRAWING='@T6G_MB_LIB.T6G(SCH_1):PAGE245',
 TOLERANCE='1%',
 MATERIAL='NPO',
 PHYS_PAGE='190',
 XY='(2100,-1600)',
 ROT='0',
 VER='2',
 PACK_TYPE='0402',
 LOCATION='PC569',
 CDS_LIB='pure_quanta',
 CDS_PART_NAME='Q_CAP_0402-10PF,50V,1%,NPO,TMP_QCH0106F0B00',
 VOLTAGE='50V',
 PART_NUMBER='TMP_QCH0106F0B00',
 VALUE='10PF',
 PRIM_FILE='./archive_libs/logical/q_cap/chips/chips.prt';

PART_NAME
 PC569_5 'Q_CAP_C0402-1UF,25V,10%,X6S,CH5104KEB02':;

SECTION_NUMBER 1
 '@T6G_MB_LIB.T6G(SCH_1):PAGE171_I47@PURE_QUANTA.Q_CAP(CHIPS)':
 C_PATH='@t6g_mb_lib.t6g(sch_1):page171_i47@pure_quanta.q_cap(chips)',
 P_PATH='@t6g_mb_lib.t6g(sch_1):page196_i47@pure_quanta.q_cap(chips)',
 PATH='I47',
 DRAWING='@T6G_MB_LIB.T6G(SCH_1):PAGE171',
 TOLERANCE='10%',
 MATERIAL='X6S',
 PHYS_PAGE='196',
 XY='(-4575,5450)',
 ROT='0',
 VER='1',
 PACK_TYPE='C0402',
 LOCATION='PC569_5',
 CDS_LIB='pure_quanta',
 CDS_PART_NAME='Q_CAP_C0402-1UF,25V,10%,X6S,CH5104KEB02',
 VOLTAGE='25V',
 PART_NUMBER='CH5104KEB02',
 VALUE='1UF',
 PRIM_FILE='./archive_libs/logical/q_cap/chips/chips.prt';

PART_NAME
 PC570 'Q_CAP_C0805-22UF,16V,20%,X6S,CH6223MEA01':;

SECTION_NUMBER 1
 '@T6G_MB_LIB.T6G(SCH_1):PAGE245_I35@PURE_QUANTA.Q_CAP(CHIPS)':
 C_PATH='@t6g_mb_lib.t6g(sch_1):page245_i35@pure_quanta.q_cap(chips)',
 P_PATH='@t6g_mb_lib.t6g(sch_1):page190_i35@pure_quanta.q_cap(chips)',
 PATH='I35',
 DRAWING='@T6G_MB_LIB.T6G(SCH_1):PAGE245',
 TOLERANCE='20%',
 MATERIAL='X6S',
 PHYS_PAGE='190',
 XY='(-3025,1100)',
 ROT='0',
 VER='1',
 PACK_TYPE='C0805',
 LOCATION='PC570',
 CDS_LIB='pure_quanta',
 CDS_PART_NAME='Q_CAP_C0805-22UF,16V,20%,X6S,CH6223MEA01',
 VOLTAGE='16V',
 PART_NUMBER='CH6223MEA01',
 VALUE='22UF',
 PRIM_FILE='./archive_libs/logical/q_cap/chips/chips.prt';

PART_NAME
 PC570_5 'Q_CAP_0402-0.1UF,25V,10%,X7R,CH4104K1B00':;

SECTION_NUMBER 1
 '@T6G_MB_LIB.T6G(SCH_1):PAGE171_I44@PURE_QUANTA.Q_CAP(CHIPS)':
 C_PATH='@t6g_mb_lib.t6g(sch_1):page171_i44@pure_quanta.q_cap(chips)',
 P_PATH='@t6g_mb_lib.t6g(sch_1):page196_i44@pure_quanta.q_cap(chips)',
 PATH='I44',
 DRAWING='@T6G_MB_LIB.T6G(SCH_1):PAGE171',
 TOLERANCE='10%',
 MATERIAL='X7R',
 PHYS_PAGE='196',
 XY='(-4950,5450)',
 ROT='0',
 VER='1',
 PACK_TYPE='0402',
 LOCATION='PC570_5',
 CDS_LIB='pure_quanta',
 CDS_PART_NAME='Q_CAP_0402-0.1UF,25V,10%,X7R,CH4104K1B00',
 VOLTAGE='25V',
 PART_NUMBER='CH4104K1B00',
 VALUE='0.1UF',
 PRIM_FILE='./archive_libs/logical/q_cap/chips/chips.prt';

PART_NAME
 PC571 'Q_CAP_C0805-22UF,16V,20%,X6S,CH6223MEA01':;

SECTION_NUMBER 1
 '@T6G_MB_LIB.T6G(SCH_1):PAGE245_I36@PURE_QUANTA.Q_CAP(CHIPS)':
 C_PATH='@t6g_mb_lib.t6g(sch_1):page245_i36@pure_quanta.q_cap(chips)',
 P_PATH='@t6g_mb_lib.t6g(sch_1):page190_i36@pure_quanta.q_cap(chips)',
 PATH='I36',
 DRAWING='@T6G_MB_LIB.T6G(SCH_1):PAGE245',
 TOLERANCE='20%',
 MATERIAL='X6S',
 PHYS_PAGE='190',
 XY='(-2700,1100)',
 ROT='0',
 VER='1',
 PACK_TYPE='C0805',
 LOCATION='PC571',
 CDS_LIB='pure_quanta',
 CDS_PART_NAME='Q_CAP_C0805-22UF,16V,20%,X6S,CH6223MEA01',
 VOLTAGE='16V',
 PART_NUMBER='CH6223MEA01',
 VALUE='22UF',
 PRIM_FILE='./archive_libs/logical/q_cap/chips/chips.prt';

PART_NAME
 PC571_5 'Q_CAP_C0805-22UF,16V,20%,X6S,CH6223MEA01':;

SECTION_NUMBER 1
 '@T6G_MB_LIB.T6G(SCH_1):PAGE171_I48@PURE_QUANTA.Q_CAP(CHIPS)':
 C_PATH='@t6g_mb_lib.t6g(sch_1):page171_i48@pure_quanta.q_cap(chips)',
 P_PATH='@t6g_mb_lib.t6g(sch_1):page196_i48@pure_quanta.q_cap(chips)',
 PATH='I48',
 DRAWING='@T6G_MB_LIB.T6G(SCH_1):PAGE171',
 TOLERANCE='20%',
 MATERIAL='X6S',
 PHYS_PAGE='196',
 XY='(-4250,5450)',
 ROT='0',
 VER='1',
 PACK_TYPE='C0805',
 LOCATION='PC571_5',
 CDS_LIB='pure_quanta',
 CDS_PART_NAME='Q_CAP_C0805-22UF,16V,20%,X6S,CH6223MEA01',
 VOLTAGE='16V',
 PART_NUMBER='CH6223MEA01',
 VALUE='22UF',
 PRIM_FILE='./archive_libs/logical/q_cap/chips/chips.prt';

PART_NAME
 PC572_5 'Q_CAP_C0805-22UF,16V,20%,X6S,CH6223MEA01':;

SECTION_NUMBER 1
 '@T6G_MB_LIB.T6G(SCH_1):PAGE171_I49@PURE_QUANTA.Q_CAP(CHIPS)':
 C_PATH='@t6g_mb_lib.t6g(sch_1):page171_i49@pure_quanta.q_cap(chips)',
 P_PATH='@t6g_mb_lib.t6g(sch_1):page196_i49@pure_quanta.q_cap(chips)',
 PATH='I49',
 DRAWING='@T6G_MB_LIB.T6G(SCH_1):PAGE171',
 TOLERANCE='20%',
 MATERIAL='X6S',
 PHYS_PAGE='196',
 XY='(-3900,5450)',
 ROT='0',
 VER='1',
 PACK_TYPE='C0805',
 LOCATION='PC572_5',
 CDS_LIB='pure_quanta',
 CDS_PART_NAME='Q_CAP_C0805-22UF,16V,20%,X6S,CH6223MEA01',
 VOLTAGE='16V',
 PART_NUMBER='CH6223MEA01',
 VALUE='22UF',
 PRIM_FILE='./archive_libs/logical/q_cap/chips/chips.prt';

PART_NAME
 PC573_5 'Q_CAP_C0805-22UF,16V,20%,X6S,CH6223MEA01':;

SECTION_NUMBER 1
 '@T6G_MB_LIB.T6G(SCH_1):PAGE171_I66@PURE_QUANTA.Q_CAP(CHIPS)':
 C_PATH='@t6g_mb_lib.t6g(sch_1):page171_i66@pure_quanta.q_cap(chips)',
 P_PATH='@t6g_mb_lib.t6g(sch_1):page196_i66@pure_quanta.q_cap(chips)',
 PATH='I66',
 DRAWING='@T6G_MB_LIB.T6G(SCH_1):PAGE171',
 TOLERANCE='20%',
 MATERIAL='X6S',
 PHYS_PAGE='196',
 XY='(-3550,5450)',
 ROT='0',
 VER='1',
 PACK_TYPE='C0805',
 LOCATION='PC573_5',
 CDS_LIB='pure_quanta',
 CDS_PART_NAME='Q_CAP_C0805-22UF,16V,20%,X6S,CH6223MEA01',
 VOLTAGE='16V',
 PART_NUMBER='CH6223MEA01',
 VALUE='22UF',
 PRIM_FILE='./archive_libs/logical/q_cap/chips/chips.prt';

PART_NAME
 PC574 'Q_CAP_0402-0.22UF,16V,10%,X7R,CH4223K1B00':;

SECTION_NUMBER 1
 '@T6G_MB_LIB.T6G(SCH_1):PAGE171_I63@PURE_QUANTA.Q_CAP(CHIPS)':
 C_PATH='@t6g_mb_lib.t6g(sch_1):page171_i63@pure_quanta.q_cap(chips)',
 P_PATH='@t6g_mb_lib.t6g(sch_1):page196_i63@pure_quanta.q_cap(chips)',
 PATH='I63',
 DRAWING='@T6G_MB_LIB.T6G(SCH_1):PAGE171',
 TOLERANCE='10%',
 MATERIAL='X7R',
 PHYS_PAGE='196',
 XY='(-3275,4800)',
 ROT='0',
 VER='1',
 PACK_TYPE='0402',
 LOCATION='PC574',
 CDS_LIB='pure_quanta',
 CDS_PART_NAME='Q_CAP_0402-0.22UF,16V,10%,X7R,CH4223K1B00',
 VOLTAGE='16V',
 PART_NUMBER='CH4223K1B00',
 VALUE='0.22UF',
 PRIM_FILE='./archive_libs/logical/q_cap/chips/chips.prt';

PART_NAME
 PC575_5 'Q_CAP_C0805-22UF,4V,20%,X6S,CH622KMEA03':;

SECTION_NUMBER 1
 '@T6G_MB_LIB.T6G(SCH_1):PAGE171_I69@PURE_QUANTA.Q_CAP(CHIPS)':
 C_PATH='@t6g_mb_lib.t6g(sch_1):page171_i69@pure_quanta.q_cap(chips)',
 P_PATH='@t6g_mb_lib.t6g(sch_1):page196_i69@pure_quanta.q_cap(chips)',
 PATH='I69',
 DRAWING='@T6G_MB_LIB.T6G(SCH_1):PAGE171',
 TOLERANCE='20%',
 MATERIAL='X6S',
 PHYS_PAGE='196',
 XY='(-1075,4400)',
 ROT='0',
 VER='1',
 PACK_TYPE='C0805',
 LOCATION='PC575_5',
 CDS_LIB='pure_quanta',
 CDS_PART_NAME='Q_CAP_C0805-22UF,4V,20%,X6S,CH622KMEA03',
 VOLTAGE='4V',
 PART_NUMBER='CH622KMEA03',
 VALUE='22UF',
 PRIM_FILE='./archive_libs/logical/q_cap/chips/chips.prt';

PART_NAME
 PC576 'Q_CAP_C0805-22UF,16V,20%,X6S,CH6223MEA01':;

SECTION_NUMBER 1
 '@T6G_MB_LIB.T6G(SCH_1):PAGE245_I39@PURE_QUANTA.Q_CAP(CHIPS)':
 C_PATH='@t6g_mb_lib.t6g(sch_1):page245_i39@pure_quanta.q_cap(chips)',
 P_PATH='@t6g_mb_lib.t6g(sch_1):page190_i39@pure_quanta.q_cap(chips)',
 PATH='I39',
 DRAWING='@T6G_MB_LIB.T6G(SCH_1):PAGE245',
 TOLERANCE='20%',
 MATERIAL='X6S',
 PHYS_PAGE='190',
 XY='(-2375,1100)',
 ROT='0',
 VER='1',
 PACK_TYPE='C0805',
 LOCATION='PC576',
 CDS_LIB='pure_quanta',
 CDS_PART_NAME='Q_CAP_C0805-22UF,16V,20%,X6S,CH6223MEA01',
 VOLTAGE='16V',
 PART_NUMBER='CH6223MEA01',
 VALUE='22UF',
 PRIM_FILE='./archive_libs/logical/q_cap/chips/chips.prt';

PART_NAME
 PC576_5 'Q_CAP_C0805-22UF,4V,20%,X6S,CH622KMEA03':;

SECTION_NUMBER 1
 '@T6G_MB_LIB.T6G(SCH_1):PAGE171_I71@PURE_QUANTA.Q_CAP(CHIPS)':
 C_PATH='@t6g_mb_lib.t6g(sch_1):page171_i71@pure_quanta.q_cap(chips)',
 P_PATH='@t6g_mb_lib.t6g(sch_1):page196_i71@pure_quanta.q_cap(chips)',
 PATH='I71',
 DRAWING='@T6G_MB_LIB.T6G(SCH_1):PAGE171',
 TOLERANCE='20%',
 MATERIAL='X6S',
 PHYS_PAGE='196',
 XY='(-650,4400)',
 ROT='0',
 VER='1',
 PACK_TYPE='C0805',
 LOCATION='PC576_5',
 CDS_LIB='pure_quanta',
 CDS_PART_NAME='Q_CAP_C0805-22UF,4V,20%,X6S,CH622KMEA03',
 VOLTAGE='4V',
 PART_NUMBER='CH622KMEA03',
 VALUE='22UF',
 PRIM_FILE='./archive_libs/logical/q_cap/chips/chips.prt';

PART_NAME
 PC577 'Q_CAP_0402-0.1UF,25V,10%,X7R,CH4104K1B00':;

SECTION_NUMBER 1
 '@T6G_MB_LIB.T6G(SCH_1):PAGE245_I41@PURE_QUANTA.Q_CAP(CHIPS)':
 C_PATH='@t6g_mb_lib.t6g(sch_1):page245_i41@pure_quanta.q_cap(chips)',
 P_PATH='@t6g_mb_lib.t6g(sch_1):page190_i41@pure_quanta.q_cap(chips)',
 PATH='I41',
 DRAWING='@T6G_MB_LIB.T6G(SCH_1):PAGE245',
 TOLERANCE='10%',
 MATERIAL='X7R',
 PHYS_PAGE='190',
 XY='(-1725,1100)',
 ROT='0',
 VER='1',
 PACK_TYPE='0402',
 LOCATION='PC577',
 CDS_LIB='pure_quanta',
 CDS_PART_NAME='Q_CAP_0402-0.1UF,25V,10%,X7R,CH4104K1B00',
 VOLTAGE='25V',
 PART_NUMBER='CH4104K1B00',
 VALUE='0.1UF',
 PRIM_FILE='./archive_libs/logical/q_cap/chips/chips.prt';

PART_NAME
 PC577_7 'Q_CAP_0402-0.1UF,25V,10%,X7R,CH4104K1B00':;

SECTION_NUMBER 1
 '@T6G_MB_LIB.T6G(SCH_1):PAGE173_I29@PURE_QUANTA.Q_CAP(CHIPS)':
 C_PATH='@t6g_mb_lib.t6g(sch_1):page173_i29@pure_quanta.q_cap(chips)',
 P_PATH='@t6g_mb_lib.t6g(sch_1):page198_i29@pure_quanta.q_cap(chips)',
 PATH='I29',
 DRAWING='@T6G_MB_LIB.T6G(SCH_1):PAGE173',
 TOLERANCE='10%',
 MATERIAL='X7R',
 PHYS_PAGE='198',
 XY='(-7650,4800)',
 ROT='0',
 VER='1',
 PACK_TYPE='0402',
 LOCATION='PC577_7',
 CDS_LIB='pure_quanta',
 CDS_PART_NAME='Q_CAP_0402-0.1UF,25V,10%,X7R,CH4104K1B00',
 VOLTAGE='25V',
 PART_NUMBER='CH4104K1B00',
 VALUE='0.1UF',
 PRIM_FILE='./archive_libs/logical/q_cap/chips/chips.prt';

PART_NAME
 PC578_8 'Q_CAP_0402-0.1UF,25V,10%,X7R,CH4104K1B00':;

SECTION_NUMBER 1
 '@T6G_MB_LIB.T6G(SCH_1):PAGE173_I4@PURE_QUANTA.Q_CAP(CHIPS)':
 C_PATH='@t6g_mb_lib.t6g(sch_1):page173_i4@pure_quanta.q_cap(chips)',
 P_PATH='@t6g_mb_lib.t6g(sch_1):page198_i4@pure_quanta.q_cap(chips)',
 PATH='I4',
 DRAWING='@T6G_MB_LIB.T6G(SCH_1):PAGE173',
 TOLERANCE='10%',
 MATERIAL='X7R',
 PHYS_PAGE='198',
 XY='(-7625,1700)',
 ROT='0',
 VER='1',
 PACK_TYPE='0402',
 LOCATION='PC578_8',
 CDS_LIB='pure_quanta',
 CDS_PART_NAME='Q_CAP_0402-0.1UF,25V,10%,X7R,CH4104K1B00',
 VOLTAGE='25V',
 PART_NUMBER='CH4104K1B00',
 VALUE='0.1UF',
 PRIM_FILE='./archive_libs/logical/q_cap/chips/chips.prt';

PART_NAME
 PC579 'Q_CAP_C0402-2.2UF,10V,10%,X6S,CH5222KEB01':;

SECTION_NUMBER 1
 '@T6G_MB_LIB.T6G(SCH_1):PAGE173_I36@PURE_QUANTA.Q_CAP(CHIPS)':
 C_PATH='@t6g_mb_lib.t6g(sch_1):page173_i36@pure_quanta.q_cap(chips)',
 P_PATH='@t6g_mb_lib.t6g(sch_1):page198_i36@pure_quanta.q_cap(chips)',
 PATH='I36',
 DRAWING='@T6G_MB_LIB.T6G(SCH_1):PAGE173',
 TOLERANCE='10%',
 MATERIAL='X6S',
 PHYS_PAGE='198',
 XY='(-7325,5425)',
 ROT='0',
 VER='1',
 PACK_TYPE='C0402',
 LOCATION='PC579',
 CDS_LIB='pure_quanta',
 CDS_PART_NAME='Q_CAP_C0402-2.2UF,10V,10%,X6S,CH5222KEB01',
 VOLTAGE='10V',
 PART_NUMBER='CH5222KEB01',
 VALUE='2.2UF',
 PRIM_FILE='./archive_libs/logical/q_cap/chips/chips.prt';

PART_NAME
 PC580 'Q_CAP_C0402-2.2UF,10V,10%,X6S,CH5222KEB01':;

SECTION_NUMBER 1
 '@T6G_MB_LIB.T6G(SCH_1):PAGE173_I11@PURE_QUANTA.Q_CAP(CHIPS)':
 C_PATH='@t6g_mb_lib.t6g(sch_1):page173_i11@pure_quanta.q_cap(chips)',
 P_PATH='@t6g_mb_lib.t6g(sch_1):page198_i11@pure_quanta.q_cap(chips)',
 PATH='I11',
 DRAWING='@T6G_MB_LIB.T6G(SCH_1):PAGE173',
 TOLERANCE='10%',
 MATERIAL='X6S',
 PHYS_PAGE='198',
 XY='(-7300,2325)',
 ROT='0',
 VER='1',
 PACK_TYPE='C0402',
 LOCATION='PC580',
 CDS_LIB='pure_quanta',
 CDS_PART_NAME='Q_CAP_C0402-2.2UF,10V,10%,X6S,CH5222KEB01',
 VOLTAGE='10V',
 PART_NUMBER='CH5222KEB01',
 VALUE='2.2UF',
 PRIM_FILE='./archive_libs/logical/q_cap/chips/chips.prt';

PART_NAME
 PC581 'Q_CAP_C0603-4.7UF,16V,10%,X6S,CH5473KE902':;

SECTION_NUMBER 1
 '@T6G_MB_LIB.T6G(SCH_1):PAGE245_I12@PURE_QUANTA.Q_CAP(CHIPS)':
 C_PATH='@t6g_mb_lib.t6g(sch_1):page245_i12@pure_quanta.q_cap(chips)',
 P_PATH='@t6g_mb_lib.t6g(sch_1):page190_i12@pure_quanta.q_cap(chips)',
 PATH='I12',
 DRAWING='@T6G_MB_LIB.T6G(SCH_1):PAGE245',
 TOLERANCE='10%',
 MATERIAL='X6S',
 PHYS_PAGE='190',
 XY='(-2050,-375)',
 ROT='0',
 VER='1',
 PACK_TYPE='C0603',
 LOCATION='PC581',
 CDS_LIB='pure_quanta',
 CDS_PART_NAME='Q_CAP_C0603-4.7UF,16V,10%,X6S,CH5473KE902',
 VOLTAGE='16V',
 PART_NUMBER='CH5473KE902',
 VALUE='4.7UF',
 PRIM_FILE='./archive_libs/logical/q_cap/chips/chips.prt';

PART_NAME
 PC581_SOP0_1 'Q_CAP_C0402-2.2UF,10V,10%,X6S,CH5222KEB01':;

SECTION_NUMBER 1
 '@T6G_MB_LIB.T6G(SCH_1):PAGE173_I40@PURE_QUANTA.Q_CAP(CHIPS)':
 C_PATH='@t6g_mb_lib.t6g(sch_1):page173_i40@pure_quanta.q_cap(chips)',
 P_PATH='@t6g_mb_lib.t6g(sch_1):page198_i40@pure_quanta.q_cap(chips)',
 PATH='I40',
 DRAWING='@T6G_MB_LIB.T6G(SCH_1):PAGE173',
 TOLERANCE='10%',
 MATERIAL='X6S',
 PHYS_PAGE='198',
 XY='(-6975,5925)',
 ROT='0',
 VER='1',
 PACK_TYPE='C0402',
 LOCATION='PC581_SOP0_1',
 CDS_LIB='pure_quanta',
 CDS_PART_NAME='Q_CAP_C0402-2.2UF,10V,10%,X6S,CH5222KEB01',
 VOLTAGE='10V',
 PART_NUMBER='CH5222KEB01',
 VALUE='2.2UF',
 PRIM_FILE='./archive_libs/logical/q_cap/chips/chips.prt';

PART_NAME
 PC582_SOP0_2 'Q_CAP_C0402-2.2UF,10V,10%,X6S,CH5222KEB01':;

SECTION_NUMBER 1
 '@T6G_MB_LIB.T6G(SCH_1):PAGE173_I14@PURE_QUANTA.Q_CAP(CHIPS)':
 C_PATH='@t6g_mb_lib.t6g(sch_1):page173_i14@pure_quanta.q_cap(chips)',
 P_PATH='@t6g_mb_lib.t6g(sch_1):page198_i14@pure_quanta.q_cap(chips)',
 PATH='I14',
 DRAWING='@T6G_MB_LIB.T6G(SCH_1):PAGE173',
 TOLERANCE='10%',
 MATERIAL='X6S',
 PHYS_PAGE='198',
 XY='(-6950,2850)',
 ROT='0',
 VER='1',
 PACK_TYPE='C0402',
 LOCATION='PC582_SOP0_2',
 CDS_LIB='pure_quanta',
 CDS_PART_NAME='Q_CAP_C0402-2.2UF,10V,10%,X6S,CH5222KEB01',
 VOLTAGE='10V',
 PART_NUMBER='CH5222KEB01',
 VALUE='2.2UF',
 PRIM_FILE='./archive_libs/logical/q_cap/chips/chips.prt';

PART_NAME
 PC583 'Q_CAP_0402-0.1UF,25V,10%,X7R,CH4104K1B00':;

SECTION_NUMBER 1
 '@T6G_MB_LIB.T6G(SCH_1):PAGE173_I77@PURE_QUANTA.Q_CAP(CHIPS)':
 C_PATH='@t6g_mb_lib.t6g(sch_1):page173_i77@pure_quanta.q_cap(chips)',
 P_PATH='@t6g_mb_lib.t6g(sch_1):page198_i77@pure_quanta.q_cap(chips)',
 PATH='I77',
 DRAWING='@T6G_MB_LIB.T6G(SCH_1):PAGE173',
 TOLERANCE='10%',
 MATERIAL='X7R',
 PHYS_PAGE='198',
 XY='(-2375,5950)',
 ROT='0',
 VER='1',
 PACK_TYPE='0402',
 LOCATION='PC583',
 CDS_LIB='pure_quanta',
 CDS_PART_NAME='Q_CAP_0402-0.1UF,25V,10%,X7R,CH4104K1B00',
 VOLTAGE='25V',
 PART_NUMBER='CH4104K1B00',
 VALUE='0.1UF',
 PRIM_FILE='./archive_libs/logical/q_cap/chips/chips.prt';

PART_NAME
 PC583_1 'Q_CAP_0402-0.1UF,25V,10%,X7R,CH4104K1B00':;

SECTION_NUMBER 1
 '@T6G_MB_LIB.T6G(SCH_1):PAGE173_I43@PURE_QUANTA.Q_CAP(CHIPS)':
 C_PATH='@t6g_mb_lib.t6g(sch_1):page173_i43@pure_quanta.q_cap(chips)',
 P_PATH='@t6g_mb_lib.t6g(sch_1):page198_i43@pure_quanta.q_cap(chips)',
 PATH='I43',
 DRAWING='@T6G_MB_LIB.T6G(SCH_1):PAGE173',
 TOLERANCE='10%',
 MATERIAL='X7R',
 PHYS_PAGE='198',
 XY='(-5225,5925)',
 ROT='0',
 VER='1',
 PACK_TYPE='0402',
 LOCATION='PC583_1',
 CDS_LIB='pure_quanta',
 CDS_PART_NAME='Q_CAP_0402-0.1UF,25V,10%,X7R,CH4104K1B00',
 VOLTAGE='25V',
 PART_NUMBER='CH4104K1B00',
 VALUE='0.1UF',
 PRIM_FILE='./archive_libs/logical/q_cap/chips/chips.prt';

PART_NAME
 PC584_2 'Q_CAP_C0402-1UF,25V,10%,X6S,CH5104KEB02':;

SECTION_NUMBER 1
 '@T6G_MB_LIB.T6G(SCH_1):PAGE173_I23@PURE_QUANTA.Q_CAP(CHIPS)':
 C_PATH='@t6g_mb_lib.t6g(sch_1):page173_i23@pure_quanta.q_cap(chips)',
 P_PATH='@t6g_mb_lib.t6g(sch_1):page198_i23@pure_quanta.q_cap(chips)',
 PATH='I23',
 DRAWING='@T6G_MB_LIB.T6G(SCH_1):PAGE173',
 TOLERANCE='10%',
 MATERIAL='X6S',
 PHYS_PAGE='198',
 XY='(-4775,2875)',
 ROT='0',
 VER='1',
 PACK_TYPE='C0402',
 LOCATION='PC584_2',
 CDS_LIB='pure_quanta',
 CDS_PART_NAME='Q_CAP_C0402-1UF,25V,10%,X6S,CH5104KEB02',
 VOLTAGE='25V',
 PART_NUMBER='CH5104KEB02',
 VALUE='1UF',
 PRIM_FILE='./archive_libs/logical/q_cap/chips/chips.prt';

PART_NAME
 PC585_1 'Q_CAP_C0402-1UF,25V,10%,X6S,CH5104KEB02':;

SECTION_NUMBER 1
 '@T6G_MB_LIB.T6G(SCH_1):PAGE173_I44@PURE_QUANTA.Q_CAP(CHIPS)':
 C_PATH='@t6g_mb_lib.t6g(sch_1):page173_i44@pure_quanta.q_cap(chips)',
 P_PATH='@t6g_mb_lib.t6g(sch_1):page198_i44@pure_quanta.q_cap(chips)',
 PATH='I44',
 DRAWING='@T6G_MB_LIB.T6G(SCH_1):PAGE173',
 TOLERANCE='10%',
 MATERIAL='X6S',
 PHYS_PAGE='198',
 XY='(-4900,5925)',
 ROT='0',
 VER='1',
 PACK_TYPE='C0402',
 LOCATION='PC585_1',
 CDS_LIB='pure_quanta',
 CDS_PART_NAME='Q_CAP_C0402-1UF,25V,10%,X6S,CH5104KEB02',
 VOLTAGE='25V',
 PART_NUMBER='CH5104KEB02',
 VALUE='1UF',
 PRIM_FILE='./archive_libs/logical/q_cap/chips/chips.prt';

PART_NAME
 PC586_2 'Q_CAP_0402-0.1UF,25V,10%,X7R,CH4104K1B00':;

SECTION_NUMBER 1
 '@T6G_MB_LIB.T6G(SCH_1):PAGE173_I21@PURE_QUANTA.Q_CAP(CHIPS)':
 C_PATH='@t6g_mb_lib.t6g(sch_1):page173_i21@pure_quanta.q_cap(chips)',
 P_PATH='@t6g_mb_lib.t6g(sch_1):page198_i21@pure_quanta.q_cap(chips)',
 PATH='I21',
 DRAWING='@T6G_MB_LIB.T6G(SCH_1):PAGE173',
 TOLERANCE='10%',
 MATERIAL='X7R',
 PHYS_PAGE='198',
 XY='(-5150,2875)',
 ROT='0',
 VER='1',
 PACK_TYPE='0402',
 LOCATION='PC586_2',
 CDS_LIB='pure_quanta',
 CDS_PART_NAME='Q_CAP_0402-0.1UF,25V,10%,X7R,CH4104K1B00',
 VOLTAGE='25V',
 PART_NUMBER='CH4104K1B00',
 VALUE='0.1UF',
 PRIM_FILE='./archive_libs/logical/q_cap/chips/chips.prt';

PART_NAME
 PC587_1 'Q_CAP_C0805-22UF,16V,20%,X6S,CH6223MEA01':;

SECTION_NUMBER 1
 '@T6G_MB_LIB.T6G(SCH_1):PAGE173_I49@PURE_QUANTA.Q_CAP(CHIPS)':
 C_PATH='@t6g_mb_lib.t6g(sch_1):page173_i49@pure_quanta.q_cap(chips)',
 P_PATH='@t6g_mb_lib.t6g(sch_1):page198_i49@pure_quanta.q_cap(chips)',
 PATH='I49',
 DRAWING='@T6G_MB_LIB.T6G(SCH_1):PAGE173',
 TOLERANCE='20%',
 MATERIAL='X6S',
 PHYS_PAGE='198',
 XY='(-4575,5925)',
 ROT='0',
 VER='1',
 PACK_TYPE='C0805',
 LOCATION='PC587_1',
 CDS_LIB='pure_quanta',
 CDS_PART_NAME='Q_CAP_C0805-22UF,16V,20%,X6S,CH6223MEA01',
 VOLTAGE='16V',
 PART_NUMBER='CH6223MEA01',
 VALUE='22UF',
 PRIM_FILE='./archive_libs/logical/q_cap/chips/chips.prt';

PART_NAME
 PC588_2 'Q_CAP_C0805-22UF,16V,20%,X6S,CH6223MEA01':;

SECTION_NUMBER 1
 '@T6G_MB_LIB.T6G(SCH_1):PAGE173_I24@PURE_QUANTA.Q_CAP(CHIPS)':
 C_PATH='@t6g_mb_lib.t6g(sch_1):page173_i24@pure_quanta.q_cap(chips)',
 P_PATH='@t6g_mb_lib.t6g(sch_1):page198_i24@pure_quanta.q_cap(chips)',
 PATH='I24',
 DRAWING='@T6G_MB_LIB.T6G(SCH_1):PAGE173',
 TOLERANCE='20%',
 MATERIAL='X6S',
 PHYS_PAGE='198',
 XY='(-4450,2875)',
 ROT='0',
 VER='1',
 PACK_TYPE='C0805',
 LOCATION='PC588_2',
 CDS_LIB='pure_quanta',
 CDS_PART_NAME='Q_CAP_C0805-22UF,16V,20%,X6S,CH6223MEA01',
 VOLTAGE='16V',
 PART_NUMBER='CH6223MEA01',
 VALUE='22UF',
 PRIM_FILE='./archive_libs/logical/q_cap/chips/chips.prt';

PART_NAME
 PC589_1 'Q_CAP_C0805-22UF,16V,20%,X6S,CH6223MEA01':;

SECTION_NUMBER 1
 '@T6G_MB_LIB.T6G(SCH_1):PAGE173_I50@PURE_QUANTA.Q_CAP(CHIPS)':
 C_PATH='@t6g_mb_lib.t6g(sch_1):page173_i50@pure_quanta.q_cap(chips)',
 P_PATH='@t6g_mb_lib.t6g(sch_1):page198_i50@pure_quanta.q_cap(chips)',
 PATH='I50',
 DRAWING='@T6G_MB_LIB.T6G(SCH_1):PAGE173',
 TOLERANCE='20%',
 MATERIAL='X6S',
 PHYS_PAGE='198',
 XY='(-4250,5925)',
 ROT='0',
 VER='1',
 PACK_TYPE='C0805',
 LOCATION='PC589_1',
 CDS_LIB='pure_quanta',
 CDS_PART_NAME='Q_CAP_C0805-22UF,16V,20%,X6S,CH6223MEA01',
 VOLTAGE='16V',
 PART_NUMBER='CH6223MEA01',
 VALUE='22UF',
 PRIM_FILE='./archive_libs/logical/q_cap/chips/chips.prt';

PART_NAME
 PC590_2 'Q_CAP_C0805-22UF,16V,20%,X6S,CH6223MEA01':;

SECTION_NUMBER 1
 '@T6G_MB_LIB.T6G(SCH_1):PAGE173_I25@PURE_QUANTA.Q_CAP(CHIPS)':
 C_PATH='@t6g_mb_lib.t6g(sch_1):page173_i25@pure_quanta.q_cap(chips)',
 P_PATH='@t6g_mb_lib.t6g(sch_1):page198_i25@pure_quanta.q_cap(chips)',
 PATH='I25',
 DRAWING='@T6G_MB_LIB.T6G(SCH_1):PAGE173',
 TOLERANCE='20%',
 MATERIAL='X6S',
 PHYS_PAGE='198',
 XY='(-4125,2875)',
 ROT='0',
 VER='1',
 PACK_TYPE='C0805',
 LOCATION='PC590_2',
 CDS_LIB='pure_quanta',
 CDS_PART_NAME='Q_CAP_C0805-22UF,16V,20%,X6S,CH6223MEA01',
 VOLTAGE='16V',
 PART_NUMBER='CH6223MEA01',
 VALUE='22UF',
 PRIM_FILE='./archive_libs/logical/q_cap/chips/chips.prt';

PART_NAME
 PC591 'Q_CAP_C0603-2.2UF,16V,10%,X6S,CH5223KE901':;

SECTION_NUMBER 1
 '@T6G_MB_LIB.T6G(SCH_1):PAGE245_I19@PURE_QUANTA.Q_CAP(CHIPS)':
 C_PATH='@t6g_mb_lib.t6g(sch_1):page245_i19@pure_quanta.q_cap(chips)',
 P_PATH='@t6g_mb_lib.t6g(sch_1):page190_i19@pure_quanta.q_cap(chips)',
 PATH='I19',
 DRAWING='@T6G_MB_LIB.T6G(SCH_1):PAGE245',
 TOLERANCE='10%',
 MATERIAL='X6S',
 PHYS_PAGE='190',
 XY='(-1625,-375)',
 ROT='0',
 VER='1',
 PACK_TYPE='C0603',
 LOCATION='PC591',
 CDS_LIB='pure_quanta',
 CDS_PART_NAME='Q_CAP_C0603-2.2UF,16V,10%,X6S,CH5223KE901',
 VOLTAGE='16V',
 PART_NUMBER='CH5223KE901',
 VALUE='2.2UF',
 PRIM_FILE='./archive_libs/logical/q_cap/chips/chips.prt';

PART_NAME
 PC591_1 'Q_CAP_C0805-22UF,16V,20%,X6S,CH6223MEA01':;

SECTION_NUMBER 1
 '@T6G_MB_LIB.T6G(SCH_1):PAGE173_I51@PURE_QUANTA.Q_CAP(CHIPS)':
 C_PATH='@t6g_mb_lib.t6g(sch_1):page173_i51@pure_quanta.q_cap(chips)',
 P_PATH='@t6g_mb_lib.t6g(sch_1):page198_i51@pure_quanta.q_cap(chips)',
 PATH='I51',
 DRAWING='@T6G_MB_LIB.T6G(SCH_1):PAGE173',
 TOLERANCE='20%',
 MATERIAL='X6S',
 PHYS_PAGE='198',
 XY='(-4025,5925)',
 ROT='0',
 VER='1',
 PACK_TYPE='C0805',
 LOCATION='PC591_1',
 CDS_LIB='pure_quanta',
 CDS_PART_NAME='Q_CAP_C0805-22UF,16V,20%,X6S,CH6223MEA01',
 VOLTAGE='16V',
 PART_NUMBER='CH6223MEA01',
 VALUE='22UF',
 PRIM_FILE='./archive_libs/logical/q_cap/chips/chips.prt';

PART_NAME
 PC592_2 'Q_CAP_C0805-22UF,16V,20%,X6S,CH6223MEA01':;

SECTION_NUMBER 1
 '@T6G_MB_LIB.T6G(SCH_1):PAGE173_I56@PURE_QUANTA.Q_CAP(CHIPS)':
 C_PATH='@t6g_mb_lib.t6g(sch_1):page173_i56@pure_quanta.q_cap(chips)',
 P_PATH='@t6g_mb_lib.t6g(sch_1):page198_i56@pure_quanta.q_cap(chips)',
 PATH='I56',
 DRAWING='@T6G_MB_LIB.T6G(SCH_1):PAGE173',
 TOLERANCE='20%',
 MATERIAL='X6S',
 PHYS_PAGE='198',
 XY='(-3800,2875)',
 ROT='0',
 VER='1',
 PACK_TYPE='C0805',
 LOCATION='PC592_2',
 CDS_LIB='pure_quanta',
 CDS_PART_NAME='Q_CAP_C0805-22UF,16V,20%,X6S,CH6223MEA01',
 VOLTAGE='16V',
 PART_NUMBER='CH6223MEA01',
 VALUE='22UF',
 PRIM_FILE='./archive_libs/logical/q_cap/chips/chips.prt';

PART_NAME
 PC593 'Q_CAP_0402-0.22UF,16V,10%,X7R,CH4223K1B00':;

SECTION_NUMBER 1
 '@T6G_MB_LIB.T6G(SCH_1):PAGE173_I68@PURE_QUANTA.Q_CAP(CHIPS)':
 C_PATH='@t6g_mb_lib.t6g(sch_1):page173_i68@pure_quanta.q_cap(chips)',
 P_PATH='@t6g_mb_lib.t6g(sch_1):page198_i68@pure_quanta.q_cap(chips)',
 PATH='I68',
 DRAWING='@T6G_MB_LIB.T6G(SCH_1):PAGE173',
 TOLERANCE='10%',
 MATERIAL='X7R',
 PHYS_PAGE='198',
 XY='(-3675,5300)',
 ROT='0',
 VER='1',
 PACK_TYPE='0402',
 LOCATION='PC593',
 CDS_LIB='pure_quanta',
 CDS_PART_NAME='Q_CAP_0402-0.22UF,16V,10%,X7R,CH4223K1B00',
 VOLTAGE='16V',
 PART_NUMBER='CH4223K1B00',
 VALUE='0.22UF',
 PRIM_FILE='./archive_libs/logical/q_cap/chips/chips.prt';

PART_NAME
 PC593_1 'Q_CAP_C0805-22UF,16V,20%,X6S,CH6223MEA01':;

SECTION_NUMBER 1
 '@T6G_MB_LIB.T6G(SCH_1):PAGE173_I72@PURE_QUANTA.Q_CAP(CHIPS)':
 C_PATH='@t6g_mb_lib.t6g(sch_1):page173_i72@pure_quanta.q_cap(chips)',
 P_PATH='@t6g_mb_lib.t6g(sch_1):page198_i72@pure_quanta.q_cap(chips)',
 PATH='I72',
 DRAWING='@T6G_MB_LIB.T6G(SCH_1):PAGE173',
 TOLERANCE='20%',
 MATERIAL='X6S',
 PHYS_PAGE='198',
 XY='(-3800,5925)',
 ROT='0',
 VER='1',
 PACK_TYPE='C0805',
 LOCATION='PC593_1',
 CDS_LIB='pure_quanta',
 CDS_PART_NAME='Q_CAP_C0805-22UF,16V,20%,X6S,CH6223MEA01',
 VOLTAGE='16V',
 PART_NUMBER='CH6223MEA01',
 VALUE='22UF',
 PRIM_FILE='./archive_libs/logical/q_cap/chips/chips.prt';

PART_NAME
 PC594 'Q_CAP_0402-0.22UF,16V,10%,X7R,CH4223K1B00':;

SECTION_NUMBER 1
 '@T6G_MB_LIB.T6G(SCH_1):PAGE173_I52@PURE_QUANTA.Q_CAP(CHIPS)':
 C_PATH='@t6g_mb_lib.t6g(sch_1):page173_i52@pure_quanta.q_cap(chips)',
 P_PATH='@t6g_mb_lib.t6g(sch_1):page198_i52@pure_quanta.q_cap(chips)',
 PATH='I52',
 DRAWING='@T6G_MB_LIB.T6G(SCH_1):PAGE173',
 TOLERANCE='10%',
 MATERIAL='X7R',
 PHYS_PAGE='198',
 XY='(-3575,2200)',
 ROT='0',
 VER='1',
 PACK_TYPE='0402',
 LOCATION='PC594',
 CDS_LIB='pure_quanta',
 CDS_PART_NAME='Q_CAP_0402-0.22UF,16V,10%,X7R,CH4223K1B00',
 VOLTAGE='16V',
 PART_NUMBER='CH4223K1B00',
 VALUE='0.22UF',
 PRIM_FILE='./archive_libs/logical/q_cap/chips/chips.prt';

PART_NAME
 PC595_2 'Q_CAP_C0805-22UF,16V,20%,X6S,CH6223MEA01':;

SECTION_NUMBER 1
 '@T6G_MB_LIB.T6G(SCH_1):PAGE173_I57@PURE_QUANTA.Q_CAP(CHIPS)':
 C_PATH='@t6g_mb_lib.t6g(sch_1):page173_i57@pure_quanta.q_cap(chips)',
 P_PATH='@t6g_mb_lib.t6g(sch_1):page198_i57@pure_quanta.q_cap(chips)',
 PATH='I57',
 DRAWING='@T6G_MB_LIB.T6G(SCH_1):PAGE173',
 TOLERANCE='20%',
 MATERIAL='X6S',
 PHYS_PAGE='198',
 XY='(-3400,2875)',
 ROT='0',
 VER='1',
 PACK_TYPE='C0805',
 LOCATION='PC595_2',
 CDS_LIB='pure_quanta',
 CDS_PART_NAME='Q_CAP_C0805-22UF,16V,20%,X6S,CH6223MEA01',
 VOLTAGE='16V',
 PART_NUMBER='CH6223MEA01',
 VALUE='22UF',
 PRIM_FILE='./archive_libs/logical/q_cap/chips/chips.prt';

PART_NAME
 PC596 'Q_CAPP_THLF-270UF,16V,20%,OSCON,CC72703MD38':;

SECTION_NUMBER 1
 '@T6G_MB_LIB.T6G(SCH_1):PAGE173_I73@PURE_QUANTA.Q_CAPP(CHIPS)':
 C_PATH='@t6g_mb_lib.t6g(sch_1):page173_i73@pure_quanta.q_capp(chips)',
 P_PATH='@t6g_mb_lib.t6g(sch_1):page198_i73@pure_quanta.q_capp(chips)',
 PATH='I73',
 DRAWING='@T6G_MB_LIB.T6G(SCH_1):PAGE173',
 TOLERANCE='20%',
 MATERIAL='OSCON',
 PHYS_PAGE='198',
 XY='(-3225,5925)',
 ROT='0',
 VER='1',
 PACK_TYPE='THLF',
 LOCATION='PC596',
 CDS_LIB='pure_quanta',
 CDS_PART_NAME='Q_CAPP_THLF-270UF,16V,20%,OSCON,CC72703MD38',
 VOLTAGE='16V',
 PART_NUMBER='CC72703MD38',
 VALUE='270UF',
 PRIM_FILE='./archive_libs/logical/q_capp/chips/chips.prt';

PART_NAME
 PC597 'Q_CAPP_SMLF-470UF,2.5V,20%,EMPTY,CH747LM8825':;

SECTION_NUMBER 1
 '@T6G_MB_LIB.T6G(SCH_1):PAGE173_I63@PURE_QUANTA.Q_CAPP(CHIPS)':
 C_PATH='@t6g_mb_lib.t6g(sch_1):page173_i63@pure_quanta.q_capp(chips)',
 P_PATH='@t6g_mb_lib.t6g(sch_1):page198_i63@pure_quanta.q_capp(chips)',
 PATH='I63',
 DRAWING='@T6G_MB_LIB.T6G(SCH_1):PAGE173',
 TOLERANCE='20%',
 MATERIAL='EMPTY',
 PHYS_PAGE='198',
 XY='(-1625,3250)',
 ROT='0',
 VER='1',
 PACK_TYPE='SMLF',
 LOCATION='PC597',
 CDS_LIB='pure_quanta',
 CDS_PART_NAME='Q_CAPP_SMLF-470UF,2.5V,20%,EMPTY,CH747LM8825',
 VOLTAGE='2.5V',
 PART_NUMBER='CH747LM8825',
 VALUE='470UF',
 PRIM_FILE='./archive_libs/logical/q_capp/chips/chips.prt';

PART_NAME
 PC598 'Q_CAPP_SMLF-470UF,2.5V,20%,SPCAP,CH747LM8825':;

SECTION_NUMBER 1
 '@T6G_MB_LIB.T6G(SCH_1):PAGE173_I64@PURE_QUANTA.Q_CAPP(CHIPS)':
 C_PATH='@t6g_mb_lib.t6g(sch_1):page173_i64@pure_quanta.q_capp(chips)',
 P_PATH='@t6g_mb_lib.t6g(sch_1):page198_i64@pure_quanta.q_capp(chips)',
 PATH='I64',
 DRAWING='@T6G_MB_LIB.T6G(SCH_1):PAGE173',
 TOLERANCE='20%',
 MATERIAL='SPCAP',
 PHYS_PAGE='198',
 XY='(-1275,3250)',
 ROT='0',
 VER='1',
 PACK_TYPE='SMLF',
 LOCATION='PC598',
 CDS_LIB='pure_quanta',
 CDS_PART_NAME='Q_CAPP_SMLF-470UF,2.5V,20%,SPCAP,CH747LM8825',
 VOLTAGE='2.5V',
 PART_NUMBER='CH747LM8825',
 VALUE='470UF',
 PRIM_FILE='./archive_libs/logical/q_capp/chips/chips.prt';

PART_NAME
 PC599 'Q_CAP_0402-0.1UF,25V,10%,X7R,CH4104K1B00':;

SECTION_NUMBER 1
 '@T6G_MB_LIB.T6G(SCH_1):PAGE173_I79@PURE_QUANTA.Q_CAP(CHIPS)':
 C_PATH='@t6g_mb_lib.t6g(sch_1):page173_i79@pure_quanta.q_cap(chips)',
 P_PATH='@t6g_mb_lib.t6g(sch_1):page198_i79@pure_quanta.q_cap(chips)',
 PATH='I79',
 DRAWING='@T6G_MB_LIB.T6G(SCH_1):PAGE173',
 TOLERANCE='10%',
 MATERIAL='X7R',
 PHYS_PAGE='198',
 XY='(-1500,4900)',
 ROT='0',
 VER='1',
 PACK_TYPE='0402',
 LOCATION='PC599',
 CDS_LIB='pure_quanta',
 CDS_PART_NAME='Q_CAP_0402-0.1UF,25V,10%,X7R,CH4104K1B00',
 VOLTAGE='25V',
 PART_NUMBER='CH4104K1B00',
 VALUE='0.1UF',
 PRIM_FILE='./archive_libs/logical/q_cap/chips/chips.prt';

PART_NAME
 PC600_2 'Q_CAP_C0805-22UF,4V,20%,X6S,CH622KMEA03':;

SECTION_NUMBER 1
 '@T6G_MB_LIB.T6G(SCH_1):PAGE173_I59@PURE_QUANTA.Q_CAP(CHIPS)':
 C_PATH='@t6g_mb_lib.t6g(sch_1):page173_i59@pure_quanta.q_cap(chips)',
 P_PATH='@t6g_mb_lib.t6g(sch_1):page198_i59@pure_quanta.q_cap(chips)',
 PATH='I59',
 DRAWING='@T6G_MB_LIB.T6G(SCH_1):PAGE173',
 TOLERANCE='20%',
 MATERIAL='X6S',
 PHYS_PAGE='198',
 XY='(-1425,1800)',
 ROT='0',
 VER='1',
 PACK_TYPE='C0805',
 LOCATION='PC600_2',
 CDS_LIB='pure_quanta',
 CDS_PART_NAME='Q_CAP_C0805-22UF,4V,20%,X6S,CH622KMEA03',
 VOLTAGE='4V',
 PART_NUMBER='CH622KMEA03',
 VALUE='22UF',
 PRIM_FILE='./archive_libs/logical/q_cap/chips/chips.prt';

PART_NAME
 PC601 'Q_CAPP_SMLF-470UF,2.5V,20%,SPCAP,CH747LM8825':;

SECTION_NUMBER 1
 '@T6G_MB_LIB.T6G(SCH_1):PAGE173_I66@PURE_QUANTA.Q_CAPP(CHIPS)':
 C_PATH='@t6g_mb_lib.t6g(sch_1):page173_i66@pure_quanta.q_capp(chips)',
 P_PATH='@t6g_mb_lib.t6g(sch_1):page198_i66@pure_quanta.q_capp(chips)',
 PATH='I66',
 DRAWING='@T6G_MB_LIB.T6G(SCH_1):PAGE173',
 TOLERANCE='20%',
 MATERIAL='SPCAP',
 PHYS_PAGE='198',
 XY='(-950,3250)',
 ROT='0',
 VER='1',
 PACK_TYPE='SMLF',
 LOCATION='PC601',
 CDS_LIB='pure_quanta',
 CDS_PART_NAME='Q_CAPP_SMLF-470UF,2.5V,20%,SPCAP,CH747LM8825',
 VOLTAGE='2.5V',
 PART_NUMBER='CH747LM8825',
 VALUE='470UF',
 PRIM_FILE='./archive_libs/logical/q_capp/chips/chips.prt';

PART_NAME
 PC602_1 'Q_CAP_C0805-22UF,4V,20%,X6S,CH622KMEA03':;

SECTION_NUMBER 1
 '@T6G_MB_LIB.T6G(SCH_1):PAGE173_I80@PURE_QUANTA.Q_CAP(CHIPS)':
 C_PATH='@t6g_mb_lib.t6g(sch_1):page173_i80@pure_quanta.q_cap(chips)',
 P_PATH='@t6g_mb_lib.t6g(sch_1):page198_i80@pure_quanta.q_cap(chips)',
 PATH='I80',
 DRAWING='@T6G_MB_LIB.T6G(SCH_1):PAGE173',
 TOLERANCE='20%',
 MATERIAL='X6S',
 PHYS_PAGE='198',
 XY='(-1125,4900)',
 ROT='0',
 VER='1',
 PACK_TYPE='C0805',
 LOCATION='PC602_1',
 CDS_LIB='pure_quanta',
 CDS_PART_NAME='Q_CAP_C0805-22UF,4V,20%,X6S,CH622KMEA03',
 VOLTAGE='4V',
 PART_NUMBER='CH622KMEA03',
 VALUE='22UF',
 PRIM_FILE='./archive_libs/logical/q_cap/chips/chips.prt';

PART_NAME
 PC603_2 'Q_CAP_C0805-22UF,4V,20%,X6S,CH622KMEA03':;

SECTION_NUMBER 1
 '@T6G_MB_LIB.T6G(SCH_1):PAGE173_I61@PURE_QUANTA.Q_CAP(CHIPS)':
 C_PATH='@t6g_mb_lib.t6g(sch_1):page173_i61@pure_quanta.q_cap(chips)',
 P_PATH='@t6g_mb_lib.t6g(sch_1):page198_i61@pure_quanta.q_cap(chips)',
 PATH='I61',
 DRAWING='@T6G_MB_LIB.T6G(SCH_1):PAGE173',
 TOLERANCE='20%',
 MATERIAL='X6S',
 PHYS_PAGE='198',
 XY='(-1000,1800)',
 ROT='0',
 VER='1',
 PACK_TYPE='C0805',
 LOCATION='PC603_2',
 CDS_LIB='pure_quanta',
 CDS_PART_NAME='Q_CAP_C0805-22UF,4V,20%,X6S,CH622KMEA03',
 VOLTAGE='4V',
 PART_NUMBER='CH622KMEA03',
 VALUE='22UF',
 PRIM_FILE='./archive_libs/logical/q_cap/chips/chips.prt';

PART_NAME
 PC604_1 'Q_CAP_C0805-22UF,4V,20%,X6S,CH622KMEA03':;

SECTION_NUMBER 1
 '@T6G_MB_LIB.T6G(SCH_1):PAGE173_I83@PURE_QUANTA.Q_CAP(CHIPS)':
 C_PATH='@t6g_mb_lib.t6g(sch_1):page173_i83@pure_quanta.q_cap(chips)',
 P_PATH='@t6g_mb_lib.t6g(sch_1):page198_i83@pure_quanta.q_cap(chips)',
 PATH='I83',
 DRAWING='@T6G_MB_LIB.T6G(SCH_1):PAGE173',
 TOLERANCE='20%',
 MATERIAL='X6S',
 PHYS_PAGE='198',
 XY='(-675,4900)',
 ROT='0',
 VER='1',
 PACK_TYPE='C0805',
 LOCATION='PC604_1',
 CDS_LIB='pure_quanta',
 CDS_PART_NAME='Q_CAP_C0805-22UF,4V,20%,X6S,CH622KMEA03',
 VOLTAGE='4V',
 PART_NUMBER='CH622KMEA03',
 VALUE='22UF',
 PRIM_FILE='./archive_libs/logical/q_cap/chips/chips.prt';

PART_NAME
 PC605_9 'Q_CAP_0402-0.1UF,25V,10%,X7R,CH4104K1B00':;

SECTION_NUMBER 1
 '@T6G_MB_LIB.T6G(SCH_1):PAGE174_I2@PURE_QUANTA.Q_CAP(CHIPS)':
 C_PATH='@t6g_mb_lib.t6g(sch_1):page174_i2@pure_quanta.q_cap(chips)',
 P_PATH='@t6g_mb_lib.t6g(sch_1):page199_i2@pure_quanta.q_cap(chips)',
 PATH='I2',
 DRAWING='@T6G_MB_LIB.T6G(SCH_1):PAGE174',
 TOLERANCE='10%',
 MATERIAL='X7R',
 PHYS_PAGE='199',
 XY='(-7550,3950)',
 ROT='0',
 VER='1',
 PACK_TYPE='0402',
 LOCATION='PC605_9',
 CDS_LIB='pure_quanta',
 CDS_PART_NAME='Q_CAP_0402-0.1UF,25V,10%,X7R,CH4104K1B00',
 VOLTAGE='25V',
 PART_NUMBER='CH4104K1B00',
 VALUE='0.1UF',
 PRIM_FILE='./archive_libs/logical/q_cap/chips/chips.prt';

PART_NAME
 PC606 'Q_CAP_C0402-2.2UF,10V,10%,X6S,CH5222KEB01':;

SECTION_NUMBER 1
 '@T6G_MB_LIB.T6G(SCH_1):PAGE174_I14@PURE_QUANTA.Q_CAP(CHIPS)':
 C_PATH='@t6g_mb_lib.t6g(sch_1):page174_i14@pure_quanta.q_cap(chips)',
 P_PATH='@t6g_mb_lib.t6g(sch_1):page199_i14@pure_quanta.q_cap(chips)',
 PATH='I14',
 DRAWING='@T6G_MB_LIB.T6G(SCH_1):PAGE174',
 TOLERANCE='10%',
 MATERIAL='X6S',
 PHYS_PAGE='199',
 XY='(-7225,4575)',
 ROT='0',
 VER='1',
 PACK_TYPE='C0402',
 LOCATION='PC606',
 CDS_LIB='pure_quanta',
 CDS_PART_NAME='Q_CAP_C0402-2.2UF,10V,10%,X6S,CH5222KEB01',
 VOLTAGE='10V',
 PART_NUMBER='CH5222KEB01',
 VALUE='2.2UF',
 PRIM_FILE='./archive_libs/logical/q_cap/chips/chips.prt';

PART_NAME
 PC607_SOP0_3 'Q_CAP_C0402-2.2UF,10V,10%,X6S,CH5222KEB01':;

SECTION_NUMBER 1
 '@T6G_MB_LIB.T6G(SCH_1):PAGE174_I19@PURE_QUANTA.Q_CAP(CHIPS)':
 C_PATH='@t6g_mb_lib.t6g(sch_1):page174_i19@pure_quanta.q_cap(chips)',
 P_PATH='@t6g_mb_lib.t6g(sch_1):page199_i19@pure_quanta.q_cap(chips)',
 PATH='I19',
 DRAWING='@T6G_MB_LIB.T6G(SCH_1):PAGE174',
 TOLERANCE='10%',
 MATERIAL='X6S',
 PHYS_PAGE='199',
 XY='(-6875,5050)',
 ROT='0',
 VER='1',
 PACK_TYPE='C0402',
 LOCATION='PC607_SOP0_3',
 CDS_LIB='pure_quanta',
 CDS_PART_NAME='Q_CAP_C0402-2.2UF,10V,10%,X6S,CH5222KEB01',
 VOLTAGE='10V',
 PART_NUMBER='CH5222KEB01',
 VALUE='2.2UF',
 PRIM_FILE='./archive_libs/logical/q_cap/chips/chips.prt';

PART_NAME
 PC608_3 'Q_CAP_C0402-1UF,25V,10%,X6S,CH5104KEB02':;

SECTION_NUMBER 1
 '@T6G_MB_LIB.T6G(SCH_1):PAGE174_I21@PURE_QUANTA.Q_CAP(CHIPS)':
 C_PATH='@t6g_mb_lib.t6g(sch_1):page174_i21@pure_quanta.q_cap(chips)',
 P_PATH='@t6g_mb_lib.t6g(sch_1):page199_i21@pure_quanta.q_cap(chips)',
 PATH='I21',
 DRAWING='@T6G_MB_LIB.T6G(SCH_1):PAGE174',
 TOLERANCE='10%',
 MATERIAL='X6S',
 PHYS_PAGE='199',
 XY='(-4525,5100)',
 ROT='0',
 VER='1',
 PACK_TYPE='C0402',
 LOCATION='PC608_3',
 CDS_LIB='pure_quanta',
 CDS_PART_NAME='Q_CAP_C0402-1UF,25V,10%,X6S,CH5104KEB02',
 VOLTAGE='25V',
 PART_NUMBER='CH5104KEB02',
 VALUE='1UF',
 PRIM_FILE='./archive_libs/logical/q_cap/chips/chips.prt';

PART_NAME
 PC609_3 'Q_CAP_0402-0.1UF,25V,10%,X7R,CH4104K1B00':;

SECTION_NUMBER 1
 '@T6G_MB_LIB.T6G(SCH_1):PAGE174_I37@PURE_QUANTA.Q_CAP(CHIPS)':
 C_PATH='@t6g_mb_lib.t6g(sch_1):page174_i37@pure_quanta.q_cap(chips)',
 P_PATH='@t6g_mb_lib.t6g(sch_1):page199_i37@pure_quanta.q_cap(chips)',
 PATH='I37',
 DRAWING='@T6G_MB_LIB.T6G(SCH_1):PAGE174',
 TOLERANCE='10%',
 MATERIAL='X7R',
 PHYS_PAGE='199',
 XY='(-4925,5100)',
 ROT='0',
 VER='1',
 PACK_TYPE='0402',
 LOCATION='PC609_3',
 CDS_LIB='pure_quanta',
 CDS_PART_NAME='Q_CAP_0402-0.1UF,25V,10%,X7R,CH4104K1B00',
 VOLTAGE='25V',
 PART_NUMBER='CH4104K1B00',
 VALUE='0.1UF',
 PRIM_FILE='./archive_libs/logical/q_cap/chips/chips.prt';

PART_NAME
 PC610_3 'Q_CAP_C0805-22UF,16V,20%,X6S,CH6223MEA01':;

SECTION_NUMBER 1
 '@T6G_MB_LIB.T6G(SCH_1):PAGE174_I22@PURE_QUANTA.Q_CAP(CHIPS)':
 C_PATH='@t6g_mb_lib.t6g(sch_1):page174_i22@pure_quanta.q_cap(chips)',
 P_PATH='@t6g_mb_lib.t6g(sch_1):page199_i22@pure_quanta.q_cap(chips)',
 PATH='I22',
 DRAWING='@T6G_MB_LIB.T6G(SCH_1):PAGE174',
 TOLERANCE='20%',
 MATERIAL='X6S',
 PHYS_PAGE='199',
 XY='(-4200,5100)',
 ROT='0',
 VER='1',
 PACK_TYPE='C0805',
 LOCATION='PC610_3',
 CDS_LIB='pure_quanta',
 CDS_PART_NAME='Q_CAP_C0805-22UF,16V,20%,X6S,CH6223MEA01',
 VOLTAGE='16V',
 PART_NUMBER='CH6223MEA01',
 VALUE='22UF',
 PRIM_FILE='./archive_libs/logical/q_cap/chips/chips.prt';

PART_NAME
 PC611_3 'Q_CAP_C0805-22UF,16V,20%,X6S,CH6223MEA01':;

SECTION_NUMBER 1
 '@T6G_MB_LIB.T6G(SCH_1):PAGE174_I31@PURE_QUANTA.Q_CAP(CHIPS)':
 C_PATH='@t6g_mb_lib.t6g(sch_1):page174_i31@pure_quanta.q_cap(chips)',
 P_PATH='@t6g_mb_lib.t6g(sch_1):page199_i31@pure_quanta.q_cap(chips)',
 PATH='I31',
 DRAWING='@T6G_MB_LIB.T6G(SCH_1):PAGE174',
 TOLERANCE='20%',
 MATERIAL='X6S',
 PHYS_PAGE='199',
 XY='(-3875,5100)',
 ROT='0',
 VER='1',
 PACK_TYPE='C0805',
 LOCATION='PC611_3',
 CDS_LIB='pure_quanta',
 CDS_PART_NAME='Q_CAP_C0805-22UF,16V,20%,X6S,CH6223MEA01',
 VOLTAGE='16V',
 PART_NUMBER='CH6223MEA01',
 VALUE='22UF',
 PRIM_FILE='./archive_libs/logical/q_cap/chips/chips.prt';

PART_NAME
 PC612 'Q_CAP_0402-0.22UF,16V,10%,X7R,CH4223K1B00':;

SECTION_NUMBER 1
 '@T6G_MB_LIB.T6G(SCH_1):PAGE174_I30@PURE_QUANTA.Q_CAP(CHIPS)':
 C_PATH='@t6g_mb_lib.t6g(sch_1):page174_i30@pure_quanta.q_cap(chips)',
 P_PATH='@t6g_mb_lib.t6g(sch_1):page199_i30@pure_quanta.q_cap(chips)',
 PATH='I30',
 DRAWING='@T6G_MB_LIB.T6G(SCH_1):PAGE174',
 TOLERANCE='10%',
 MATERIAL='X7R',
 PHYS_PAGE='199',
 XY='(-3600,4450)',
 ROT='0',
 VER='1',
 PACK_TYPE='0402',
 LOCATION='PC612',
 CDS_LIB='pure_quanta',
 CDS_PART_NAME='Q_CAP_0402-0.22UF,16V,10%,X7R,CH4223K1B00',
 VOLTAGE='16V',
 PART_NUMBER='CH4223K1B00',
 VALUE='0.22UF',
 PRIM_FILE='./archive_libs/logical/q_cap/chips/chips.prt';

PART_NAME
 PC612_3 'Q_CAP_C0805-22UF,16V,20%,X6S,CH6223MEA01':;

SECTION_NUMBER 1
 '@T6G_MB_LIB.T6G(SCH_1):PAGE174_I34@PURE_QUANTA.Q_CAP(CHIPS)':
 C_PATH='@t6g_mb_lib.t6g(sch_1):page174_i34@pure_quanta.q_cap(chips)',
 P_PATH='@t6g_mb_lib.t6g(sch_1):page199_i34@pure_quanta.q_cap(chips)',
 PATH='I34',
 DRAWING='@T6G_MB_LIB.T6G(SCH_1):PAGE174',
 TOLERANCE='20%',
 MATERIAL='X6S',
 PHYS_PAGE='199',
 XY='(-3225,5100)',
 ROT='0',
 VER='1',
 PACK_TYPE='C0805',
 LOCATION='PC612_3',
 CDS_LIB='pure_quanta',
 CDS_PART_NAME='Q_CAP_C0805-22UF,16V,20%,X6S,CH6223MEA01',
 VOLTAGE='16V',
 PART_NUMBER='CH6223MEA01',
 VALUE='22UF',
 PRIM_FILE='./archive_libs/logical/q_cap/chips/chips.prt';

PART_NAME
 PC613_3 'Q_CAP_C0805-22UF,16V,20%,X6S,CH6223MEA01':;

SECTION_NUMBER 1
 '@T6G_MB_LIB.T6G(SCH_1):PAGE174_I32@PURE_QUANTA.Q_CAP(CHIPS)':
 C_PATH='@t6g_mb_lib.t6g(sch_1):page174_i32@pure_quanta.q_cap(chips)',
 P_PATH='@t6g_mb_lib.t6g(sch_1):page199_i32@pure_quanta.q_cap(chips)',
 PATH='I32',
 DRAWING='@T6G_MB_LIB.T6G(SCH_1):PAGE174',
 TOLERANCE='20%',
 MATERIAL='X6S',
 PHYS_PAGE='199',
 XY='(-3575,5100)',
 ROT='0',
 VER='1',
 PACK_TYPE='C0805',
 LOCATION='PC613_3',
 CDS_LIB='pure_quanta',
 CDS_PART_NAME='Q_CAP_C0805-22UF,16V,20%,X6S,CH6223MEA01',
 VOLTAGE='16V',
 PART_NUMBER='CH6223MEA01',
 VALUE='22UF',
 PRIM_FILE='./archive_libs/logical/q_cap/chips/chips.prt';

PART_NAME
 PC614_3 'Q_CAP_C0805-22UF,4V,20%,X6S,CH622KMEA03':;

SECTION_NUMBER 1
 '@T6G_MB_LIB.T6G(SCH_1):PAGE174_I27@PURE_QUANTA.Q_CAP(CHIPS)':
 C_PATH='@t6g_mb_lib.t6g(sch_1):page174_i27@pure_quanta.q_cap(chips)',
 P_PATH='@t6g_mb_lib.t6g(sch_1):page199_i27@pure_quanta.q_cap(chips)',
 PATH='I27',
 DRAWING='@T6G_MB_LIB.T6G(SCH_1):PAGE174',
 TOLERANCE='20%',
 MATERIAL='X6S',
 PHYS_PAGE='199',
 XY='(-1650,4050)',
 ROT='0',
 VER='1',
 PACK_TYPE='C0805',
 LOCATION='PC614_3',
 CDS_LIB='pure_quanta',
 CDS_PART_NAME='Q_CAP_C0805-22UF,4V,20%,X6S,CH622KMEA03',
 VOLTAGE='4V',
 PART_NUMBER='CH622KMEA03',
 VALUE='22UF',
 PRIM_FILE='./archive_libs/logical/q_cap/chips/chips.prt';

PART_NAME
 PC615_3 'Q_CAP_C0805-22UF,4V,20%,X6S,CH622KMEA03':;

SECTION_NUMBER 1
 '@T6G_MB_LIB.T6G(SCH_1):PAGE174_I29@PURE_QUANTA.Q_CAP(CHIPS)':
 C_PATH='@t6g_mb_lib.t6g(sch_1):page174_i29@pure_quanta.q_cap(chips)',
 P_PATH='@t6g_mb_lib.t6g(sch_1):page199_i29@pure_quanta.q_cap(chips)',
 PATH='I29',
 DRAWING='@T6G_MB_LIB.T6G(SCH_1):PAGE174',
 TOLERANCE='20%',
 MATERIAL='X6S',
 PHYS_PAGE='199',
 XY='(-1225,4050)',
 ROT='0',
 VER='1',
 PACK_TYPE='C0805',
 LOCATION='PC615_3',
 CDS_LIB='pure_quanta',
 CDS_PART_NAME='Q_CAP_C0805-22UF,4V,20%,X6S,CH622KMEA03',
 VOLTAGE='4V',
 PART_NUMBER='CH622KMEA03',
 VALUE='22UF',
 PRIM_FILE='./archive_libs/logical/q_cap/chips/chips.prt';

PART_NAME
 PC616 'Q_CAP_C0402-2.2UF,10V,10%,X6S,CH5222KEB01':;

SECTION_NUMBER 1
 '@T6G_MB_LIB.T6G(SCH_1):PAGE198_I10@PURE_QUANTA.Q_CAP(CHIPS)':
 C_PATH='@t6g_mb_lib.t6g(sch_1):page198_i10@pure_quanta.q_cap(chips)',
 P_PATH='@t6g_mb_lib.t6g(sch_1):page223_i10@pure_quanta.q_cap(chips)',
 PATH='I10',
 DRAWING='@T6G_MB_LIB.T6G(SCH_1):PAGE198',
 TOLERANCE='10%',
 MATERIAL='X6S',
 PHYS_PAGE='223',
 XY='(-11050,2700)',
 ROT='0',
 VER='1',
 PACK_TYPE='C0402',
 LOCATION='PC616',
 CDS_LIB='pure_quanta',
 CDS_PART_NAME='Q_CAP_C0402-2.2UF,10V,10%,X6S,CH5222KEB01',
 VOLTAGE='10V',
 PART_NUMBER='CH5222KEB01',
 VALUE='2.2UF',
 PRIM_FILE='./archive_libs/logical/q_cap/chips/chips.prt';

PART_NAME
 PC617 'Q_CAP_C0402-2.2UF,10V,10%,X6S,CH5222KEB01':;

SECTION_NUMBER 1
 '@T6G_MB_LIB.T6G(SCH_1):PAGE198_I28@PURE_QUANTA.Q_CAP(CHIPS)':
 C_PATH='@t6g_mb_lib.t6g(sch_1):page198_i28@pure_quanta.q_cap(chips)',
 P_PATH='@t6g_mb_lib.t6g(sch_1):page223_i28@pure_quanta.q_cap(chips)',
 PATH='I28',
 DRAWING='@T6G_MB_LIB.T6G(SCH_1):PAGE198',
 TOLERANCE='10%',
 MATERIAL='X6S',
 PHYS_PAGE='223',
 XY='(-11025,5400)',
 ROT='0',
 VER='1',
 PACK_TYPE='C0402',
 LOCATION='PC617',
 CDS_LIB='pure_quanta',
 CDS_PART_NAME='Q_CAP_C0402-2.2UF,10V,10%,X6S,CH5222KEB01',
 VOLTAGE='10V',
 PART_NUMBER='CH5222KEB01',
 VALUE='2.2UF',
 PRIM_FILE='./archive_libs/logical/q_cap/chips/chips.prt';

PART_NAME
 PC618_IOP1_4 'Q_CAP_C0402-2.2UF,10V,10%,X6S,CH5222KEB01':;

SECTION_NUMBER 1
 '@T6G_MB_LIB.T6G(SCH_1):PAGE198_I13@PURE_QUANTA.Q_CAP(CHIPS)':
 C_PATH='@t6g_mb_lib.t6g(sch_1):page198_i13@pure_quanta.q_cap(chips)',
 P_PATH='@t6g_mb_lib.t6g(sch_1):page223_i13@pure_quanta.q_cap(chips)',
 PATH='I13',
 DRAWING='@T6G_MB_LIB.T6G(SCH_1):PAGE198',
 TOLERANCE='10%',
 MATERIAL='X6S',
 PHYS_PAGE='223',
 XY='(-10700,3275)',
 ROT='0',
 VER='1',
 PACK_TYPE='C0402',
 LOCATION='PC618_IOP1_4',
 CDS_LIB='pure_quanta',
 CDS_PART_NAME='Q_CAP_C0402-2.2UF,10V,10%,X6S,CH5222KEB01',
 VOLTAGE='10V',
 PART_NUMBER='CH5222KEB01',
 VALUE='2.2UF',
 PRIM_FILE='./archive_libs/logical/q_cap/chips/chips.prt';

PART_NAME
 PC619_IOP1_3 'Q_CAP_C0402-2.2UF,10V,10%,X6S,CH5222KEB01':;

SECTION_NUMBER 1
 '@T6G_MB_LIB.T6G(SCH_1):PAGE198_I31@PURE_QUANTA.Q_CAP(CHIPS)':
 C_PATH='@t6g_mb_lib.t6g(sch_1):page198_i31@pure_quanta.q_cap(chips)',
 P_PATH='@t6g_mb_lib.t6g(sch_1):page223_i31@pure_quanta.q_cap(chips)',
 PATH='I31',
 DRAWING='@T6G_MB_LIB.T6G(SCH_1):PAGE198',
 TOLERANCE='10%',
 MATERIAL='X6S',
 PHYS_PAGE='223',
 XY='(-10675,5975)',
 ROT='0',
 VER='1',
 PACK_TYPE='C0402',
 LOCATION='PC619_IOP1_3',
 CDS_LIB='pure_quanta',
 CDS_PART_NAME='Q_CAP_C0402-2.2UF,10V,10%,X6S,CH5222KEB01',
 VOLTAGE='10V',
 PART_NUMBER='CH5222KEB01',
 VALUE='2.2UF',
 PRIM_FILE='./archive_libs/logical/q_cap/chips/chips.prt';

PART_NAME
 PC620_9 'Q_CAP_0402-0.1UF,25V,10%,X7R,CH4104K1B00':;

SECTION_NUMBER 1
 '@T6G_MB_LIB.T6G(SCH_1):PAGE198_I20@PURE_QUANTA.Q_CAP(CHIPS)':
 C_PATH='@t6g_mb_lib.t6g(sch_1):page198_i20@pure_quanta.q_cap(chips)',
 P_PATH='@t6g_mb_lib.t6g(sch_1):page223_i20@pure_quanta.q_cap(chips)',
 PATH='I20',
 DRAWING='@T6G_MB_LIB.T6G(SCH_1):PAGE198',
 TOLERANCE='10%',
 MATERIAL='X7R',
 PHYS_PAGE='223',
 XY='(-11900,4725)',
 ROT='0',
 VER='1',
 PACK_TYPE='0402',
 LOCATION='PC620_9',
 CDS_LIB='pure_quanta',
 CDS_PART_NAME='Q_CAP_0402-0.1UF,25V,10%,X7R,CH4104K1B00',
 VOLTAGE='25V',
 PART_NUMBER='CH4104K1B00',
 VALUE='0.1UF',
 PRIM_FILE='./archive_libs/logical/q_cap/chips/chips.prt';

PART_NAME
 PC621_10 'Q_CAP_0402-0.1UF,25V,10%,X7R,CH4104K1B00':;

SECTION_NUMBER 1
 '@T6G_MB_LIB.T6G(SCH_1):PAGE198_I2@PURE_QUANTA.Q_CAP(CHIPS)':
 C_PATH='@t6g_mb_lib.t6g(sch_1):page198_i2@pure_quanta.q_cap(chips)',
 P_PATH='@t6g_mb_lib.t6g(sch_1):page223_i2@pure_quanta.q_cap(chips)',
 PATH='I2',
 DRAWING='@T6G_MB_LIB.T6G(SCH_1):PAGE198',
 TOLERANCE='10%',
 MATERIAL='X7R',
 PHYS_PAGE='223',
 XY='(-11925,1925)',
 ROT='0',
 VER='1',
 PACK_TYPE='0402',
 LOCATION='PC621_10',
 CDS_LIB='pure_quanta',
 CDS_PART_NAME='Q_CAP_0402-0.1UF,25V,10%,X7R,CH4104K1B00',
 VOLTAGE='25V',
 PART_NUMBER='CH4104K1B00',
 VALUE='0.1UF',
 PRIM_FILE='./archive_libs/logical/q_cap/chips/chips.prt';

PART_NAME
 PC622_3 'Q_CAP_0402-0.1UF,25V,10%,X7R,CH4104K1B00':;

SECTION_NUMBER 1
 '@T6G_MB_LIB.T6G(SCH_1):PAGE198_I35@PURE_QUANTA.Q_CAP(CHIPS)':
 C_PATH='@t6g_mb_lib.t6g(sch_1):page198_i35@pure_quanta.q_cap(chips)',
 P_PATH='@t6g_mb_lib.t6g(sch_1):page223_i35@pure_quanta.q_cap(chips)',
 PATH='I35',
 DRAWING='@T6G_MB_LIB.T6G(SCH_1):PAGE198',
 TOLERANCE='10%',
 MATERIAL='X7R',
 PHYS_PAGE='223',
 XY='(-8500,6050)',
 ROT='0',
 VER='1',
 PACK_TYPE='0402',
 LOCATION='PC622_3',
 CDS_LIB='pure_quanta',
 CDS_PART_NAME='Q_CAP_0402-0.1UF,25V,10%,X7R,CH4104K1B00',
 VOLTAGE='25V',
 PART_NUMBER='CH4104K1B00',
 VALUE='0.1UF',
 PRIM_FILE='./archive_libs/logical/q_cap/chips/chips.prt';

PART_NAME
 PC623_4 'Q_CAP_0402-0.1UF,25V,10%,X7R,CH4104K1B00':;

SECTION_NUMBER 1
 '@T6G_MB_LIB.T6G(SCH_1):PAGE198_I18@PURE_QUANTA.Q_CAP(CHIPS)':
 C_PATH='@t6g_mb_lib.t6g(sch_1):page198_i18@pure_quanta.q_cap(chips)',
 P_PATH='@t6g_mb_lib.t6g(sch_1):page223_i18@pure_quanta.q_cap(chips)',
 PATH='I18',
 DRAWING='@T6G_MB_LIB.T6G(SCH_1):PAGE198',
 TOLERANCE='10%',
 MATERIAL='X7R',
 PHYS_PAGE='223',
 XY='(-8475,3275)',
 ROT='0',
 VER='1',
 PACK_TYPE='0402',
 LOCATION='PC623_4',
 CDS_LIB='pure_quanta',
 CDS_PART_NAME='Q_CAP_0402-0.1UF,25V,10%,X7R,CH4104K1B00',
 VOLTAGE='25V',
 PART_NUMBER='CH4104K1B00',
 VALUE='0.1UF',
 PRIM_FILE='./archive_libs/logical/q_cap/chips/chips.prt';

PART_NAME
 PC624_3 'Q_CAP_C0402-1UF,25V,10%,X6S,CH5104KEB02':;

SECTION_NUMBER 1
 '@T6G_MB_LIB.T6G(SCH_1):PAGE198_I36@PURE_QUANTA.Q_CAP(CHIPS)':
 C_PATH='@t6g_mb_lib.t6g(sch_1):page198_i36@pure_quanta.q_cap(chips)',
 P_PATH='@t6g_mb_lib.t6g(sch_1):page223_i36@pure_quanta.q_cap(chips)',
 PATH='I36',
 DRAWING='@T6G_MB_LIB.T6G(SCH_1):PAGE198',
 TOLERANCE='10%',
 MATERIAL='X6S',
 PHYS_PAGE='223',
 XY='(-8075,6050)',
 ROT='0',
 VER='1',
 PACK_TYPE='C0402',
 LOCATION='PC624_3',
 CDS_LIB='pure_quanta',
 CDS_PART_NAME='Q_CAP_C0402-1UF,25V,10%,X6S,CH5104KEB02',
 VOLTAGE='25V',
 PART_NUMBER='CH5104KEB02',
 VALUE='1UF',
 PRIM_FILE='./archive_libs/logical/q_cap/chips/chips.prt';

PART_NAME
 PC625_4 'Q_CAP_C0402-1UF,25V,10%,X6S,CH5104KEB02':;

SECTION_NUMBER 1
 '@T6G_MB_LIB.T6G(SCH_1):PAGE198_I45@PURE_QUANTA.Q_CAP(CHIPS)':
 C_PATH='@t6g_mb_lib.t6g(sch_1):page198_i45@pure_quanta.q_cap(chips)',
 P_PATH='@t6g_mb_lib.t6g(sch_1):page223_i45@pure_quanta.q_cap(chips)',
 PATH='I45',
 DRAWING='@T6G_MB_LIB.T6G(SCH_1):PAGE198',
 TOLERANCE='10%',
 MATERIAL='X6S',
 PHYS_PAGE='223',
 XY='(-8000,3250)',
 ROT='0',
 VER='1',
 PACK_TYPE='C0402',
 LOCATION='PC625_4',
 CDS_LIB='pure_quanta',
 CDS_PART_NAME='Q_CAP_C0402-1UF,25V,10%,X6S,CH5104KEB02',
 VOLTAGE='25V',
 PART_NUMBER='CH5104KEB02',
 VALUE='1UF',
 PRIM_FILE='./archive_libs/logical/q_cap/chips/chips.prt';

PART_NAME
 PC626_3 'Q_CAP_C0805-22UF,16V,20%,X6S,CH6223MEA01':;

SECTION_NUMBER 1
 '@T6G_MB_LIB.T6G(SCH_1):PAGE198_I60@PURE_QUANTA.Q_CAP(CHIPS)':
 C_PATH='@t6g_mb_lib.t6g(sch_1):page198_i60@pure_quanta.q_cap(chips)',
 P_PATH='@t6g_mb_lib.t6g(sch_1):page223_i60@pure_quanta.q_cap(chips)',
 PATH='I60',
 DRAWING='@T6G_MB_LIB.T6G(SCH_1):PAGE198',
 TOLERANCE='20%',
 MATERIAL='X6S',
 PHYS_PAGE='223',
 XY='(-7675,6050)',
 ROT='0',
 VER='1',
 PACK_TYPE='C0805',
 LOCATION='PC626_3',
 CDS_LIB='pure_quanta',
 CDS_PART_NAME='Q_CAP_C0805-22UF,16V,20%,X6S,CH6223MEA01',
 VOLTAGE='16V',
 PART_NUMBER='CH6223MEA01',
 VALUE='22UF',
 PRIM_FILE='./archive_libs/logical/q_cap/chips/chips.prt';

PART_NAME
 PC627_4 'Q_CAP_C0805-22UF,16V,20%,X6S,CH6223MEA01':;

SECTION_NUMBER 1
 '@T6G_MB_LIB.T6G(SCH_1):PAGE198_I72@PURE_QUANTA.Q_CAP(CHIPS)':
 C_PATH='@t6g_mb_lib.t6g(sch_1):page198_i72@pure_quanta.q_cap(chips)',
 P_PATH='@t6g_mb_lib.t6g(sch_1):page223_i72@pure_quanta.q_cap(chips)',
 PATH='I72',
 DRAWING='@T6G_MB_LIB.T6G(SCH_1):PAGE198',
 TOLERANCE='20%',
 MATERIAL='X6S',
 PHYS_PAGE='223',
 XY='(-7600,3250)',
 ROT='0',
 VER='1',
 PACK_TYPE='C0805',
 LOCATION='PC627_4',
 CDS_LIB='pure_quanta',
 CDS_PART_NAME='Q_CAP_C0805-22UF,16V,20%,X6S,CH6223MEA01',
 VOLTAGE='16V',
 PART_NUMBER='CH6223MEA01',
 VALUE='22UF',
 PRIM_FILE='./archive_libs/logical/q_cap/chips/chips.prt';

PART_NAME
 PC628_3 'Q_CAP_C0805-22UF,16V,20%,X6S,CH6223MEA01':;

SECTION_NUMBER 1
 '@T6G_MB_LIB.T6G(SCH_1):PAGE198_I61@PURE_QUANTA.Q_CAP(CHIPS)':
 C_PATH='@t6g_mb_lib.t6g(sch_1):page198_i61@pure_quanta.q_cap(chips)',
 P_PATH='@t6g_mb_lib.t6g(sch_1):page223_i61@pure_quanta.q_cap(chips)',
 PATH='I61',
 DRAWING='@T6G_MB_LIB.T6G(SCH_1):PAGE198',
 TOLERANCE='20%',
 MATERIAL='X6S',
 PHYS_PAGE='223',
 XY='(-7275,6050)',
 ROT='0',
 VER='1',
 PACK_TYPE='C0805',
 LOCATION='PC628_3',
 CDS_LIB='pure_quanta',
 CDS_PART_NAME='Q_CAP_C0805-22UF,16V,20%,X6S,CH6223MEA01',
 VOLTAGE='16V',
 PART_NUMBER='CH6223MEA01',
 VALUE='22UF',
 PRIM_FILE='./archive_libs/logical/q_cap/chips/chips.prt';

PART_NAME
 PC629_4 'Q_CAP_C0805-22UF,16V,20%,X6S,CH6223MEA01':;

SECTION_NUMBER 1
 '@T6G_MB_LIB.T6G(SCH_1):PAGE198_I46@PURE_QUANTA.Q_CAP(CHIPS)':
 C_PATH='@t6g_mb_lib.t6g(sch_1):page198_i46@pure_quanta.q_cap(chips)',
 P_PATH='@t6g_mb_lib.t6g(sch_1):page223_i46@pure_quanta.q_cap(chips)',
 PATH='I46',
 DRAWING='@T6G_MB_LIB.T6G(SCH_1):PAGE198',
 TOLERANCE='20%',
 MATERIAL='X6S',
 PHYS_PAGE='223',
 XY='(-7200,3250)',
 ROT='0',
 VER='1',
 PACK_TYPE='C0805',
 LOCATION='PC629_4',
 CDS_LIB='pure_quanta',
 CDS_PART_NAME='Q_CAP_C0805-22UF,16V,20%,X6S,CH6223MEA01',
 VOLTAGE='16V',
 PART_NUMBER='CH6223MEA01',
 VALUE='22UF',
 PRIM_FILE='./archive_libs/logical/q_cap/chips/chips.prt';

PART_NAME
 PC630 'Q_CAP_0402-0.22UF,16V,10%,X7R,CH4223K1B00':;

SECTION_NUMBER 1
 '@T6G_MB_LIB.T6G(SCH_1):PAGE198_I44@PURE_QUANTA.Q_CAP(CHIPS)':
 C_PATH='@t6g_mb_lib.t6g(sch_1):page198_i44@pure_quanta.q_cap(chips)',
 P_PATH='@t6g_mb_lib.t6g(sch_1):page223_i44@pure_quanta.q_cap(chips)',
 PATH='I44',
 DRAWING='@T6G_MB_LIB.T6G(SCH_1):PAGE198',
 TOLERANCE='10%',
 MATERIAL='X7R',
 PHYS_PAGE='223',
 XY='(-7025,2525)',
 ROT='0',
 VER='1',
 PACK_TYPE='0402',
 LOCATION='PC630',
 CDS_LIB='pure_quanta',
 CDS_PART_NAME='Q_CAP_0402-0.22UF,16V,10%,X7R,CH4223K1B00',
 VOLTAGE='16V',
 PART_NUMBER='CH4223K1B00',
 VALUE='0.22UF',
 PRIM_FILE='./archive_libs/logical/q_cap/chips/chips.prt';

PART_NAME
 PC631 'Q_CAP_0402-0.22UF,16V,10%,X7R,CH4223K1B00':;

SECTION_NUMBER 1
 '@T6G_MB_LIB.T6G(SCH_1):PAGE198_I63@PURE_QUANTA.Q_CAP(CHIPS)':
 C_PATH='@t6g_mb_lib.t6g(sch_1):page198_i63@pure_quanta.q_cap(chips)',
 P_PATH='@t6g_mb_lib.t6g(sch_1):page223_i63@pure_quanta.q_cap(chips)',
 PATH='I63',
 DRAWING='@T6G_MB_LIB.T6G(SCH_1):PAGE198',
 TOLERANCE='10%',
 MATERIAL='X7R',
 PHYS_PAGE='223',
 XY='(-6950,5325)',
 ROT='0',
 VER='1',
 PACK_TYPE='0402',
 LOCATION='PC631',
 CDS_LIB='pure_quanta',
 CDS_PART_NAME='Q_CAP_0402-0.22UF,16V,10%,X7R,CH4223K1B00',
 VOLTAGE='16V',
 PART_NUMBER='CH4223K1B00',
 VALUE='0.22UF',
 PRIM_FILE='./archive_libs/logical/q_cap/chips/chips.prt';

PART_NAME
 PC632_3 'Q_CAP_C0805-22UF,16V,20%,X6S,CH6223MEA01':;

SECTION_NUMBER 1
 '@T6G_MB_LIB.T6G(SCH_1):PAGE198_I65@PURE_QUANTA.Q_CAP(CHIPS)':
 C_PATH='@t6g_mb_lib.t6g(sch_1):page198_i65@pure_quanta.q_cap(chips)',
 P_PATH='@t6g_mb_lib.t6g(sch_1):page223_i65@pure_quanta.q_cap(chips)',
 PATH='I65',
 DRAWING='@T6G_MB_LIB.T6G(SCH_1):PAGE198',
 TOLERANCE='20%',
 MATERIAL='X6S',
 PHYS_PAGE='223',
 XY='(-6850,6075)',
 ROT='0',
 VER='1',
 PACK_TYPE='C0805',
 LOCATION='PC632_3',
 CDS_LIB='pure_quanta',
 CDS_PART_NAME='Q_CAP_C0805-22UF,16V,20%,X6S,CH6223MEA01',
 VOLTAGE='16V',
 PART_NUMBER='CH6223MEA01',
 VALUE='22UF',
 PRIM_FILE='./archive_libs/logical/q_cap/chips/chips.prt';

PART_NAME
 PC633_4 'Q_CAP_C0805-22UF,16V,20%,X6S,CH6223MEA01':;

SECTION_NUMBER 1
 '@T6G_MB_LIB.T6G(SCH_1):PAGE198_I48@PURE_QUANTA.Q_CAP(CHIPS)':
 C_PATH='@t6g_mb_lib.t6g(sch_1):page198_i48@pure_quanta.q_cap(chips)',
 P_PATH='@t6g_mb_lib.t6g(sch_1):page223_i48@pure_quanta.q_cap(chips)',
 PATH='I48',
 DRAWING='@T6G_MB_LIB.T6G(SCH_1):PAGE198',
 TOLERANCE='20%',
 MATERIAL='X6S',
 PHYS_PAGE='223',
 XY='(-6725,3250)',
 ROT='0',
 VER='1',
 PACK_TYPE='C0805',
 LOCATION='PC633_4',
 CDS_LIB='pure_quanta',
 CDS_PART_NAME='Q_CAP_C0805-22UF,16V,20%,X6S,CH6223MEA01',
 VOLTAGE='16V',
 PART_NUMBER='CH6223MEA01',
 VALUE='22UF',
 PRIM_FILE='./archive_libs/logical/q_cap/chips/chips.prt';

PART_NAME
 PC634_4 'Q_CAP_C0805-22UF,4V,20%,X6S,CH622KMEA03':;

SECTION_NUMBER 1
 '@T6G_MB_LIB.T6G(SCH_1):PAGE198_I51@PURE_QUANTA.Q_CAP(CHIPS)':
 C_PATH='@t6g_mb_lib.t6g(sch_1):page198_i51@pure_quanta.q_cap(chips)',
 P_PATH='@t6g_mb_lib.t6g(sch_1):page223_i51@pure_quanta.q_cap(chips)',
 PATH='I51',
 DRAWING='@T6G_MB_LIB.T6G(SCH_1):PAGE198',
 TOLERANCE='20%',
 MATERIAL='X6S',
 PHYS_PAGE='223',
 XY='(-4475,2100)',
 ROT='0',
 VER='1',
 PACK_TYPE='C0805',
 LOCATION='PC634_4',
 CDS_LIB='pure_quanta',
 CDS_PART_NAME='Q_CAP_C0805-22UF,4V,20%,X6S,CH622KMEA03',
 VOLTAGE='4V',
 PART_NUMBER='CH622KMEA03',
 VALUE='22UF',
 PRIM_FILE='./archive_libs/logical/q_cap/chips/chips.prt';

PART_NAME
 PC635_3 'Q_CAP_C0805-22UF,4V,20%,X6S,CH622KMEA03':;

SECTION_NUMBER 1
 '@T6G_MB_LIB.T6G(SCH_1):PAGE198_I68@PURE_QUANTA.Q_CAP(CHIPS)':
 C_PATH='@t6g_mb_lib.t6g(sch_1):page198_i68@pure_quanta.q_cap(chips)',
 P_PATH='@t6g_mb_lib.t6g(sch_1):page223_i68@pure_quanta.q_cap(chips)',
 PATH='I68',
 DRAWING='@T6G_MB_LIB.T6G(SCH_1):PAGE198',
 TOLERANCE='20%',
 MATERIAL='X6S',
 PHYS_PAGE='223',
 XY='(-4150,4900)',
 ROT='0',
 VER='1',
 PACK_TYPE='C0805',
 LOCATION='PC635_3',
 CDS_LIB='pure_quanta',
 CDS_PART_NAME='Q_CAP_C0805-22UF,4V,20%,X6S,CH622KMEA03',
 VOLTAGE='4V',
 PART_NUMBER='CH622KMEA03',
 VALUE='22UF',
 PRIM_FILE='./archive_libs/logical/q_cap/chips/chips.prt';

PART_NAME
 PC636_4 'Q_CAP_C0805-22UF,4V,20%,X6S,CH622KMEA03':;

SECTION_NUMBER 1
 '@T6G_MB_LIB.T6G(SCH_1):PAGE198_I53@PURE_QUANTA.Q_CAP(CHIPS)':
 C_PATH='@t6g_mb_lib.t6g(sch_1):page198_i53@pure_quanta.q_cap(chips)',
 P_PATH='@t6g_mb_lib.t6g(sch_1):page223_i53@pure_quanta.q_cap(chips)',
 PATH='I53',
 DRAWING='@T6G_MB_LIB.T6G(SCH_1):PAGE198',
 TOLERANCE='20%',
 MATERIAL='X6S',
 PHYS_PAGE='223',
 XY='(-4050,2100)',
 ROT='0',
 VER='1',
 PACK_TYPE='C0805',
 LOCATION='PC636_4',
 CDS_LIB='pure_quanta',
 CDS_PART_NAME='Q_CAP_C0805-22UF,4V,20%,X6S,CH622KMEA03',
 VOLTAGE='4V',
 PART_NUMBER='CH622KMEA03',
 VALUE='22UF',
 PRIM_FILE='./archive_libs/logical/q_cap/chips/chips.prt';

PART_NAME
 PC637_3 'Q_CAP_C0805-22UF,4V,20%,X6S,CH622KMEA03':;

SECTION_NUMBER 1
 '@T6G_MB_LIB.T6G(SCH_1):PAGE198_I70@PURE_QUANTA.Q_CAP(CHIPS)':
 C_PATH='@t6g_mb_lib.t6g(sch_1):page198_i70@pure_quanta.q_cap(chips)',
 P_PATH='@t6g_mb_lib.t6g(sch_1):page223_i70@pure_quanta.q_cap(chips)',
 PATH='I70',
 DRAWING='@T6G_MB_LIB.T6G(SCH_1):PAGE198',
 TOLERANCE='20%',
 MATERIAL='X6S',
 PHYS_PAGE='223',
 XY='(-3725,4900)',
 ROT='0',
 VER='1',
 PACK_TYPE='C0805',
 LOCATION='PC637_3',
 CDS_LIB='pure_quanta',
 CDS_PART_NAME='Q_CAP_C0805-22UF,4V,20%,X6S,CH622KMEA03',
 VOLTAGE='4V',
 PART_NUMBER='CH622KMEA03',
 VALUE='22UF',
 PRIM_FILE='./archive_libs/logical/q_cap/chips/chips.prt';

PART_NAME
 PC638 'Q_CAP_0402-0.1UF,25V,10%,X7R,CH4104K1B00':;

SECTION_NUMBER 1
 '@T6G_MB_LIB.T6G(SCH_1):PAGE199_I4@PURE_QUANTA.Q_CAP(CHIPS)':
 C_PATH='@t6g_mb_lib.t6g(sch_1):page199_i4@pure_quanta.q_cap(chips)',
 P_PATH='@t6g_mb_lib.t6g(sch_1):page224_i4@pure_quanta.q_cap(chips)',
 PATH='I4',
 DRAWING='@T6G_MB_LIB.T6G(SCH_1):PAGE199',
 TOLERANCE='10%',
 MATERIAL='X7R',
 PHYS_PAGE='224',
 XY='(-6950,675)',
 ROT='0',
 VER='1',
 PACK_TYPE='0402',
 LOCATION='PC638',
 CDS_LIB='pure_quanta',
 CDS_PART_NAME='Q_CAP_0402-0.1UF,25V,10%,X7R,CH4104K1B00',
 VOLTAGE='25V',
 PART_NUMBER='CH4104K1B00',
 VALUE='0.1UF',
 PRIM_FILE='./archive_libs/logical/q_cap/chips/chips.prt';

PART_NAME
 PC639 'Q_CAP_0402-3300PF,50V,10%,X7R,TMP_QCH2336K1B12':;

SECTION_NUMBER 1
 '@T6G_MB_LIB.T6G(SCH_1):PAGE199_I28@PURE_QUANTA.Q_CAP(CHIPS)':
 C_PATH='@t6g_mb_lib.t6g(sch_1):page199_i28@pure_quanta.q_cap(chips)',
 P_PATH='@t6g_mb_lib.t6g(sch_1):page224_i28@pure_quanta.q_cap(chips)',
 PATH='I28',
 DRAWING='@T6G_MB_LIB.T6G(SCH_1):PAGE199',
 TOLERANCE='10%',
 MATERIAL='X7R',
 PHYS_PAGE='224',
 XY='(-5750,3950)',
 ROT='0',
 VER='1',
 PACK_TYPE='0402',
 LOCATION='PC639',
 CDS_LIB='pure_quanta',
 CDS_PART_NAME='Q_CAP_0402-3300PF,50V,10%,X7R,TMP_QCH2336K1B12',
 VOLTAGE='50V',
 PART_NUMBER='TMP_QCH2336K1B12',
 VALUE='3300PF',
 PRIM_FILE='./archive_libs/logical/q_cap/chips/chips.prt';

PART_NAME
 PC641 'Q_CAP_C0402-0.22UF,25V,10%,X7R,CH4224K1B01':;

SECTION_NUMBER 1
 '@T6G_MB_LIB.T6G(SCH_1):PAGE315_I30@PURE_QUANTA.Q_CAP(CHIPS)':
 C_PATH='@t6g_mb_lib.t6g(sch_1):page315_i30@pure_quanta.q_cap(chips)',
 P_PATH='@t6g_mb_lib.t6g(sch_1):page269_i30@pure_quanta.q_cap(chips)',
 PATH='I30',
 DRAWING='@T6G_MB_LIB.T6G(SCH_1):PAGE315',
 TOLERANCE='10%',
 MATERIAL='X7R',
 PHYS_PAGE='269',
 XY='(350,2200)',
 ROT='0',
 VER='1',
 PACK_TYPE='C0402',
 LOCATION='PC641',
 CDS_LIB='pure_quanta',
 CDS_PART_NAME='Q_CAP_C0402-0.22UF,25V,10%,X7R,CH4224K1B01',
 VOLTAGE='25V',
 PART_NUMBER='CH4224K1B01',
 VALUE='0.22UF',
 PRIM_FILE='./archive_libs/logical/q_cap/chips/chips.prt';

PART_NAME
 PC643 'Q_CAP_0402-470PF,50V,10%,X7R,TMP_QCH14706KB18':;

SECTION_NUMBER 1
 '@T6G_MB_LIB.T6G(SCH_1):PAGE199_I49@PURE_QUANTA.Q_CAP(CHIPS)':
 C_PATH='@t6g_mb_lib.t6g(sch_1):page199_i49@pure_quanta.q_cap(chips)',
 P_PATH='@t6g_mb_lib.t6g(sch_1):page224_i49@pure_quanta.q_cap(chips)',
 PATH='I49',
 DRAWING='@T6G_MB_LIB.T6G(SCH_1):PAGE199',
 TOLERANCE='10%',
 MATERIAL='X7R',
 PHYS_PAGE='224',
 XY='(-3450,725)',
 ROT='0',
 VER='1',
 PACK_TYPE='0402',
 LOCATION='PC643',
 CDS_LIB='pure_quanta',
 CDS_PART_NAME='Q_CAP_0402-470PF,50V,10%,X7R,TMP_QCH14706KB18',
 VOLTAGE='50V',
 PART_NUMBER='TMP_QCH14706KB18',
 VALUE='470PF',
 PRIM_FILE='./archive_libs/logical/q_cap/chips/chips.prt';

PART_NAME
 PC644 'Q_CAP_C0402-10UF,6.3V,20%,X6S,CH6101MEB03':;

SECTION_NUMBER 1
 '@T6G_MB_LIB.T6G(SCH_1):PAGE199_I80@PURE_QUANTA.Q_CAP(CHIPS)':
 C_PATH='@t6g_mb_lib.t6g(sch_1):page199_i80@pure_quanta.q_cap(chips)',
 P_PATH='@t6g_mb_lib.t6g(sch_1):page224_i80@pure_quanta.q_cap(chips)',
 PATH='I80',
 DRAWING='@T6G_MB_LIB.T6G(SCH_1):PAGE199',
 TOLERANCE='20%',
 MATERIAL='X6S',
 PHYS_PAGE='224',
 XY='(-3000,5675)',
 ROT='0',
 VER='1',
 PACK_TYPE='C0402',
 LOCATION='PC644',
 CDS_LIB='pure_quanta',
 CDS_PART_NAME='Q_CAP_C0402-10UF,6.3V,20%,X6S,CH6101MEB03',
 VOLTAGE='6.3V',
 PART_NUMBER='CH6101MEB03',
 VALUE='10UF',
 PRIM_FILE='./archive_libs/logical/q_cap/chips/chips.prt';

PART_NAME
 PC645 'Q_CAP_C0402-1UF,16V,10%,X6S,CH5103KEB01':;

SECTION_NUMBER 1
 '@T6G_MB_LIB.T6G(SCH_1):PAGE199_I81@PURE_QUANTA.Q_CAP(CHIPS)':
 C_PATH='@t6g_mb_lib.t6g(sch_1):page199_i81@pure_quanta.q_cap(chips)',
 P_PATH='@t6g_mb_lib.t6g(sch_1):page224_i81@pure_quanta.q_cap(chips)',
 PATH='I81',
 DRAWING='@T6G_MB_LIB.T6G(SCH_1):PAGE199',
 TOLERANCE='10%',
 MATERIAL='X6S',
 PHYS_PAGE='224',
 XY='(-3000,6150)',
 ROT='0',
 VER='1',
 PACK_TYPE='C0402',
 LOCATION='PC645',
 CDS_LIB='pure_quanta',
 CDS_PART_NAME='Q_CAP_C0402-1UF,16V,10%,X6S,CH5103KEB01',
 VOLTAGE='16V',
 PART_NUMBER='CH5103KEB01',
 VALUE='1UF',
 PRIM_FILE='./archive_libs/logical/q_cap/chips/chips.prt';

PART_NAME
 PC800 'Q_CAPP_SMLF-470UF,2.5V,20%,SPCAP,CH747LM8825':;

SECTION_NUMBER 1
 '@T6G_MB_LIB.T6G(SCH_1):PAGE183_I89@PURE_QUANTA.Q_CAPP(CHIPS)':
 C_PATH='@t6g_mb_lib.t6g(sch_1):page183_i89@pure_quanta.q_capp(chips)',
 P_PATH='@t6g_mb_lib.t6g(sch_1):page208_i89@pure_quanta.q_capp(chips)',
 PATH='I89',
 DRAWING='@T6G_MB_LIB.T6G(SCH_1):PAGE183',
 TOLERANCE='20%',
 MATERIAL='SPCAP',
 PHYS_PAGE='208',
 XY='(-2075,2850)',
 ROT='0',
 VER='1',
 PACK_TYPE='SMLF',
 LOCATION='PC800',
 CDS_LIB='pure_quanta',
 CDS_PART_NAME='Q_CAPP_SMLF-470UF,2.5V,20%,SPCAP,CH747LM8825',
 VOLTAGE='2.5V',
 PART_NUMBER='CH747LM8825',
 VALUE='470UF',
 PRIM_FILE='./archive_libs/logical/q_capp/chips/chips.prt';

PART_NAME
 PC801 'Q_CAPP_SMLF-390UF,2.5V,20%,ALUM,CC7390JMZ13':;

SECTION_NUMBER 1
 '@T6G_MB_LIB.T6G(SCH_1):PAGE183_I70@PURE_QUANTA.Q_CAPP(CHIPS)':
 C_PATH='@t6g_mb_lib.t6g(sch_1):page183_i70@pure_quanta.q_capp(chips)',
 P_PATH='@t6g_mb_lib.t6g(sch_1):page208_i70@pure_quanta.q_capp(chips)',
 PATH='I70',
 DRAWING='@T6G_MB_LIB.T6G(SCH_1):PAGE183',
 TOLERANCE='20%',
 MATERIAL='ALUM',
 PHYS_PAGE='208',
 XY='(-700,2875)',
 ROT='0',
 VER='1',
 PACK_TYPE='SMLF',
 LOCATION='PC801',
 CDS_LIB='pure_quanta',
 CDS_PART_NAME='Q_CAPP_SMLF-390UF,2.5V,20%,ALUM,CC7390JMZ13',
 VOLTAGE='2.5V',
 PART_NUMBER='CC7390JMZ13',
 VALUE='390UF',
 PRIM_FILE='./archive_libs/logical/q_capp/chips/chips.prt';

PART_NAME
 PC802 'Q_CAPP_SMLF-470UF,2.5V,20%,SPCAP,CH747LM8825':;

SECTION_NUMBER 1
 '@T6G_MB_LIB.T6G(SCH_1):PAGE200_I65@PURE_QUANTA.Q_CAPP(CHIPS)':
 C_PATH='@t6g_mb_lib.t6g(sch_1):page200_i65@pure_quanta.q_capp(chips)',
 P_PATH='@t6g_mb_lib.t6g(sch_1):page225_i65@pure_quanta.q_capp(chips)',
 PATH='I65',
 DRAWING='@T6G_MB_LIB.T6G(SCH_1):PAGE200',
 TOLERANCE='20%',
 MATERIAL='SPCAP',
 PHYS_PAGE='225',
 XY='(-2175,2775)',
 ROT='0',
 VER='1',
 PACK_TYPE='SMLF',
 LOCATION='PC802',
 CDS_LIB='pure_quanta',
 CDS_PART_NAME='Q_CAPP_SMLF-470UF,2.5V,20%,SPCAP,CH747LM8825',
 VOLTAGE='2.5V',
 PART_NUMBER='CH747LM8825',
 VALUE='470UF',
 PRIM_FILE='./archive_libs/logical/q_capp/chips/chips.prt';

PART_NAME
 PC803 'Q_CAPP_SMLF-390UF,2.5V,20%,ALUM,CC7390JMZ13':;

SECTION_NUMBER 1
 '@T6G_MB_LIB.T6G(SCH_1):PAGE200_I75@PURE_QUANTA.Q_CAPP(CHIPS)':
 C_PATH='@t6g_mb_lib.t6g(sch_1):page200_i75@pure_quanta.q_capp(chips)',
 P_PATH='@t6g_mb_lib.t6g(sch_1):page225_i75@pure_quanta.q_capp(chips)',
 PATH='I75',
 DRAWING='@T6G_MB_LIB.T6G(SCH_1):PAGE200',
 TOLERANCE='20%',
 MATERIAL='ALUM',
 PHYS_PAGE='225',
 XY='(-800,2800)',
 ROT='0',
 VER='1',
 PACK_TYPE='SMLF',
 LOCATION='PC803',
 CDS_LIB='pure_quanta',
 CDS_PART_NAME='Q_CAPP_SMLF-390UF,2.5V,20%,ALUM,CC7390JMZ13',
 VOLTAGE='2.5V',
 PART_NUMBER='CC7390JMZ13',
 VALUE='390UF',
 PRIM_FILE='./archive_libs/logical/q_capp/chips/chips.prt';

PART_NAME
 PC819 'Q_CAP_0402-0.1UF,25V,10%,X7R,CH4104K1B00':;

SECTION_NUMBER 1
 '@T6G_MB_LIB.T6G(SCH_1):PAGE477_I48@PURE_QUANTA.Q_CAP(CHIPS)':
 C_PATH='@t6g_mb_lib.t6g(sch_1):page477_i48@pure_quanta.q_cap(chips)',
 P_PATH='@t6g_mb_lib.t6g(sch_1):page364_i48@pure_quanta.q_cap(chips)',
 PATH='I48',
 DRAWING='@T6G_MB_LIB.T6G(SCH_1):PAGE477',
 TOLERANCE='10%',
 MATERIAL='X7R',
 PHYS_PAGE='364',
 XY='(-5125,400)',
 ROT='0',
 VER='1',
 PACK_TYPE='0402',
 LOCATION='PC819',
 CDS_LIB='pure_quanta',
 CDS_PART_NAME='Q_CAP_0402-0.1UF,25V,10%,X7R,CH4104K1B00',
 VOLTAGE='25V',
 PART_NUMBER='CH4104K1B00',
 VALUE='0.1UF',
 PRIM_FILE='./archive_libs/logical/q_cap/chips/chips.prt';

PART_NAME
 PC850 'Q_CAP_C0805-22UF,4V,20%,X6S,CH622KMEA03':;

SECTION_NUMBER 1
 '@T6G_MB_LIB.T6G(SCH_1):PAGE315_I37@PURE_QUANTA.Q_CAP(CHIPS)':
 C_PATH='@t6g_mb_lib.t6g(sch_1):page315_i37@pure_quanta.q_cap(chips)',
 P_PATH='@t6g_mb_lib.t6g(sch_1):page269_i37@pure_quanta.q_cap(chips)',
 PATH='I37',
 DRAWING='@T6G_MB_LIB.T6G(SCH_1):PAGE315',
 TOLERANCE='20%',
 MATERIAL='X6S',
 PHYS_PAGE='269',
 XY='(2775,1825)',
 ROT='0',
 VER='1',
 PACK_TYPE='C0805',
 LOCATION='PC850',
 CDS_LIB='pure_quanta',
 CDS_PART_NAME='Q_CAP_C0805-22UF,4V,20%,X6S,CH622KMEA03',
 VOLTAGE='4V',
 PART_NUMBER='CH622KMEA03',
 VALUE='22UF',
 PRIM_FILE='./archive_libs/logical/q_cap/chips/chips.prt';

PART_NAME
 PC852 'Q_CAP_0402-330PF,50V,10%,X7R,CH1336K1B02':;

SECTION_NUMBER 1
 '@T6G_MB_LIB.T6G(SCH_1):PAGE380_I26@PURE_QUANTA.Q_CAP(CHIPS)':
 C_PATH='@t6g_mb_lib.t6g(sch_1):page380_i26@pure_quanta.q_cap(chips)',
 P_PATH='@t6g_mb_lib.t6g(sch_1):page270_i26@pure_quanta.q_cap(chips)',
 PATH='I26',
 DRAWING='@T6G_MB_LIB.T6G(SCH_1):PAGE380',
 TOLERANCE='10%',
 MATERIAL='X7R',
 PHYS_PAGE='270',
 XY='(-2050,800)',
 ROT='0',
 VER='2',
 PACK_TYPE='0402',
 LOCATION='PC852',
 CDS_LIB='pure_quanta',
 CDS_PART_NAME='Q_CAP_0402-330PF,50V,10%,X7R,CH1336K1B02',
 VOLTAGE='50V',
 PART_NUMBER='CH1336K1B02',
 VALUE='330PF',
 PRIM_FILE='./archive_libs/logical/q_cap/chips/chips.prt';

PART_NAME
 PC865 'Q_CAP_C0805-22UF,4V,20%,X6S,CH622KMEA03':;

SECTION_NUMBER 1
 '@T6G_MB_LIB.T6G(SCH_1):PAGE315_I29@PURE_QUANTA.Q_CAP(CHIPS)':
 C_PATH='@t6g_mb_lib.t6g(sch_1):page315_i29@pure_quanta.q_cap(chips)',
 P_PATH='@t6g_mb_lib.t6g(sch_1):page269_i29@pure_quanta.q_cap(chips)',
 PATH='I29',
 DRAWING='@T6G_MB_LIB.T6G(SCH_1):PAGE315',
 TOLERANCE='20%',
 MATERIAL='X6S',
 PHYS_PAGE='269',
 XY='(1400,1825)',
 ROT='0',
 VER='1',
 PACK_TYPE='C0805',
 LOCATION='PC865',
 CDS_LIB='pure_quanta',
 CDS_PART_NAME='Q_CAP_C0805-22UF,4V,20%,X6S,CH622KMEA03',
 VOLTAGE='4V',
 PART_NUMBER='CH622KMEA03',
 VALUE='22UF',
 PRIM_FILE='./archive_libs/logical/q_cap/chips/chips.prt';

PART_NAME
 PC866 'Q_CAP_C0805-22UF,4V,20%,X6S,CH622KMEA03':;

SECTION_NUMBER 1
 '@T6G_MB_LIB.T6G(SCH_1):PAGE315_I34@PURE_QUANTA.Q_CAP(CHIPS)':
 C_PATH='@t6g_mb_lib.t6g(sch_1):page315_i34@pure_quanta.q_cap(chips)',
 P_PATH='@t6g_mb_lib.t6g(sch_1):page269_i34@pure_quanta.q_cap(chips)',
 PATH='I34',
 DRAWING='@T6G_MB_LIB.T6G(SCH_1):PAGE315',
 TOLERANCE='20%',
 MATERIAL='X6S',
 PHYS_PAGE='269',
 XY='(1775,1825)',
 ROT='0',
 VER='1',
 PACK_TYPE='C0805',
 LOCATION='PC866',
 CDS_LIB='pure_quanta',
 CDS_PART_NAME='Q_CAP_C0805-22UF,4V,20%,X6S,CH622KMEA03',
 VOLTAGE='4V',
 PART_NUMBER='CH622KMEA03',
 VALUE='22UF',
 PRIM_FILE='./archive_libs/logical/q_cap/chips/chips.prt';

PART_NAME
 PC867 'Q_CAP_C0805-22UF,4V,20%,X6S,CH622KMEA03':;

SECTION_NUMBER 1
 '@T6G_MB_LIB.T6G(SCH_1):PAGE315_I36@PURE_QUANTA.Q_CAP(CHIPS)':
 C_PATH='@t6g_mb_lib.t6g(sch_1):page315_i36@pure_quanta.q_cap(chips)',
 P_PATH='@t6g_mb_lib.t6g(sch_1):page269_i36@pure_quanta.q_cap(chips)',
 PATH='I36',
 DRAWING='@T6G_MB_LIB.T6G(SCH_1):PAGE315',
 TOLERANCE='20%',
 MATERIAL='X6S',
 PHYS_PAGE='269',
 XY='(2275,1825)',
 ROT='0',
 VER='1',
 PACK_TYPE='C0805',
 LOCATION='PC867',
 CDS_LIB='pure_quanta',
 CDS_PART_NAME='Q_CAP_C0805-22UF,4V,20%,X6S,CH622KMEA03',
 VOLTAGE='4V',
 PART_NUMBER='CH622KMEA03',
 VALUE='22UF',
 PRIM_FILE='./archive_libs/logical/q_cap/chips/chips.prt';

PART_NAME
 PC1320 'Q_CAP_C0603-2.2UF,16V,20%,X7R,CH5223M1900':
 ROOM='NIC_P12V_MPS_MAM_BOM2';

SECTION_NUMBER 1
 '@T6G_MB_LIB.T6G(SCH_1):PAGE344_I24@PURE_QUANTA.Q_CAP(CHIPS)':
 C_PATH='@t6g_mb_lib.t6g(sch_1):page344_i24@pure_quanta.q_cap(chips)',
 P_PATH='@t6g_mb_lib.t6g(sch_1):page141_i24@pure_quanta.q_cap(chips)',
 PATH='I24',
 DRAWING='@T6G_MB_LIB.T6G(SCH_1):PAGE344',
 TOLERANCE='20%',
 MATERIAL='X7R',
 PHYS_PAGE='141',
 XY='(550,2525)',
 ROT='0',
 VER='1',
 PACK_TYPE='C0603',
 LOCATION='PC1320',
 CDS_LIB='pure_quanta',
 CDS_PART_NAME='Q_CAP_C0603-2.2UF,16V,20%,X7R,CH5223M1900',
 VOLTAGE='16V',
 ROOM='NIC_P12V_MPS_MAM_BOM2',
 PART_NUMBER='CH5223M1900',
 VALUE='2.2UF',
 PRIM_FILE='./archive_libs/logical/q_cap/chips/chips.prt';

PART_NAME
 PC1321 'Q_CAP_0402-0.068UF,16V,10%,X7R,CH3683K1B09':
 ROOM='NIC_P3V3_BOM2';

SECTION_NUMBER 1
 '@T6G_MB_LIB.T6G(SCH_1):PAGE344_I50@PURE_QUANTA.Q_CAP(CHIPS)':
 C_PATH='@t6g_mb_lib.t6g(sch_1):page344_i50@pure_quanta.q_cap(chips)',
 P_PATH='@t6g_mb_lib.t6g(sch_1):page141_i50@pure_quanta.q_cap(chips)',
 PATH='I50',
 DRAWING='@T6G_MB_LIB.T6G(SCH_1):PAGE344',
 TOLERANCE='10%',
 MATERIAL='X7R',
 PHYS_PAGE='141',
 XY='(870,6108)',
 ROT='0',
 VER='1',
 PACK_TYPE='0402',
 LOCATION='PC1321',
 CDS_LIB='pure_quanta',
 CDS_PART_NAME='Q_CAP_0402-0.068UF,16V,10%,X7R,CH3683K1B09',
 VOLTAGE='16V',
 ROOM='NIC_P3V3_BOM2',
 PART_NUMBER='CH3683K1B09',
 VALUE='0.068UF',
 PRIM_FILE='./archive_libs/logical/q_cap/chips/chips.prt';

PART_NAME
 PC1322 'Q_CAP_0402-100PF,50V,5%,X7R,CH11006JB18':
 ROOM='NIC_P3V3_BOM2';

SECTION_NUMBER 1
 '@T6G_MB_LIB.T6G(SCH_1):PAGE344_I54@PURE_QUANTA.Q_CAP(CHIPS)':
 C_PATH='@t6g_mb_lib.t6g(sch_1):page344_i54@pure_quanta.q_cap(chips)',
 P_PATH='@t6g_mb_lib.t6g(sch_1):page141_i54@pure_quanta.q_cap(chips)',
 PATH='I54',
 DRAWING='@T6G_MB_LIB.T6G(SCH_1):PAGE344',
 TOLERANCE='5%',
 MATERIAL='X7R',
 PHYS_PAGE='141',
 XY='(2500,6150)',
 ROT='0',
 VER='1',
 PACK_TYPE='0402',
 LOCATION='PC1322',
 CDS_LIB='pure_quanta',
 CDS_PART_NAME='Q_CAP_0402-100PF,50V,5%,X7R,CH11006JB18',
 VOLTAGE='50V',
 ROOM='NIC_P3V3_BOM2',
 PART_NUMBER='CH11006JB18',
 VALUE='100PF',
 PRIM_FILE='./archive_libs/logical/q_cap/chips/chips.prt';

PART_NAME
 PC1525 'Q_CAP_C0402-1UF,25V,10%,X6S,CH5104KEB02':
 ROOM='HSC BOM1';

SECTION_NUMBER 1
 '@T6G_MB_LIB.T6G(SCH_1):PAGE301_I20@PURE_QUANTA.Q_CAP(CHIPS)':
 C_PATH='@t6g_mb_lib.t6g(sch_1):page301_i20@pure_quanta.q_cap(chips)',
 P_PATH='@t6g_mb_lib.t6g(sch_1):page263_i20@pure_quanta.q_cap(chips)',
 PATH='I20',
 DRAWING='@T6G_MB_LIB.T6G(SCH_1):PAGE301',
 TOLERANCE='10%',
 MATERIAL='X6S',
 PHYS_PAGE='263',
 XY='(-3450,1375)',
 ROT='0',
 VER='1',
 PACK_TYPE='C0402',
 LOCATION='PC1525',
 CDS_LIB='pure_quanta',
 CDS_PART_NAME='Q_CAP_C0402-1UF,25V,10%,X6S,CH5104KEB02',
 VOLTAGE='25V',
 ROOM='HSC BOM1',
 PART_NUMBER='CH5104KEB02',
 VALUE='1UF',
 PRIM_FILE='./archive_libs/logical/q_cap/chips/chips.prt';

PART_NAME
 PC1599 'Q_CAP_C0805-22UF,10V,20%,X6S,CH6222MEA01':;

SECTION_NUMBER 1
 '@T6G_MB_LIB.T6G(SCH_1):PAGE245_I60@PURE_QUANTA.Q_CAP(CHIPS)':
 C_PATH='@t6g_mb_lib.t6g(sch_1):page245_i60@pure_quanta.q_cap(chips)',
 P_PATH='@t6g_mb_lib.t6g(sch_1):page190_i60@pure_quanta.q_cap(chips)',
 PATH='I60',
 DRAWING='@T6G_MB_LIB.T6G(SCH_1):PAGE245',
 TOLERANCE='20%',
 MATERIAL='X6S',
 PHYS_PAGE='190',
 XY='(2950,-725)',
 ROT='0',
 VER='1',
 PACK_TYPE='C0805',
 LOCATION='PC1599',
 CDS_LIB='pure_quanta',
 CDS_PART_NAME='Q_CAP_C0805-22UF,10V,20%,X6S,CH6222MEA01',
 VOLTAGE='10V',
 PART_NUMBER='CH6222MEA01',
 VALUE='22UF',
 PRIM_FILE='./archive_libs/logical/q_cap/chips/chips.prt';

PART_NAME
 PC1600 'Q_CAP_C0805-22UF,10V,20%,X6S,CH6222MEA01':;

SECTION_NUMBER 1
 '@T6G_MB_LIB.T6G(SCH_1):PAGE245_I62@PURE_QUANTA.Q_CAP(CHIPS)':
 C_PATH='@t6g_mb_lib.t6g(sch_1):page245_i62@pure_quanta.q_cap(chips)',
 P_PATH='@t6g_mb_lib.t6g(sch_1):page190_i62@pure_quanta.q_cap(chips)',
 PATH='I62',
 DRAWING='@T6G_MB_LIB.T6G(SCH_1):PAGE245',
 TOLERANCE='20%',
 MATERIAL='X6S',
 PHYS_PAGE='190',
 XY='(3325,-725)',
 ROT='0',
 VER='1',
 PACK_TYPE='C0805',
 LOCATION='PC1600',
 CDS_LIB='pure_quanta',
 CDS_PART_NAME='Q_CAP_C0805-22UF,10V,20%,X6S,CH6222MEA01',
 VOLTAGE='10V',
 PART_NUMBER='CH6222MEA01',
 VALUE='22UF',
 PRIM_FILE='./archive_libs/logical/q_cap/chips/chips.prt';

PART_NAME
 PC1648 'Q_CAP_C0402-0.1UF,25V,10%,X6S,CH4104KEB00':;

SECTION_NUMBER 1
 '@T6G_MB_LIB.T6G(SCH_1):PAGE244_I2@PURE_QUANTA.Q_CAP(CHIPS)':
 C_PATH='@t6g_mb_lib.t6g(sch_1):page244_i2@pure_quanta.q_cap(chips)',
 P_PATH='@t6g_mb_lib.t6g(sch_1):page189_i2@pure_quanta.q_cap(chips)',
 PATH='I2',
 DRAWING='@T6G_MB_LIB.T6G(SCH_1):PAGE244',
 TOLERANCE='10%',
 MATERIAL='X6S',
 PHYS_PAGE='189',
 XY='(-8200,8925)',
 ROT='0',
 VER='1',
 PACK_TYPE='C0402',
 LOCATION='PC1648',
 CDS_LIB='pure_quanta',
 CDS_PART_NAME='Q_CAP_C0402-0.1UF,25V,10%,X6S,CH4104KEB00',
 VOLTAGE='25V',
 PART_NUMBER='CH4104KEB00',
 VALUE='0.1UF',
 PRIM_FILE='./archive_libs/logical/q_cap/chips/chips.prt';

PART_NAME
 PC1649 'Q_CAP_C0402-0.1UF,25V,10%,X6S,CH4104KEB00':;

SECTION_NUMBER 1
 '@T6G_MB_LIB.T6G(SCH_1):PAGE245_I23@PURE_QUANTA.Q_CAP(CHIPS)':
 C_PATH='@t6g_mb_lib.t6g(sch_1):page245_i23@pure_quanta.q_cap(chips)',
 P_PATH='@t6g_mb_lib.t6g(sch_1):page190_i23@pure_quanta.q_cap(chips)',
 PATH='I23',
 DRAWING='@T6G_MB_LIB.T6G(SCH_1):PAGE245',
 TOLERANCE='10%',
 MATERIAL='X6S',
 PHYS_PAGE='190',
 XY='(-4525,1100)',
 ROT='0',
 VER='1',
 PACK_TYPE='C0402',
 LOCATION='PC1649',
 CDS_LIB='pure_quanta',
 CDS_PART_NAME='Q_CAP_C0402-0.1UF,25V,10%,X6S,CH4104KEB00',
 VOLTAGE='25V',
 PART_NUMBER='CH4104KEB00',
 VALUE='0.1UF',
 PRIM_FILE='./archive_libs/logical/q_cap/chips/chips.prt';

PART_NAME
 PC1750 'Q_CAP_C0402-33NF,25V,10%,EMPTY,CH3334K1B00':
 ROOM='HSC BOM2';

SECTION_NUMBER 1
 '@T6G_MB_LIB.T6G(SCH_1):PAGE302_I63@PURE_QUANTA.Q_CAP(CHIPS)':
 C_PATH='@t6g_mb_lib.t6g(sch_1):page302_i63@pure_quanta.q_cap(chips)',
 P_PATH='@t6g_mb_lib.t6g(sch_1):page266_i63@pure_quanta.q_cap(chips)',
 PATH='I63',
 DRAWING='@T6G_MB_LIB.T6G(SCH_1):PAGE302',
 TOLERANCE='10%',
 MATERIAL='EMPTY',
 PHYS_PAGE='266',
 XY='(-1650,1575)',
 ROT='0',
 VER='1',
 PACK_TYPE='C0402',
 LOCATION='PC1750',
 CDS_LIB='pure_quanta',
 CDS_PART_NAME='Q_CAP_C0402-33NF,25V,10%,EMPTY,CH3334K1B00',
 VOLTAGE='25V',
 ROOM='HSC BOM2',
 PART_NUMBER='CH3334K1B00',
 VALUE='33NF',
 PRIM_FILE='./archive_libs/logical/q_cap/chips/chips.prt';

PART_NAME
 PC1751 'Q_CAP_0402-1NF,50V,10%,EMPTY,CH21006KB16':
 ROOM='HSC BOM2';

SECTION_NUMBER 1
 '@T6G_MB_LIB.T6G(SCH_1):PAGE302_I70@PURE_QUANTA.Q_CAP(CHIPS)':
 C_PATH='@t6g_mb_lib.t6g(sch_1):page302_i70@pure_quanta.q_cap(chips)',
 P_PATH='@t6g_mb_lib.t6g(sch_1):page266_i70@pure_quanta.q_cap(chips)',
 PATH='I70',
 DRAWING='@T6G_MB_LIB.T6G(SCH_1):PAGE302',
 TOLERANCE='10%',
 MATERIAL='EMPTY',
 PHYS_PAGE='266',
 XY='(-1175,1275)',
 ROT='0',
 VER='1',
 PACK_TYPE='0402',
 LOCATION='PC1751',
 CDS_LIB='pure_quanta',
 CDS_PART_NAME='Q_CAP_0402-1NF,50V,10%,EMPTY,CH21006KB16',
 VOLTAGE='50V',
 ROOM='HSC BOM2',
 PART_NUMBER='CH21006KB16',
 VALUE='1NF',
 PRIM_FILE='./archive_libs/logical/q_cap/chips/chips.prt';

PART_NAME
 PC1789 'Q_CAP_0402-0.1UF,25V,10%,X7R,CH4104K1B00':
 ROOM='HSC BOM2';

SECTION_NUMBER 1
 '@T6G_MB_LIB.T6G(SCH_1):PAGE371_I28@PURE_QUANTA.Q_CAP(CHIPS)':
 C_PATH='@t6g_mb_lib.t6g(sch_1):page371_i28@pure_quanta.q_cap(chips)',
 P_PATH='@t6g_mb_lib.t6g(sch_1):page267_i28@pure_quanta.q_cap(chips)',
 PATH='I28',
 DRAWING='@T6G_MB_LIB.T6G(SCH_1):PAGE371',
 TOLERANCE='10%',
 MATERIAL='X7R',
 PHYS_PAGE='267',
 XY='(-925,3625)',
 ROT='0',
 VER='1',
 PACK_TYPE='0402',
 LOCATION='PC1789',
 CDS_LIB='pure_quanta',
 CDS_PART_NAME='Q_CAP_0402-0.1UF,25V,10%,X7R,CH4104K1B00',
 VOLTAGE='25V',
 ROOM='HSC BOM2',
 PART_NUMBER='CH4104K1B00',
 VALUE='0.1UF',
 PRIM_FILE='./archive_libs/logical/q_cap/chips/chips.prt';

PART_NAME
 PC1845 'Q_CAPP_SMLF-220UF,6.3V,20%,ALUM,CC72201MZ28':;

SECTION_NUMBER 1
 '@T6G_MB_LIB.T6G(SCH_1):PAGE244_I30@PURE_QUANTA.Q_CAPP(CHIPS)':
 C_PATH='@t6g_mb_lib.t6g(sch_1):page244_i30@pure_quanta.q_capp(chips)',
 P_PATH='@t6g_mb_lib.t6g(sch_1):page189_i30@pure_quanta.q_capp(chips)',
 PATH='I30',
 DRAWING='@T6G_MB_LIB.T6G(SCH_1):PAGE244',
 TOLERANCE='20%',
 MATERIAL='ALUM',
 PHYS_PAGE='189',
 XY='(-1550,7500)',
 ROT='0',
 VER='1',
 PACK_TYPE='SMLF',
 LOCATION='PC1845',
 CDS_LIB='pure_quanta',
 CDS_PART_NAME='Q_CAPP_SMLF-220UF,6.3V,20%,ALUM,CC72201MZ28',
 VOLTAGE='6.3V',
 PART_NUMBER='CC72201MZ28',
 VALUE='220UF',
 PRIM_FILE='./archive_libs/logical/q_capp/chips/chips.prt';

PART_NAME
 PC1846 'Q_CAP_C0402-1UF,16V,10%,X6S,CH5103KEB01':;

SECTION_NUMBER 1
 '@T6G_MB_LIB.T6G(SCH_1):PAGE244_I13@PURE_QUANTA.Q_CAP(CHIPS)':
 C_PATH='@t6g_mb_lib.t6g(sch_1):page244_i13@pure_quanta.q_cap(chips)',
 P_PATH='@t6g_mb_lib.t6g(sch_1):page189_i13@pure_quanta.q_cap(chips)',
 PATH='I13',
 DRAWING='@T6G_MB_LIB.T6G(SCH_1):PAGE244',
 TOLERANCE='10%',
 MATERIAL='X6S',
 PHYS_PAGE='189',
 XY='(-6175,8900)',
 ROT='0',
 VER='1',
 PACK_TYPE='C0402',
 LOCATION='PC1846',
 CDS_LIB='pure_quanta',
 CDS_PART_NAME='Q_CAP_C0402-1UF,16V,10%,X6S,CH5103KEB01',
 VOLTAGE='16V',
 PART_NUMBER='CH5103KEB01',
 VALUE='1UF',
 PRIM_FILE='./archive_libs/logical/q_cap/chips/chips.prt';

PART_NAME
 PC1847 'Q_CAP_C0402-0.22UF,25V,10%,X7R,CH4224K1B01':;

SECTION_NUMBER 1
 '@T6G_MB_LIB.T6G(SCH_1):PAGE244_I24@PURE_QUANTA.Q_CAP(CHIPS)':
 C_PATH='@t6g_mb_lib.t6g(sch_1):page244_i24@pure_quanta.q_cap(chips)',
 P_PATH='@t6g_mb_lib.t6g(sch_1):page189_i24@pure_quanta.q_cap(chips)',
 PATH='I24',
 DRAWING='@T6G_MB_LIB.T6G(SCH_1):PAGE244',
 TOLERANCE='10%',
 MATERIAL='X7R',
 PHYS_PAGE='189',
 XY='(-3725,7900)',
 ROT='0',
 VER='1',
 PACK_TYPE='C0402',
 LOCATION='PC1847',
 CDS_LIB='pure_quanta',
 CDS_PART_NAME='Q_CAP_C0402-0.22UF,25V,10%,X7R,CH4224K1B01',
 VOLTAGE='25V',
 PART_NUMBER='CH4224K1B01',
 VALUE='0.22UF',
 PRIM_FILE='./archive_libs/logical/q_cap/chips/chips.prt';

PART_NAME
 PC1848 'Q_CAP_C0402-1UF,25V,10%,X6S,CH5104KEB02':
 SIGNAL_MODEL='DEFAULT_CAPACITOR_100000PF_2_1';

SECTION_NUMBER 1
 '@T6G_MB_LIB.T6G(SCH_1):PAGE244_I8@PURE_QUANTA.Q_CAP(CHIPS)':
 C_PATH='@t6g_mb_lib.t6g(sch_1):page244_i8@pure_quanta.q_cap(chips)',
 P_PATH='@t6g_mb_lib.t6g(sch_1):page189_i8@pure_quanta.q_cap(chips)',
 PATH='I8',
 DRAWING='@T6G_MB_LIB.T6G(SCH_1):PAGE244',
 SEC_TYPE='C0402',
 TOLERANCE='10%',
 MATERIAL='X6S',
 PHYS_PAGE='189',
 XY='(-6825,7025)',
 ROT='2',
 VER='1',
 PACK_TYPE='C0402',
 LOCATION='PC1848',
 SEC='1',
 CDS_LIB='pure_quanta',
 CDS_PART_NAME='Q_CAP_C0402-1UF,25V,10%,X6S,CH5104KEB02',
 SIGNAL_MODEL='DEFAULT_CAPACITOR_100000PF_2_1',
 VOLTAGE='25V',
 PART_NUMBER='CH5104KEB02',
 VALUE='1UF',
 PRIM_FILE='./archive_libs/logical/q_cap/chips/chips.prt';

PART_NAME
 PC1849 'Q_CAP_C0805-22UF,16V,20%,X6S,CH6223MEA01':;

SECTION_NUMBER 1
 '@T6G_MB_LIB.T6G(SCH_1):PAGE244_I7@PURE_QUANTA.Q_CAP(CHIPS)':
 C_PATH='@t6g_mb_lib.t6g(sch_1):page244_i7@pure_quanta.q_cap(chips)',
 P_PATH='@t6g_mb_lib.t6g(sch_1):page189_i7@pure_quanta.q_cap(chips)',
 PATH='I7',
 DRAWING='@T6G_MB_LIB.T6G(SCH_1):PAGE244',
 TOLERANCE='20%',
 MATERIAL='X6S',
 PHYS_PAGE='189',
 XY='(-7425,8900)',
 ROT='0',
 VER='1',
 PACK_TYPE='C0805',
 LOCATION='PC1849',
 CDS_LIB='pure_quanta',
 CDS_PART_NAME='Q_CAP_C0805-22UF,16V,20%,X6S,CH6223MEA01',
 VOLTAGE='16V',
 PART_NUMBER='CH6223MEA01',
 VALUE='22UF',
 PRIM_FILE='./archive_libs/logical/q_cap/chips/chips.prt';

PART_NAME
 PC1850 'Q_CAP_C0805-22UF,16V,20%,X6S,CH6223MEA01':;

SECTION_NUMBER 1
 '@T6G_MB_LIB.T6G(SCH_1):PAGE244_I10@PURE_QUANTA.Q_CAP(CHIPS)':
 C_PATH='@t6g_mb_lib.t6g(sch_1):page244_i10@pure_quanta.q_cap(chips)',
 P_PATH='@t6g_mb_lib.t6g(sch_1):page189_i10@pure_quanta.q_cap(chips)',
 PATH='I10',
 DRAWING='@T6G_MB_LIB.T6G(SCH_1):PAGE244',
 TOLERANCE='20%',
 MATERIAL='X6S',
 PHYS_PAGE='189',
 XY='(-7025,8900)',
 ROT='0',
 VER='1',
 PACK_TYPE='C0805',
 LOCATION='PC1850',
 CDS_LIB='pure_quanta',
 CDS_PART_NAME='Q_CAP_C0805-22UF,16V,20%,X6S,CH6223MEA01',
 VOLTAGE='16V',
 PART_NUMBER='CH6223MEA01',
 VALUE='22UF',
 PRIM_FILE='./archive_libs/logical/q_cap/chips/chips.prt';

PART_NAME
 PC1852 'Q_CAP_0402-0.1UF,25V,10%,X7R,CH4104K1B00':;

SECTION_NUMBER 1
 '@T6G_MB_LIB.T6G(SCH_1):PAGE244_I34@PURE_QUANTA.Q_CAP(CHIPS)':
 C_PATH='@t6g_mb_lib.t6g(sch_1):page244_i34@pure_quanta.q_cap(chips)',
 P_PATH='@t6g_mb_lib.t6g(sch_1):page189_i34@pure_quanta.q_cap(chips)',
 PATH='I34',
 DRAWING='@T6G_MB_LIB.T6G(SCH_1):PAGE244',
 SEC_TYPE='0402',
 TOLERANCE='10%',
 MATERIAL='X7R',
 PHYS_PAGE='189',
 XY='(-175,7500)',
 ROT='0',
 VER='1',
 PACK_TYPE='0402',
 LOCATION='PC1852',
 SEC='1',
 CDS_LIB='pure_quanta',
 CDS_PART_NAME='Q_CAP_0402-0.1UF,25V,10%,X7R,CH4104K1B00',
 VOLTAGE='25V',
 PART_NUMBER='CH4104K1B00',
 VALUE='0.1UF',
 PRIM_FILE='./archive_libs/logical/q_cap/chips/chips.prt';

PART_NAME
 PC1853 'Q_CAP_0402-0.1UF,25V,10%,X7R,CH4104K1B00':;

SECTION_NUMBER 1
 '@T6G_MB_LIB.T6G(SCH_1):PAGE244_I19@PURE_QUANTA.Q_CAP(CHIPS)':
 C_PATH='@t6g_mb_lib.t6g(sch_1):page244_i19@pure_quanta.q_cap(chips)',
 P_PATH='@t6g_mb_lib.t6g(sch_1):page189_i19@pure_quanta.q_cap(chips)',
 PATH='I19',
 DRAWING='@T6G_MB_LIB.T6G(SCH_1):PAGE244',
 TOLERANCE='10%',
 MATERIAL='X7R',
 PHYS_PAGE='189',
 XY='(-4250,6850)',
 ROT='0',
 VER='1',
 PACK_TYPE='0402',
 LOCATION='PC1853',
 CDS_LIB='pure_quanta',
 CDS_PART_NAME='Q_CAP_0402-0.1UF,25V,10%,X7R,CH4104K1B00',
 VOLTAGE='25V',
 PART_NUMBER='CH4104K1B00',
 VALUE='0.1UF',
 PRIM_FILE='./archive_libs/logical/q_cap/chips/chips.prt';

PART_NAME
 PC1855 'Q_CAP_C0805-22UF,10V,20%,X6S,CH6222MEA01':;

SECTION_NUMBER 1
 '@T6G_MB_LIB.T6G(SCH_1):PAGE244_I31@PURE_QUANTA.Q_CAP(CHIPS)':
 C_PATH='@t6g_mb_lib.t6g(sch_1):page244_i31@pure_quanta.q_cap(chips)',
 P_PATH='@t6g_mb_lib.t6g(sch_1):page189_i31@pure_quanta.q_cap(chips)',
 PATH='I31',
 DRAWING='@T6G_MB_LIB.T6G(SCH_1):PAGE244',
 TOLERANCE='20%',
 MATERIAL='X6S',
 PHYS_PAGE='189',
 XY='(-1100,7500)',
 ROT='0',
 VER='1',
 PACK_TYPE='C0805',
 LOCATION='PC1855',
 CDS_LIB='pure_quanta',
 CDS_PART_NAME='Q_CAP_C0805-22UF,10V,20%,X6S,CH6222MEA01',
 VOLTAGE='10V',
 PART_NUMBER='CH6222MEA01',
 VALUE='22UF',
 PRIM_FILE='./archive_libs/logical/q_cap/chips/chips.prt';

PART_NAME
 PC1856 'Q_CAP_C0805-22UF,10V,20%,X6S,CH6222MEA01':;

SECTION_NUMBER 1
 '@T6G_MB_LIB.T6G(SCH_1):PAGE244_I32@PURE_QUANTA.Q_CAP(CHIPS)':
 C_PATH='@t6g_mb_lib.t6g(sch_1):page244_i32@pure_quanta.q_cap(chips)',
 P_PATH='@t6g_mb_lib.t6g(sch_1):page189_i32@pure_quanta.q_cap(chips)',
 PATH='I32',
 DRAWING='@T6G_MB_LIB.T6G(SCH_1):PAGE244',
 TOLERANCE='20%',
 MATERIAL='X6S',
 PHYS_PAGE='189',
 XY='(-600,7500)',
 ROT='0',
 VER='1',
 PACK_TYPE='C0805',
 LOCATION='PC1856',
 CDS_LIB='pure_quanta',
 CDS_PART_NAME='Q_CAP_C0805-22UF,10V,20%,X6S,CH6222MEA01',
 VOLTAGE='10V',
 PART_NUMBER='CH6222MEA01',
 VALUE='22UF',
 PRIM_FILE='./archive_libs/logical/q_cap/chips/chips.prt';

PART_NAME
 PC1866 'Q_CAPP_THLF-560UF,6.3V,20%,OSCON,CC75601MD16':;

SECTION_NUMBER 1
 '@T6G_MB_LIB.T6G(SCH_1):PAGE245_I57@PURE_QUANTA.Q_CAPP(CHIPS)':
 C_PATH='@t6g_mb_lib.t6g(sch_1):page245_i57@pure_quanta.q_capp(chips)',
 P_PATH='@t6g_mb_lib.t6g(sch_1):page190_i57@pure_quanta.q_capp(chips)',
 PATH='I57',
 DRAWING='@T6G_MB_LIB.T6G(SCH_1):PAGE245',
 TOLERANCE='20%',
 MATERIAL='OSCON',
 PHYS_PAGE='190',
 XY='(1650,-725)',
 ROT='0',
 VER='1',
 PACK_TYPE='THLF',
 LOCATION='PC1866',
 CDS_LIB='pure_quanta',
 CDS_PART_NAME='Q_CAPP_THLF-560UF,6.3V,20%,OSCON,CC75601MD16',
 VOLTAGE='6.3V',
 PART_NUMBER='CC75601MD16',
 VALUE='560UF',
 PRIM_FILE='./archive_libs/logical/q_capp/chips/chips.prt';

PART_NAME
 PC1867 'Q_CAPP_THLF-560UF,6.3V,20%,OSCON,CC75601MD16':;

SECTION_NUMBER 1
 '@T6G_MB_LIB.T6G(SCH_1):PAGE245_I58@PURE_QUANTA.Q_CAPP(CHIPS)':
 C_PATH='@t6g_mb_lib.t6g(sch_1):page245_i58@pure_quanta.q_capp(chips)',
 P_PATH='@t6g_mb_lib.t6g(sch_1):page190_i58@pure_quanta.q_capp(chips)',
 PATH='I58',
 DRAWING='@T6G_MB_LIB.T6G(SCH_1):PAGE245',
 TOLERANCE='20%',
 MATERIAL='OSCON',
 PHYS_PAGE='190',
 XY='(2100,-725)',
 ROT='0',
 VER='1',
 PACK_TYPE='THLF',
 LOCATION='PC1867',
 CDS_LIB='pure_quanta',
 CDS_PART_NAME='Q_CAPP_THLF-560UF,6.3V,20%,OSCON,CC75601MD16',
 VOLTAGE='6.3V',
 PART_NUMBER='CC75601MD16',
 VALUE='560UF',
 PRIM_FILE='./archive_libs/logical/q_capp/chips/chips.prt';

PART_NAME
 PC1868 'Q_CAP_C0805-22UF,10V,20%,X6S,CH6222MEA01':;

SECTION_NUMBER 1
 '@T6G_MB_LIB.T6G(SCH_1):PAGE245_I59@PURE_QUANTA.Q_CAP(CHIPS)':
 C_PATH='@t6g_mb_lib.t6g(sch_1):page245_i59@pure_quanta.q_cap(chips)',
 P_PATH='@t6g_mb_lib.t6g(sch_1):page190_i59@pure_quanta.q_cap(chips)',
 PATH='I59',
 DRAWING='@T6G_MB_LIB.T6G(SCH_1):PAGE245',
 TOLERANCE='20%',
 MATERIAL='X6S',
 PHYS_PAGE='190',
 XY='(2550,-700)',
 ROT='0',
 VER='1',
 PACK_TYPE='C0805',
 LOCATION='PC1868',
 CDS_LIB='pure_quanta',
 CDS_PART_NAME='Q_CAP_C0805-22UF,10V,20%,X6S,CH6222MEA01',
 VOLTAGE='10V',
 PART_NUMBER='CH6222MEA01',
 VALUE='22UF',
 PRIM_FILE='./archive_libs/logical/q_cap/chips/chips.prt';

PART_NAME
 PC1869 'Q_CAP_0402-0.1UF,25V,10%,X7R,CH4104K1B00':;

SECTION_NUMBER 1
 '@T6G_MB_LIB.T6G(SCH_1):PAGE245_I63@PURE_QUANTA.Q_CAP(CHIPS)':
 C_PATH='@t6g_mb_lib.t6g(sch_1):page245_i63@pure_quanta.q_cap(chips)',
 P_PATH='@t6g_mb_lib.t6g(sch_1):page190_i63@pure_quanta.q_cap(chips)',
 PATH='I63',
 DRAWING='@T6G_MB_LIB.T6G(SCH_1):PAGE245',
 TOLERANCE='10%',
 MATERIAL='X7R',
 PHYS_PAGE='190',
 XY='(3725,-725)',
 ROT='0',
 VER='1',
 PACK_TYPE='0402',
 LOCATION='PC1869',
 CDS_LIB='pure_quanta',
 CDS_PART_NAME='Q_CAP_0402-0.1UF,25V,10%,X7R,CH4104K1B00',
 VOLTAGE='25V',
 PART_NUMBER='CH4104K1B00',
 VALUE='0.1UF',
 PRIM_FILE='./archive_libs/logical/q_cap/chips/chips.prt';

PART_NAME
 PC1870 'Q_CAP_0402-0.1UF,25V,10%,EMPTY,CH4104K1B00':;

SECTION_NUMBER 1
 '@T6G_MB_LIB.T6G(SCH_1):PAGE245_I8@PURE_QUANTA.Q_CAP(CHIPS)':
 C_PATH='@t6g_mb_lib.t6g(sch_1):page245_i8@pure_quanta.q_cap(chips)',
 P_PATH='@t6g_mb_lib.t6g(sch_1):page190_i8@pure_quanta.q_cap(chips)',
 PATH='I8',
 DRAWING='@T6G_MB_LIB.T6G(SCH_1):PAGE245',
 TOLERANCE='10%',
 MATERIAL='EMPTY',
 PHYS_PAGE='190',
 XY='(-2700,-1175)',
 ROT='2',
 VER='1',
 PACK_TYPE='0402',
 LOCATION='PC1870',
 CDS_LIB='pure_quanta',
 CDS_PART_NAME='Q_CAP_0402-0.1UF,25V,10%,EMPTY,CH4104K1B00',
 VOLTAGE='25V',
 PART_NUMBER='CH4104K1B00',
 VALUE='0.1UF',
 PRIM_FILE='./archive_libs/logical/q_cap/chips/chips.prt';

PART_NAME
 PC1877 'Q_CAP_0402-47PF,50V,5%,NPO,TMP_QCH04706JB01':;

SECTION_NUMBER 1
 '@T6G_MB_LIB.T6G(SCH_1):PAGE244_I20@PURE_QUANTA.Q_CAP(CHIPS)':
 C_PATH='@t6g_mb_lib.t6g(sch_1):page244_i20@pure_quanta.q_cap(chips)',
 P_PATH='@t6g_mb_lib.t6g(sch_1):page189_i20@pure_quanta.q_cap(chips)',
 PATH='I20',
 DRAWING='@T6G_MB_LIB.T6G(SCH_1):PAGE244',
 TOLERANCE='5%',
 MATERIAL='NPO',
 PHYS_PAGE='189',
 XY='(-2325,6625)',
 ROT='0',
 VER='2',
 PACK_TYPE='0402',
 LOCATION='PC1877',
 CDS_LIB='pure_quanta',
 CDS_PART_NAME='Q_CAP_0402-47PF,50V,5%,NPO,TMP_QCH04706JB01',
 VOLTAGE='50V',
 PART_NUMBER='TMP_QCH04706JB01',
 VALUE='47PF',
 PRIM_FILE='./archive_libs/logical/q_cap/chips/chips.prt';

PART_NAME
 PC1898 'Q_CAP_C0805-22UF,16V,20%,X6S,CH6223MEA01':;

SECTION_NUMBER 1
 '@T6G_MB_LIB.T6G(SCH_1):PAGE244_I11@PURE_QUANTA.Q_CAP(CHIPS)':
 C_PATH='@t6g_mb_lib.t6g(sch_1):page244_i11@pure_quanta.q_cap(chips)',
 P_PATH='@t6g_mb_lib.t6g(sch_1):page189_i11@pure_quanta.q_cap(chips)',
 PATH='I11',
 DRAWING='@T6G_MB_LIB.T6G(SCH_1):PAGE244',
 TOLERANCE='20%',
 MATERIAL='X6S',
 PHYS_PAGE='189',
 XY='(-6575,8900)',
 ROT='0',
 VER='1',
 PACK_TYPE='C0805',
 LOCATION='PC1898',
 CDS_LIB='pure_quanta',
 CDS_PART_NAME='Q_CAP_C0805-22UF,16V,20%,X6S,CH6223MEA01',
 VOLTAGE='16V',
 PART_NUMBER='CH6223MEA01',
 VALUE='22UF',
 PRIM_FILE='./archive_libs/logical/q_cap/chips/chips.prt';

PART_NAME
 PC2079 'Q_CAP_C0402-1UF,25V,10%,X6S,CH5104KEB02':;

SECTION_NUMBER 1
 '@T6G_MB_LIB.T6G(SCH_1):PAGE338_I45@PURE_QUANTA.Q_CAP(CHIPS)':
 C_PATH='@t6g_mb_lib.t6g(sch_1):page338_i45@pure_quanta.q_cap(chips)',
 P_PATH='@t6g_mb_lib.t6g(sch_1):page134_i45@pure_quanta.q_cap(chips)',
 PATH='I45',
 DRAWING='@T6G_MB_LIB.T6G(SCH_1):PAGE338',
 TOLERANCE='10%',
 MATERIAL='X6S',
 PHYS_PAGE='134',
 XY='(5675,11450)',
 ROT='0',
 VER='1',
 PACK_TYPE='C0402',
 LOCATION='PC2079',
 CDS_LIB='pure_quanta',
 CDS_PART_NAME='Q_CAP_C0402-1UF,25V,10%,X6S,CH5104KEB02',
 VOLTAGE='25V',
 PART_NUMBER='CH5104KEB02',
 VALUE='1UF',
 PRIM_FILE='./archive_libs/logical/q_cap/chips/chips.prt';

PART_NAME
 PC2080 'Q_CAP_C0805-22UF,16V,20%,X6S,CH6223MEA01':;

SECTION_NUMBER 1
 '@T6G_MB_LIB.T6G(SCH_1):PAGE338_I87@PURE_QUANTA.Q_CAP(CHIPS)':
 C_PATH='@t6g_mb_lib.t6g(sch_1):page338_i87@pure_quanta.q_cap(chips)',
 P_PATH='@t6g_mb_lib.t6g(sch_1):page134_i87@pure_quanta.q_cap(chips)',
 PATH='I87',
 DRAWING='@T6G_MB_LIB.T6G(SCH_1):PAGE338',
 TOLERANCE='20%',
 MATERIAL='X6S',
 PHYS_PAGE='134',
 XY='(9725,11675)',
 ROT='0',
 VER='1',
 PACK_TYPE='C0805',
 LOCATION='PC2080',
 CDS_LIB='pure_quanta',
 CDS_PART_NAME='Q_CAP_C0805-22UF,16V,20%,X6S,CH6223MEA01',
 VOLTAGE='16V',
 PART_NUMBER='CH6223MEA01',
 VALUE='22UF',
 PRIM_FILE='./archive_libs/logical/q_cap/chips/chips.prt';

PART_NAME
 PC2081 'Q_CAP_C0805-10UF,16V,10%,X6S,CH6103KEA01':;

SECTION_NUMBER 1
 '@T6G_MB_LIB.T6G(SCH_1):PAGE338_I106@PURE_QUANTA.Q_CAP(CHIPS)':
 C_PATH='@t6g_mb_lib.t6g(sch_1):page338_i106@pure_quanta.q_cap(chips)',
 P_PATH='@t6g_mb_lib.t6g(sch_1):page134_i106@pure_quanta.q_cap(chips)',
 PATH='I106',
 DRAWING='@T6G_MB_LIB.T6G(SCH_1):PAGE338',
 TOLERANCE='10%',
 MATERIAL='X6S',
 PHYS_PAGE='134',
 XY='(10125,13650)',
 ROT='0',
 VER='1',
 PACK_TYPE='C0805',
 LOCATION='PC2081',
 CDS_LIB='pure_quanta',
 CDS_PART_NAME='Q_CAP_C0805-10UF,16V,10%,X6S,CH6103KEA01',
 VOLTAGE='16V',
 PART_NUMBER='CH6103KEA01',
 VALUE='10UF',
 PRIM_FILE='./archive_libs/logical/q_cap/chips/chips.prt';

PART_NAME
 PC2082 'Q_CAP_C0805-10UF,16V,10%,X6S,CH6103KEA01':;

SECTION_NUMBER 1
 '@T6G_MB_LIB.T6G(SCH_1):PAGE338_I89@PURE_QUANTA.Q_CAP(CHIPS)':
 C_PATH='@t6g_mb_lib.t6g(sch_1):page338_i89@pure_quanta.q_cap(chips)',
 P_PATH='@t6g_mb_lib.t6g(sch_1):page134_i89@pure_quanta.q_cap(chips)',
 PATH='I89',
 DRAWING='@T6G_MB_LIB.T6G(SCH_1):PAGE338',
 TOLERANCE='10%',
 MATERIAL='X6S',
 PHYS_PAGE='134',
 XY='(10125,11675)',
 ROT='0',
 VER='1',
 PACK_TYPE='C0805',
 LOCATION='PC2082',
 CDS_LIB='pure_quanta',
 CDS_PART_NAME='Q_CAP_C0805-10UF,16V,10%,X6S,CH6103KEA01',
 VOLTAGE='16V',
 PART_NUMBER='CH6103KEA01',
 VALUE='10UF',
 PRIM_FILE='./archive_libs/logical/q_cap/chips/chips.prt';

PART_NAME
 PC2085 'Q_CAP_C0402-1UF,25V,10%,X6S,CH5104KEB02':
 ROOM='NIC_P12V_MAM_TIC_BOM1';

SECTION_NUMBER 1
 '@T6G_MB_LIB.T6G(SCH_1):PAGE338_I55@PURE_QUANTA.Q_CAP(CHIPS)':
 C_PATH='@t6g_mb_lib.t6g(sch_1):page338_i55@pure_quanta.q_cap(chips)',
 P_PATH='@t6g_mb_lib.t6g(sch_1):page134_i55@pure_quanta.q_cap(chips)',
 PATH='I55',
 DRAWING='@T6G_MB_LIB.T6G(SCH_1):PAGE338',
 TOLERANCE='10%',
 MATERIAL='X6S',
 PHYS_PAGE='134',
 XY='(6350,11025)',
 ROT='0',
 VER='1',
 PACK_TYPE='C0402',
 LOCATION='PC2085',
 CDS_LIB='pure_quanta',
 CDS_PART_NAME='Q_CAP_C0402-1UF,25V,10%,X6S,CH5104KEB02',
 VOLTAGE='25V',
 ROOM='NIC_P12V_MAM_TIC_BOM1',
 PART_NUMBER='CH5104KEB02',
 VALUE='1UF',
 PRIM_FILE='./archive_libs/logical/q_cap/chips/chips.prt';

PART_NAME
 PC2086 'Q_CAP_C0402-1UF,25V,10%,X6S,CH5104KEB02':
 ROOM='NIC_P3V3_BOM1';

SECTION_NUMBER 1
 '@T6G_MB_LIB.T6G(SCH_1):PAGE338_I110@PURE_QUANTA.Q_CAP(CHIPS)':
 C_PATH='@t6g_mb_lib.t6g(sch_1):page338_i110@pure_quanta.q_cap(chips)',
 P_PATH='@t6g_mb_lib.t6g(sch_1):page134_i110@pure_quanta.q_cap(chips)',
 PATH='I110',
 DRAWING='@T6G_MB_LIB.T6G(SCH_1):PAGE338',
 TOLERANCE='10%',
 MATERIAL='X6S',
 PHYS_PAGE='134',
 XY='(6575,13075)',
 ROT='0',
 VER='1',
 PACK_TYPE='C0402',
 LOCATION='PC2086',
 CDS_LIB='pure_quanta',
 CDS_PART_NAME='Q_CAP_C0402-1UF,25V,10%,X6S,CH5104KEB02',
 VOLTAGE='25V',
 ROOM='NIC_P3V3_BOM1',
 PART_NUMBER='CH5104KEB02',
 VALUE='1UF',
 PRIM_FILE='./archive_libs/logical/q_cap/chips/chips.prt';

PART_NAME
 PC2087 'Q_CAP_C0402-1UF,25V,10%,X6S,CH5104KEB02':
 ROOM='NIC_P12V_MAM_TIC_BOM1';

SECTION_NUMBER 1
 '@T6G_MB_LIB.T6G(SCH_1):PAGE338_I54@PURE_QUANTA.Q_CAP(CHIPS)':
 C_PATH='@t6g_mb_lib.t6g(sch_1):page338_i54@pure_quanta.q_cap(chips)',
 P_PATH='@t6g_mb_lib.t6g(sch_1):page134_i54@pure_quanta.q_cap(chips)',
 PATH='I54',
 DRAWING='@T6G_MB_LIB.T6G(SCH_1):PAGE338',
 TOLERANCE='10%',
 MATERIAL='X6S',
 PHYS_PAGE='134',
 XY='(6575,10725)',
 ROT='1',
 VER='1',
 PACK_TYPE='C0402',
 LOCATION='PC2087',
 CDS_LIB='pure_quanta',
 CDS_PART_NAME='Q_CAP_C0402-1UF,25V,10%,X6S,CH5104KEB02',
 VOLTAGE='25V',
 ROOM='NIC_P12V_MAM_TIC_BOM1',
 PART_NUMBER='CH5104KEB02',
 VALUE='1UF',
 PRIM_FILE='./archive_libs/logical/q_cap/chips/chips.prt';

PART_NAME
 PC2088 'Q_CAP_C0402-0.01UF,50V,10%,EMPTY,CH31006KB18':
 ROOM='NIC_P12V_MAM_TIC_BOM1';

SECTION_NUMBER 1
 '@T6G_MB_LIB.T6G(SCH_1):PAGE338_I74@PURE_QUANTA.Q_CAP(CHIPS)':
 C_PATH='@t6g_mb_lib.t6g(sch_1):page338_i74@pure_quanta.q_cap(chips)',
 P_PATH='@t6g_mb_lib.t6g(sch_1):page134_i74@pure_quanta.q_cap(chips)',
 PATH='I74',
 DRAWING='@T6G_MB_LIB.T6G(SCH_1):PAGE338',
 TOLERANCE='10%',
 MATERIAL='EMPTY',
 PHYS_PAGE='134',
 XY='(8400,11050)',
 ROT='0',
 VER='1',
 PACK_TYPE='C0402',
 LOCATION='PC2088',
 CDS_LIB='pure_quanta',
 CDS_PART_NAME='Q_CAP_C0402-0.01UF,50V,10%,EMPTY,CH31006KB18',
 VOLTAGE='50V',
 ROOM='NIC_P12V_MAM_TIC_BOM1',
 PART_NUMBER='CH31006KB18',
 VALUE='0.01UF',
 PRIM_FILE='./archive_libs/logical/q_cap/chips/chips.prt';

PART_NAME
 PC2089 'Q_CAP_C0402-6800PF,50V,10%,X7R,CH2686K1B01':
 ROOM='NIC_P3V3_BOM1';

SECTION_NUMBER 1
 '@T6G_MB_LIB.T6G(SCH_1):PAGE338_I100@PURE_QUANTA.Q_CAP(CHIPS)':
 C_PATH='@t6g_mb_lib.t6g(sch_1):page338_i100@pure_quanta.q_cap(chips)',
 P_PATH='@t6g_mb_lib.t6g(sch_1):page134_i100@pure_quanta.q_cap(chips)',
 PATH='I100',
 DRAWING='@T6G_MB_LIB.T6G(SCH_1):PAGE338',
 TOLERANCE='10%',
 MATERIAL='X7R',
 PHYS_PAGE='134',
 XY='(9275,12875)',
 ROT='1',
 VER='1',
 PACK_TYPE='C0402',
 LOCATION='PC2089',
 CDS_LIB='pure_quanta',
 CDS_PART_NAME='Q_CAP_C0402-6800PF,50V,10%,X7R,CH2686K1B01',
 VOLTAGE='50V',
 ROOM='NIC_P3V3_BOM1',
 PART_NUMBER='CH2686K1B01',
 VALUE='6800PF',
 PRIM_FILE='./archive_libs/logical/q_cap/chips/chips.prt';

PART_NAME
 PC2091 'Q_CAP_0402-0.1UF,25V,10%,X7R,CH4104K1B00':;

SECTION_NUMBER 1
 '@T6G_MB_LIB.T6G(SCH_1):PAGE338_I104@PURE_QUANTA.Q_CAP(CHIPS)':
 C_PATH='@t6g_mb_lib.t6g(sch_1):page338_i104@pure_quanta.q_cap(chips)',
 P_PATH='@t6g_mb_lib.t6g(sch_1):page134_i104@pure_quanta.q_cap(chips)',
 PATH='I104',
 DRAWING='@T6G_MB_LIB.T6G(SCH_1):PAGE338',
 TOLERANCE='10%',
 MATERIAL='X7R',
 PHYS_PAGE='134',
 XY='(9550,13650)',
 ROT='0',
 VER='1',
 PACK_TYPE='0402',
 LOCATION='PC2091',
 CDS_LIB='pure_quanta',
 CDS_PART_NAME='Q_CAP_0402-0.1UF,25V,10%,X7R,CH4104K1B00',
 VOLTAGE='25V',
 PART_NUMBER='CH4104K1B00',
 VALUE='0.1UF',
 PRIM_FILE='./archive_libs/logical/q_cap/chips/chips.prt';

PART_NAME
 PC2092 'Q_CAP_0402-0.1UF,25V,10%,X7R,CH4104K1B00':;

SECTION_NUMBER 1
 '@T6G_MB_LIB.T6G(SCH_1):PAGE338_I86@PURE_QUANTA.Q_CAP(CHIPS)':
 C_PATH='@t6g_mb_lib.t6g(sch_1):page338_i86@pure_quanta.q_cap(chips)',
 P_PATH='@t6g_mb_lib.t6g(sch_1):page134_i86@pure_quanta.q_cap(chips)',
 PATH='I86',
 DRAWING='@T6G_MB_LIB.T6G(SCH_1):PAGE338',
 TOLERANCE='10%',
 MATERIAL='X7R',
 PHYS_PAGE='134',
 XY='(9300,11675)',
 ROT='0',
 VER='1',
 PACK_TYPE='0402',
 LOCATION='PC2092',
 CDS_LIB='pure_quanta',
 CDS_PART_NAME='Q_CAP_0402-0.1UF,25V,10%,X7R,CH4104K1B00',
 VOLTAGE='25V',
 PART_NUMBER='CH4104K1B00',
 VALUE='0.1UF',
 PRIM_FILE='./archive_libs/logical/q_cap/chips/chips.prt';

PART_NAME
 PC2093 'Q_CAP_C0402-1UF,25V,10%,X6S,CH5104KEB02':
 ROOM='NIC_P3V3_BOM1';

SECTION_NUMBER 1
 '@T6G_MB_LIB.T6G(SCH_1):PAGE338_I67@PURE_QUANTA.Q_CAP(CHIPS)':
 C_PATH='@t6g_mb_lib.t6g(sch_1):page338_i67@pure_quanta.q_cap(chips)',
 P_PATH='@t6g_mb_lib.t6g(sch_1):page134_i67@pure_quanta.q_cap(chips)',
 PATH='I67',
 DRAWING='@T6G_MB_LIB.T6G(SCH_1):PAGE338',
 TOLERANCE='10%',
 MATERIAL='X6S',
 PHYS_PAGE='134',
 XY='(6800,12775)',
 ROT='1',
 VER='1',
 PACK_TYPE='C0402',
 LOCATION='PC2093',
 CDS_LIB='pure_quanta',
 CDS_PART_NAME='Q_CAP_C0402-1UF,25V,10%,X6S,CH5104KEB02',
 VOLTAGE='25V',
 ROOM='NIC_P3V3_BOM1',
 PART_NUMBER='CH5104KEB02',
 VALUE='1UF',
 PRIM_FILE='./archive_libs/logical/q_cap/chips/chips.prt';

PART_NAME
 PC2098 'Q_CAP_C0402-1UF,25V,10%,X6S,CH5104KEB02':
 ROOM='NIC_P12V_MAM_TIC_BOM1';

SECTION_NUMBER 1
 '@T6G_MB_LIB.T6G(SCH_1):PAGE343_I65@PURE_QUANTA.Q_CAP(CHIPS)':
 C_PATH='@t6g_mb_lib.t6g(sch_1):page343_i65@pure_quanta.q_cap(chips)',
 P_PATH='@t6g_mb_lib.t6g(sch_1):page140_i65@pure_quanta.q_cap(chips)',
 PATH='I65',
 DRAWING='@T6G_MB_LIB.T6G(SCH_1):PAGE343',
 TOLERANCE='10%',
 MATERIAL='X6S',
 PHYS_PAGE='140',
 XY='(175,6600)',
 ROT='0',
 VER='1',
 PACK_TYPE='C0402',
 LOCATION='PC2098',
 CDS_LIB='pure_quanta',
 CDS_PART_NAME='Q_CAP_C0402-1UF,25V,10%,X6S,CH5104KEB02',
 VOLTAGE='25V',
 ROOM='NIC_P12V_MAM_TIC_BOM1',
 PART_NUMBER='CH5104KEB02',
 VALUE='1UF',
 PRIM_FILE='./archive_libs/logical/q_cap/chips/chips.prt';

PART_NAME
 PC2103 'Q_CAP_C0402-1UF,25V,10%,X6S,CH5104KEB02':
 ROOM='HSC BOM1';

SECTION_NUMBER 1
 '@T6G_MB_LIB.T6G(SCH_1):PAGE267_I50@PURE_QUANTA.Q_CAP(CHIPS)':
 C_PATH='@t6g_mb_lib.t6g(sch_1):page267_i50@pure_quanta.q_cap(chips)',
 P_PATH='@t6g_mb_lib.t6g(sch_1):page262_i50@pure_quanta.q_cap(chips)',
 PATH='I50',
 DRAWING='@T6G_MB_LIB.T6G(SCH_1):PAGE267',
 TOLERANCE='10%',
 MATERIAL='X6S',
 PHYS_PAGE='262',
 XY='(-13325,2175)',
 ROT='0',
 VER='1',
 PACK_TYPE='C0402',
 LOCATION='PC2103',
 CDS_LIB='pure_quanta',
 CDS_PART_NAME='Q_CAP_C0402-1UF,25V,10%,X6S,CH5104KEB02',
 VOLTAGE='25V',
 ROOM='HSC BOM1',
 PART_NUMBER='CH5104KEB02',
 VALUE='1UF',
 PRIM_FILE='./archive_libs/logical/q_cap/chips/chips.prt';

PART_NAME
 PC2137 'Q_CAP_0402-0.1UF,25V,10%,X7R,CH4104K1B00':;

SECTION_NUMBER 1
 '@T6G_MB_LIB.T6G(SCH_1):PAGE343_I108@PURE_QUANTA.Q_CAP(CHIPS)':
 C_PATH='@t6g_mb_lib.t6g(sch_1):page343_i108@pure_quanta.q_cap(chips)',
 P_PATH='@t6g_mb_lib.t6g(sch_1):page140_i108@pure_quanta.q_cap(chips)',
 PATH='I108',
 DRAWING='@T6G_MB_LIB.T6G(SCH_1):PAGE343',
 TOLERANCE='10%',
 MATERIAL='X7R',
 PHYS_PAGE='140',
 XY='(3300,9550)',
 ROT='0',
 VER='1',
 PACK_TYPE='0402',
 LOCATION='PC2137',
 CDS_LIB='pure_quanta',
 CDS_PART_NAME='Q_CAP_0402-0.1UF,25V,10%,X7R,CH4104K1B00',
 VOLTAGE='25V',
 PART_NUMBER='CH4104K1B00',
 VALUE='0.1UF',
 PRIM_FILE='./archive_libs/logical/q_cap/chips/chips.prt';

PART_NAME
 PC2139 'Q_CAP_C0402-1UF,25V,10%,X6S,CH5104KEB02':;

SECTION_NUMBER 1
 '@T6G_MB_LIB.T6G(SCH_1):PAGE343_I49@PURE_QUANTA.Q_CAP(CHIPS)':
 C_PATH='@t6g_mb_lib.t6g(sch_1):page343_i49@pure_quanta.q_cap(chips)',
 P_PATH='@t6g_mb_lib.t6g(sch_1):page140_i49@pure_quanta.q_cap(chips)',
 PATH='I49',
 DRAWING='@T6G_MB_LIB.T6G(SCH_1):PAGE343',
 TOLERANCE='10%',
 MATERIAL='X6S',
 PHYS_PAGE='140',
 XY='(-500,7025)',
 ROT='0',
 VER='1',
 PACK_TYPE='C0402',
 LOCATION='PC2139',
 CDS_LIB='pure_quanta',
 CDS_PART_NAME='Q_CAP_C0402-1UF,25V,10%,X6S,CH5104KEB02',
 VOLTAGE='25V',
 PART_NUMBER='CH5104KEB02',
 VALUE='1UF',
 PRIM_FILE='./archive_libs/logical/q_cap/chips/chips.prt';

PART_NAME
 PC2140 'Q_CAP_C0402-1UF,25V,10%,X6S,CH5104KEB02':;

SECTION_NUMBER 1
 '@T6G_MB_LIB.T6G(SCH_1):PAGE343_I55@PURE_QUANTA.Q_CAP(CHIPS)':
 C_PATH='@t6g_mb_lib.t6g(sch_1):page343_i55@pure_quanta.q_cap(chips)',
 P_PATH='@t6g_mb_lib.t6g(sch_1):page140_i55@pure_quanta.q_cap(chips)',
 PATH='I55',
 DRAWING='@T6G_MB_LIB.T6G(SCH_1):PAGE343',
 TOLERANCE='10%',
 MATERIAL='X6S',
 PHYS_PAGE='140',
 XY='(-375,9350)',
 ROT='0',
 VER='1',
 PACK_TYPE='C0402',
 LOCATION='PC2140',
 CDS_LIB='pure_quanta',
 CDS_PART_NAME='Q_CAP_C0402-1UF,25V,10%,X6S,CH5104KEB02',
 VOLTAGE='25V',
 PART_NUMBER='CH5104KEB02',
 VALUE='1UF',
 PRIM_FILE='./archive_libs/logical/q_cap/chips/chips.prt';

PART_NAME
 PC2141 'Q_CAP_C0805-22UF,16V,20%,X6S,CH6223MEA01':;

SECTION_NUMBER 1
 '@T6G_MB_LIB.T6G(SCH_1):PAGE343_I99@PURE_QUANTA.Q_CAP(CHIPS)':
 C_PATH='@t6g_mb_lib.t6g(sch_1):page343_i99@pure_quanta.q_cap(chips)',
 P_PATH='@t6g_mb_lib.t6g(sch_1):page140_i99@pure_quanta.q_cap(chips)',
 PATH='I99',
 DRAWING='@T6G_MB_LIB.T6G(SCH_1):PAGE343',
 TOLERANCE='20%',
 MATERIAL='X6S',
 PHYS_PAGE='140',
 XY='(3575,7225)',
 ROT='0',
 VER='1',
 PACK_TYPE='C0805',
 LOCATION='PC2141',
 CDS_LIB='pure_quanta',
 CDS_PART_NAME='Q_CAP_C0805-22UF,16V,20%,X6S,CH6223MEA01',
 VOLTAGE='16V',
 PART_NUMBER='CH6223MEA01',
 VALUE='22UF',
 PRIM_FILE='./archive_libs/logical/q_cap/chips/chips.prt';

PART_NAME
 PC2142 'Q_CAP_C0805-10UF,16V,10%,X6S,CH6103KEA01':;

SECTION_NUMBER 1
 '@T6G_MB_LIB.T6G(SCH_1):PAGE343_I112@PURE_QUANTA.Q_CAP(CHIPS)':
 C_PATH='@t6g_mb_lib.t6g(sch_1):page343_i112@pure_quanta.q_cap(chips)',
 P_PATH='@t6g_mb_lib.t6g(sch_1):page140_i112@pure_quanta.q_cap(chips)',
 PATH='I112',
 DRAWING='@T6G_MB_LIB.T6G(SCH_1):PAGE343',
 TOLERANCE='10%',
 MATERIAL='X6S',
 PHYS_PAGE='140',
 XY='(3875,9550)',
 ROT='0',
 VER='1',
 PACK_TYPE='C0805',
 LOCATION='PC2142',
 CDS_LIB='pure_quanta',
 CDS_PART_NAME='Q_CAP_C0805-10UF,16V,10%,X6S,CH6103KEA01',
 VOLTAGE='16V',
 PART_NUMBER='CH6103KEA01',
 VALUE='10UF',
 PRIM_FILE='./archive_libs/logical/q_cap/chips/chips.prt';

PART_NAME
 PC2143 'Q_CAP_C0805-10UF,16V,10%,X6S,CH6103KEA01':;

SECTION_NUMBER 1
 '@T6G_MB_LIB.T6G(SCH_1):PAGE343_I101@PURE_QUANTA.Q_CAP(CHIPS)':
 C_PATH='@t6g_mb_lib.t6g(sch_1):page343_i101@pure_quanta.q_cap(chips)',
 P_PATH='@t6g_mb_lib.t6g(sch_1):page140_i101@pure_quanta.q_cap(chips)',
 PATH='I101',
 DRAWING='@T6G_MB_LIB.T6G(SCH_1):PAGE343',
 TOLERANCE='10%',
 MATERIAL='X6S',
 PHYS_PAGE='140',
 XY='(3975,7225)',
 ROT='0',
 VER='1',
 PACK_TYPE='C0805',
 LOCATION='PC2143',
 CDS_LIB='pure_quanta',
 CDS_PART_NAME='Q_CAP_C0805-10UF,16V,10%,X6S,CH6103KEA01',
 VOLTAGE='16V',
 PART_NUMBER='CH6103KEA01',
 VALUE='10UF',
 PRIM_FILE='./archive_libs/logical/q_cap/chips/chips.prt';

PART_NAME
 PC2144 'Q_CAP_C0402-0.01UF,50V,10%,EMPTY,CH31006KB18':
 ROOM='NIC_P3V3_BOM1';

SECTION_NUMBER 1
 '@T6G_MB_LIB.T6G(SCH_1):PAGE338_I94@PURE_QUANTA.Q_CAP(CHIPS)':
 C_PATH='@t6g_mb_lib.t6g(sch_1):page338_i94@pure_quanta.q_cap(chips)',
 P_PATH='@t6g_mb_lib.t6g(sch_1):page134_i94@pure_quanta.q_cap(chips)',
 PATH='I94',
 DRAWING='@T6G_MB_LIB.T6G(SCH_1):PAGE338',
 TOLERANCE='10%',
 MATERIAL='EMPTY',
 PHYS_PAGE='134',
 XY='(8675,13100)',
 ROT='0',
 VER='1',
 PACK_TYPE='C0402',
 LOCATION='PC2144',
 CDS_LIB='pure_quanta',
 CDS_PART_NAME='Q_CAP_C0402-0.01UF,50V,10%,EMPTY,CH31006KB18',
 VOLTAGE='50V',
 ROOM='NIC_P3V3_BOM1',
 PART_NUMBER='CH31006KB18',
 VALUE='0.01UF',
 PRIM_FILE='./archive_libs/logical/q_cap/chips/chips.prt';

PART_NAME
 PC2146 'Q_CAP_C0402-1UF,25V,10%,X6S,CH5104KEB02':
 ROOM='NIC_P12V_MAM_TIC_BOM1';

SECTION_NUMBER 1
 '@T6G_MB_LIB.T6G(SCH_1):PAGE343_I66@PURE_QUANTA.Q_CAP(CHIPS)':
 C_PATH='@t6g_mb_lib.t6g(sch_1):page343_i66@pure_quanta.q_cap(chips)',
 P_PATH='@t6g_mb_lib.t6g(sch_1):page140_i66@pure_quanta.q_cap(chips)',
 PATH='I66',
 DRAWING='@T6G_MB_LIB.T6G(SCH_1):PAGE343',
 TOLERANCE='10%',
 MATERIAL='X6S',
 PHYS_PAGE='140',
 XY='(400,6300)',
 ROT='1',
 VER='1',
 PACK_TYPE='C0402',
 LOCATION='PC2146',
 CDS_LIB='pure_quanta',
 CDS_PART_NAME='Q_CAP_C0402-1UF,25V,10%,X6S,CH5104KEB02',
 VOLTAGE='25V',
 ROOM='NIC_P12V_MAM_TIC_BOM1',
 PART_NUMBER='CH5104KEB02',
 VALUE='1UF',
 PRIM_FILE='./archive_libs/logical/q_cap/chips/chips.prt';

PART_NAME
 PC2147 'Q_CAP_C0402-1UF,25V,10%,X6S,CH5104KEB02':
 ROOM='NIC_P3V3_BOM1';

SECTION_NUMBER 1
 '@T6G_MB_LIB.T6G(SCH_1):PAGE343_I86@PURE_QUANTA.Q_CAP(CHIPS)':
 C_PATH='@t6g_mb_lib.t6g(sch_1):page343_i86@pure_quanta.q_cap(chips)',
 P_PATH='@t6g_mb_lib.t6g(sch_1):page140_i86@pure_quanta.q_cap(chips)',
 PATH='I86',
 DRAWING='@T6G_MB_LIB.T6G(SCH_1):PAGE343',
 TOLERANCE='10%',
 MATERIAL='X6S',
 PHYS_PAGE='140',
 XY='(525,8625)',
 ROT='1',
 VER='1',
 PACK_TYPE='C0402',
 LOCATION='PC2147',
 CDS_LIB='pure_quanta',
 CDS_PART_NAME='Q_CAP_C0402-1UF,25V,10%,X6S,CH5104KEB02',
 VOLTAGE='25V',
 ROOM='NIC_P3V3_BOM1',
 PART_NUMBER='CH5104KEB02',
 VALUE='1UF',
 PRIM_FILE='./archive_libs/logical/q_cap/chips/chips.prt';

PART_NAME
 PC2149 'Q_CAP_C0402-0.01UF,50V,10%,EMPTY,CH31006KB18':
 ROOM='NIC_P3V3_BOM1';

SECTION_NUMBER 1
 '@T6G_MB_LIB.T6G(SCH_1):PAGE343_I104@PURE_QUANTA.Q_CAP(CHIPS)':
 C_PATH='@t6g_mb_lib.t6g(sch_1):page343_i104@pure_quanta.q_cap(chips)',
 P_PATH='@t6g_mb_lib.t6g(sch_1):page140_i104@pure_quanta.q_cap(chips)',
 PATH='I104',
 DRAWING='@T6G_MB_LIB.T6G(SCH_1):PAGE343',
 TOLERANCE='10%',
 MATERIAL='EMPTY',
 PHYS_PAGE='140',
 XY='(2400,8950)',
 ROT='0',
 VER='1',
 PACK_TYPE='C0402',
 LOCATION='PC2149',
 CDS_LIB='pure_quanta',
 CDS_PART_NAME='Q_CAP_C0402-0.01UF,50V,10%,EMPTY,CH31006KB18',
 VOLTAGE='50V',
 ROOM='NIC_P3V3_BOM1',
 PART_NUMBER='CH31006KB18',
 VALUE='0.01UF',
 PRIM_FILE='./archive_libs/logical/q_cap/chips/chips.prt';

PART_NAME
 PC2150 'Q_CAP_C0402-3900PF,50V,10%,X7R,CH23906KB14':
 ROOM='NIC_P12V_MAM_TIC_BOM1';

SECTION_NUMBER 1
 '@T6G_MB_LIB.T6G(SCH_1):PAGE343_I75@PURE_QUANTA.Q_CAP(CHIPS)':
 C_PATH='@t6g_mb_lib.t6g(sch_1):page343_i75@pure_quanta.q_cap(chips)',
 P_PATH='@t6g_mb_lib.t6g(sch_1):page140_i75@pure_quanta.q_cap(chips)',
 PATH='I75',
 DRAWING='@T6G_MB_LIB.T6G(SCH_1):PAGE343',
 TOLERANCE='10%',
 MATERIAL='X7R',
 PHYS_PAGE='140',
 XY='(2850,6400)',
 ROT='1',
 VER='1',
 PACK_TYPE='C0402',
 LOCATION='PC2150',
 CDS_LIB='pure_quanta',
 CDS_PART_NAME='Q_CAP_C0402-3900PF,50V,10%,X7R,CH23906KB14',
 VOLTAGE='50V',
 ROOM='NIC_P12V_MAM_TIC_BOM1',
 PART_NUMBER='CH23906KB14',
 VALUE='3900PF',
 PRIM_FILE='./archive_libs/logical/q_cap/chips/chips.prt';

PART_NAME
 PC2151 'Q_CAP_C0402-6800PF,50V,10%,X7R,CH2686K1B01':
 ROOM='NIC_P3V3_BOM1';

SECTION_NUMBER 1
 '@T6G_MB_LIB.T6G(SCH_1):PAGE343_I95@PURE_QUANTA.Q_CAP(CHIPS)':
 C_PATH='@t6g_mb_lib.t6g(sch_1):page343_i95@pure_quanta.q_cap(chips)',
 P_PATH='@t6g_mb_lib.t6g(sch_1):page140_i95@pure_quanta.q_cap(chips)',
 PATH='I95',
 DRAWING='@T6G_MB_LIB.T6G(SCH_1):PAGE343',
 TOLERANCE='10%',
 MATERIAL='X7R',
 PHYS_PAGE='140',
 XY='(3000,8725)',
 ROT='1',
 VER='1',
 PACK_TYPE='C0402',
 LOCATION='PC2151',
 CDS_LIB='pure_quanta',
 CDS_PART_NAME='Q_CAP_C0402-6800PF,50V,10%,X7R,CH2686K1B01',
 VOLTAGE='50V',
 ROOM='NIC_P3V3_BOM1',
 PART_NUMBER='CH2686K1B01',
 VALUE='6800PF',
 PRIM_FILE='./archive_libs/logical/q_cap/chips/chips.prt';

PART_NAME
 PC2152 'Q_CAP_0402-0.1UF,25V,10%,X7R,CH4104K1B00':;

SECTION_NUMBER 1
 '@T6G_MB_LIB.T6G(SCH_1):PAGE343_I97@PURE_QUANTA.Q_CAP(CHIPS)':
 C_PATH='@t6g_mb_lib.t6g(sch_1):page343_i97@pure_quanta.q_cap(chips)',
 P_PATH='@t6g_mb_lib.t6g(sch_1):page140_i97@pure_quanta.q_cap(chips)',
 PATH='I97',
 DRAWING='@T6G_MB_LIB.T6G(SCH_1):PAGE343',
 TOLERANCE='10%',
 MATERIAL='X7R',
 PHYS_PAGE='140',
 XY='(3150,7225)',
 ROT='0',
 VER='1',
 PACK_TYPE='0402',
 LOCATION='PC2152',
 CDS_LIB='pure_quanta',
 CDS_PART_NAME='Q_CAP_0402-0.1UF,25V,10%,X7R,CH4104K1B00',
 VOLTAGE='25V',
 PART_NUMBER='CH4104K1B00',
 VALUE='0.1UF',
 PRIM_FILE='./archive_libs/logical/q_cap/chips/chips.prt';

PART_NAME
 PC2153 'Q_CAP_0402-0.22UF,16V,10%,X7R,CH4223K1B00':
 ROOM='NIC_P12V_MPS_MAM_BOM2';

SECTION_NUMBER 1
 '@T6G_MB_LIB.T6G(SCH_1):PAGE339_I60@PURE_QUANTA.Q_CAP(CHIPS)':
 C_PATH='@t6g_mb_lib.t6g(sch_1):page339_i60@pure_quanta.q_cap(chips)',
 P_PATH='@t6g_mb_lib.t6g(sch_1):page135_i60@pure_quanta.q_cap(chips)',
 PATH='I60',
 DRAWING='@T6G_MB_LIB.T6G(SCH_1):PAGE339',
 TOLERANCE='10%',
 MATERIAL='X7R',
 PHYS_PAGE='135',
 XY='(-8025,9150)',
 ROT='0',
 VER='1',
 PACK_TYPE='0402',
 LOCATION='PC2153',
 CDS_LIB='pure_quanta',
 CDS_PART_NAME='Q_CAP_0402-0.22UF,16V,10%,X7R,CH4223K1B00',
 VOLTAGE='16V',
 ROOM='NIC_P12V_MPS_MAM_BOM2',
 PART_NUMBER='CH4223K1B00',
 VALUE='0.22UF',
 PRIM_FILE='./archive_libs/logical/q_cap/chips/chips.prt';

PART_NAME
 PC2154 'Q_CAP_C0402-1UF,25V,10%,X6S,CH5104KEB02':
 ROOM='NIC_P12V_MPS_MAM_BOM2';

SECTION_NUMBER 1
 '@T6G_MB_LIB.T6G(SCH_1):PAGE339_I68@PURE_QUANTA.Q_CAP(CHIPS)':
 C_PATH='@t6g_mb_lib.t6g(sch_1):page339_i68@pure_quanta.q_cap(chips)',
 P_PATH='@t6g_mb_lib.t6g(sch_1):page135_i68@pure_quanta.q_cap(chips)',
 PATH='I68',
 DRAWING='@T6G_MB_LIB.T6G(SCH_1):PAGE339',
 TOLERANCE='10%',
 MATERIAL='X6S',
 PHYS_PAGE='135',
 XY='(-7275,10000)',
 ROT='0',
 VER='1',
 PACK_TYPE='C0402',
 LOCATION='PC2154',
 CDS_LIB='pure_quanta',
 CDS_PART_NAME='Q_CAP_C0402-1UF,25V,10%,X6S,CH5104KEB02',
 VOLTAGE='25V',
 ROOM='NIC_P12V_MPS_MAM_BOM2',
 PART_NUMBER='CH5104KEB02',
 VALUE='1UF',
 PRIM_FILE='./archive_libs/logical/q_cap/chips/chips.prt';

PART_NAME
 PC2155 'Q_CAP_C0402-0.047UF,25V,10%,X7R,CH3474K1B04':
 ROOM='NIC_P12V_MPS_MAM_BOM2';

SECTION_NUMBER 1
 '@T6G_MB_LIB.T6G(SCH_1):PAGE339_I64@PURE_QUANTA.Q_CAP(CHIPS)':
 C_PATH='@t6g_mb_lib.t6g(sch_1):page339_i64@pure_quanta.q_cap(chips)',
 P_PATH='@t6g_mb_lib.t6g(sch_1):page135_i64@pure_quanta.q_cap(chips)',
 PATH='I64',
 DRAWING='@T6G_MB_LIB.T6G(SCH_1):PAGE339',
 TOLERANCE='10%',
 MATERIAL='X7R',
 PHYS_PAGE='135',
 XY='(-7200,8925)',
 ROT='0',
 VER='1',
 PACK_TYPE='C0402',
 LOCATION='PC2155',
 CDS_LIB='pure_quanta',
 CDS_PART_NAME='Q_CAP_C0402-0.047UF,25V,10%,X7R,CH3474K1B04',
 VOLTAGE='25V',
 ROOM='NIC_P12V_MPS_MAM_BOM2',
 PART_NUMBER='CH3474K1B04',
 VALUE='0.047UF',
 PRIM_FILE='./archive_libs/logical/q_cap/chips/chips.prt';

PART_NAME
 PC2156 'Q_CAP_C0402-100NF,50V,10%,X7R,CH4106K1B01':
 ROOM='NIC_P12V_MPS_MAM_BOM2';

SECTION_NUMBER 1
 '@T6G_MB_LIB.T6G(SCH_1):PAGE339_I73@PURE_QUANTA.Q_CAP(CHIPS)':
 C_PATH='@t6g_mb_lib.t6g(sch_1):page339_i73@pure_quanta.q_cap(chips)',
 P_PATH='@t6g_mb_lib.t6g(sch_1):page135_i73@pure_quanta.q_cap(chips)',
 PATH='I73',
 DRAWING='@T6G_MB_LIB.T6G(SCH_1):PAGE339',
 TOLERANCE='10%',
 MATERIAL='X7R',
 PHYS_PAGE='135',
 XY='(-5325,8725)',
 ROT='0',
 VER='1',
 PACK_TYPE='C0402',
 LOCATION='PC2156',
 CDS_LIB='pure_quanta',
 CDS_PART_NAME='Q_CAP_C0402-100NF,50V,10%,X7R,CH4106K1B01',
 VOLTAGE='50V',
 ROOM='NIC_P12V_MPS_MAM_BOM2',
 PART_NUMBER='CH4106K1B01',
 VALUE='100NF',
 PRIM_FILE='./archive_libs/logical/q_cap/chips/chips.prt';

PART_NAME
 PC2157 'Q_CAP_0402-39PF,50V,5%,NPO,CH03906JB06':
 ROOM='NIC_P3V3_BOM2';

SECTION_NUMBER 1
 '@T6G_MB_LIB.T6G(SCH_1):PAGE339_I98@PURE_QUANTA.Q_CAP(CHIPS)':
 C_PATH='@t6g_mb_lib.t6g(sch_1):page339_i98@pure_quanta.q_cap(chips)',
 P_PATH='@t6g_mb_lib.t6g(sch_1):page135_i98@pure_quanta.q_cap(chips)',
 PATH='I98',
 DRAWING='@T6G_MB_LIB.T6G(SCH_1):PAGE339',
 TOLERANCE='5%',
 MATERIAL='NPO',
 PHYS_PAGE='135',
 XY='(-4450,12275)',
 ROT='0',
 VER='1',
 PACK_TYPE='0402',
 LOCATION='PC2157',
 CDS_LIB='pure_quanta',
 CDS_PART_NAME='Q_CAP_0402-39PF,50V,5%,NPO,CH03906JB06',
 VOLTAGE='50V',
 ROOM='NIC_P3V3_BOM2',
 PART_NUMBER='CH03906JB06',
 VALUE='39PF',
 PRIM_FILE='./archive_libs/logical/q_cap/chips/chips.prt';

PART_NAME
 PC2158 'Q_CAP_C0603-2.2UF,16V,20%,X7R,CH5223M1900':
 ROOM='NIC_P12V_MPS_MAM_BOM2';

SECTION_NUMBER 1
 '@T6G_MB_LIB.T6G(SCH_1):PAGE339_I86@PURE_QUANTA.Q_CAP(CHIPS)':
 C_PATH='@t6g_mb_lib.t6g(sch_1):page339_i86@pure_quanta.q_cap(chips)',
 P_PATH='@t6g_mb_lib.t6g(sch_1):page135_i86@pure_quanta.q_cap(chips)',
 PATH='I86',
 DRAWING='@T6G_MB_LIB.T6G(SCH_1):PAGE339',
 TOLERANCE='20%',
 MATERIAL='X7R',
 PHYS_PAGE='135',
 XY='(-3875,9075)',
 ROT='0',
 VER='1',
 PACK_TYPE='C0603',
 LOCATION='PC2158',
 CDS_LIB='pure_quanta',
 CDS_PART_NAME='Q_CAP_C0603-2.2UF,16V,20%,X7R,CH5223M1900',
 VOLTAGE='16V',
 ROOM='NIC_P12V_MPS_MAM_BOM2',
 PART_NUMBER='CH5223M1900',
 VALUE='2.2UF',
 PRIM_FILE='./archive_libs/logical/q_cap/chips/chips.prt';

PART_NAME
 PC2159 'Q_CAP_C0402-1UF,25V,10%,X6S,CH5104KEB02':
 ROOM='NIC_P3V3_BOM2';

SECTION_NUMBER 1
 '@T6G_MB_LIB.T6G(SCH_1):PAGE339_I111@PURE_QUANTA.Q_CAP(CHIPS)':
 C_PATH='@t6g_mb_lib.t6g(sch_1):page339_i111@pure_quanta.q_cap(chips)',
 P_PATH='@t6g_mb_lib.t6g(sch_1):page135_i111@pure_quanta.q_cap(chips)',
 PATH='I111',
 DRAWING='@T6G_MB_LIB.T6G(SCH_1):PAGE339',
 TOLERANCE='10%',
 MATERIAL='X6S',
 PHYS_PAGE='135',
 XY='(-3400,12850)',
 ROT='0',
 VER='1',
 PACK_TYPE='C0402',
 LOCATION='PC2159',
 CDS_LIB='pure_quanta',
 CDS_PART_NAME='Q_CAP_C0402-1UF,25V,10%,X6S,CH5104KEB02',
 VOLTAGE='25V',
 ROOM='NIC_P3V3_BOM2',
 PART_NUMBER='CH5104KEB02',
 VALUE='1UF',
 PRIM_FILE='./archive_libs/logical/q_cap/chips/chips.prt';

PART_NAME
 PC2160 'Q_CAP_0402-0.1UF,25V,10%,X7R,CH4104K1B00':
 ROOM='NIC_P12V_MPS_MAM_BOM2';

SECTION_NUMBER 1
 '@T6G_MB_LIB.T6G(SCH_1):PAGE339_I91@PURE_QUANTA.Q_CAP(CHIPS)':
 C_PATH='@t6g_mb_lib.t6g(sch_1):page339_i91@pure_quanta.q_cap(chips)',
 P_PATH='@t6g_mb_lib.t6g(sch_1):page135_i91@pure_quanta.q_cap(chips)',
 PATH='I91',
 DRAWING='@T6G_MB_LIB.T6G(SCH_1):PAGE339',
 TOLERANCE='10%',
 MATERIAL='X7R',
 PHYS_PAGE='135',
 XY='(-3525,9925)',
 ROT='2',
 VER='1',
 PACK_TYPE='0402',
 LOCATION='PC2160',
 CDS_LIB='pure_quanta',
 CDS_PART_NAME='Q_CAP_0402-0.1UF,25V,10%,X7R,CH4104K1B00',
 VOLTAGE='25V',
 ROOM='NIC_P12V_MPS_MAM_BOM2',
 PART_NUMBER='CH4104K1B00',
 VALUE='0.1UF',
 PRIM_FILE='./archive_libs/logical/q_cap/chips/chips.prt';

PART_NAME
 PC2161 'Q_CAP_0402-0.068UF,16V,10%,X7R,CH3683K1B09':
 ROOM='NIC_P3V3_BOM2';

SECTION_NUMBER 1
 '@T6G_MB_LIB.T6G(SCH_1):PAGE339_I104@PURE_QUANTA.Q_CAP(CHIPS)':
 C_PATH='@t6g_mb_lib.t6g(sch_1):page339_i104@pure_quanta.q_cap(chips)',
 P_PATH='@t6g_mb_lib.t6g(sch_1):page135_i104@pure_quanta.q_cap(chips)',
 PATH='I104',
 DRAWING='@T6G_MB_LIB.T6G(SCH_1):PAGE339',
 TOLERANCE='10%',
 MATERIAL='X7R',
 PHYS_PAGE='135',
 XY='(-3050,12200)',
 ROT='0',
 VER='1',
 PACK_TYPE='0402',
 LOCATION='PC2161',
 CDS_LIB='pure_quanta',
 CDS_PART_NAME='Q_CAP_0402-0.068UF,16V,10%,X7R,CH3683K1B09',
 VOLTAGE='16V',
 ROOM='NIC_P3V3_BOM2',
 PART_NUMBER='CH3683K1B09',
 VALUE='0.068UF',
 PRIM_FILE='./archive_libs/logical/q_cap/chips/chips.prt';

PART_NAME
 PC2162 'Q_CAP_0402-100PF,50V,5%,X7R,CH11006JB18':
 ROOM='NIC_P3V3_BOM2';

SECTION_NUMBER 1
 '@T6G_MB_LIB.T6G(SCH_1):PAGE339_I106@PURE_QUANTA.Q_CAP(CHIPS)':
 C_PATH='@t6g_mb_lib.t6g(sch_1):page339_i106@pure_quanta.q_cap(chips)',
 P_PATH='@t6g_mb_lib.t6g(sch_1):page135_i106@pure_quanta.q_cap(chips)',
 PATH='I106',
 DRAWING='@T6G_MB_LIB.T6G(SCH_1):PAGE339',
 TOLERANCE='5%',
 MATERIAL='X7R',
 PHYS_PAGE='135',
 XY='(-1550,12125)',
 ROT='0',
 VER='1',
 PACK_TYPE='0402',
 LOCATION='PC2162',
 CDS_LIB='pure_quanta',
 CDS_PART_NAME='Q_CAP_0402-100PF,50V,5%,X7R,CH11006JB18',
 VOLTAGE='50V',
 ROOM='NIC_P3V3_BOM2',
 PART_NUMBER='CH11006JB18',
 VALUE='100PF',
 PRIM_FILE='./archive_libs/logical/q_cap/chips/chips.prt';

PART_NAME
 PC2163 'Q_CAP_C0805-10UF,16V,10%,X6S,CH6103KEA01':
 ROOM='NIC_P3V3_BOM2';

SECTION_NUMBER 1
 '@T6G_MB_LIB.T6G(SCH_1):PAGE339_I108@PURE_QUANTA.Q_CAP(CHIPS)':
 C_PATH='@t6g_mb_lib.t6g(sch_1):page339_i108@pure_quanta.q_cap(chips)',
 P_PATH='@t6g_mb_lib.t6g(sch_1):page135_i108@pure_quanta.q_cap(chips)',
 PATH='I108',
 DRAWING='@T6G_MB_LIB.T6G(SCH_1):PAGE339',
 TOLERANCE='10%',
 MATERIAL='X6S',
 PHYS_PAGE='135',
 XY='(-950,12350)',
 ROT='0',
 VER='1',
 PACK_TYPE='C0805',
 LOCATION='PC2163',
 CDS_LIB='pure_quanta',
 CDS_PART_NAME='Q_CAP_C0805-10UF,16V,10%,X6S,CH6103KEA01',
 VOLTAGE='16V',
 ROOM='NIC_P3V3_BOM2',
 PART_NUMBER='CH6103KEA01',
 VALUE='10UF',
 PRIM_FILE='./archive_libs/logical/q_cap/chips/chips.prt';

PART_NAME
 PC2164 'Q_CAP_0402-0.22UF,16V,10%,X7R,CH4223K1B00':
 ROOM='NIC_P12V_MPS_MAM_BOM2';

SECTION_NUMBER 1
 '@T6G_MB_LIB.T6G(SCH_1):PAGE344_I2@PURE_QUANTA.Q_CAP(CHIPS)':
 C_PATH='@t6g_mb_lib.t6g(sch_1):page344_i2@pure_quanta.q_cap(chips)',
 P_PATH='@t6g_mb_lib.t6g(sch_1):page141_i2@pure_quanta.q_cap(chips)',
 PATH='I2',
 DRAWING='@T6G_MB_LIB.T6G(SCH_1):PAGE344',
 TOLERANCE='10%',
 MATERIAL='X7R',
 PHYS_PAGE='141',
 XY='(-3600,2600)',
 ROT='0',
 VER='1',
 PACK_TYPE='0402',
 LOCATION='PC2164',
 CDS_LIB='pure_quanta',
 CDS_PART_NAME='Q_CAP_0402-0.22UF,16V,10%,X7R,CH4223K1B00',
 VOLTAGE='16V',
 ROOM='NIC_P12V_MPS_MAM_BOM2',
 PART_NUMBER='CH4223K1B00',
 VALUE='0.22UF',
 PRIM_FILE='./archive_libs/logical/q_cap/chips/chips.prt';

PART_NAME
 PC2165 'Q_CAP_C0402-1UF,25V,10%,X6S,CH5104KEB02':
 ROOM='NIC_P12V_MPS_MAM_BOM2';

SECTION_NUMBER 1
 '@T6G_MB_LIB.T6G(SCH_1):PAGE344_I13@PURE_QUANTA.Q_CAP(CHIPS)':
 C_PATH='@t6g_mb_lib.t6g(sch_1):page344_i13@pure_quanta.q_cap(chips)',
 P_PATH='@t6g_mb_lib.t6g(sch_1):page141_i13@pure_quanta.q_cap(chips)',
 PATH='I13',
 DRAWING='@T6G_MB_LIB.T6G(SCH_1):PAGE344',
 TOLERANCE='10%',
 MATERIAL='X6S',
 PHYS_PAGE='141',
 XY='(-2925,3550)',
 ROT='0',
 VER='1',
 PACK_TYPE='C0402',
 LOCATION='PC2165',
 CDS_LIB='pure_quanta',
 CDS_PART_NAME='Q_CAP_C0402-1UF,25V,10%,X6S,CH5104KEB02',
 VOLTAGE='25V',
 ROOM='NIC_P12V_MPS_MAM_BOM2',
 PART_NUMBER='CH5104KEB02',
 VALUE='1UF',
 PRIM_FILE='./archive_libs/logical/q_cap/chips/chips.prt';

PART_NAME
 PC2166 'Q_CAP_C0402-0.047UF,25V,10%,X7R,CH3474K1B04':
 ROOM='NIC_P12V_MPS_MAM_BOM2';

SECTION_NUMBER 1
 '@T6G_MB_LIB.T6G(SCH_1):PAGE344_I6@PURE_QUANTA.Q_CAP(CHIPS)':
 C_PATH='@t6g_mb_lib.t6g(sch_1):page344_i6@pure_quanta.q_cap(chips)',
 P_PATH='@t6g_mb_lib.t6g(sch_1):page141_i6@pure_quanta.q_cap(chips)',
 PATH='I6',
 DRAWING='@T6G_MB_LIB.T6G(SCH_1):PAGE344',
 TOLERANCE='10%',
 MATERIAL='X7R',
 PHYS_PAGE='141',
 XY='(-2755,2383)',
 ROT='0',
 VER='1',
 PACK_TYPE='C0402',
 LOCATION='PC2166',
 CDS_LIB='pure_quanta',
 CDS_PART_NAME='Q_CAP_C0402-0.047UF,25V,10%,X7R,CH3474K1B04',
 VOLTAGE='25V',
 ROOM='NIC_P12V_MPS_MAM_BOM2',
 PART_NUMBER='CH3474K1B04',
 VALUE='0.047UF',
 PRIM_FILE='./archive_libs/logical/q_cap/chips/chips.prt';

PART_NAME
 PC2167 'Q_CAP_0402-100PF,50V,5%,NPO,CH11006JB00':
 ROOM='NIC_P12V_MPS_MAM_BOM2';

SECTION_NUMBER 1
 '@T6G_MB_LIB.T6G(SCH_1):PAGE344_I58@PURE_QUANTA.Q_CAP(CHIPS)':
 C_PATH='@t6g_mb_lib.t6g(sch_1):page344_i58@pure_quanta.q_cap(chips)',
 P_PATH='@t6g_mb_lib.t6g(sch_1):page141_i58@pure_quanta.q_cap(chips)',
 PATH='I58',
 DRAWING='@T6G_MB_LIB.T6G(SCH_1):PAGE344',
 TOLERANCE='5%',
 MATERIAL='NPO',
 PHYS_PAGE='141',
 XY='(-975,2200)',
 ROT='0',
 VER='1',
 PACK_TYPE='0402',
 LOCATION='PC2167',
 CDS_LIB='pure_quanta',
 CDS_PART_NAME='Q_CAP_0402-100PF,50V,5%,NPO,CH11006JB00',
 VOLTAGE='50V',
 ROOM='NIC_P12V_MPS_MAM_BOM2',
 PART_NUMBER='CH11006JB00',
 VALUE='100PF',
 PRIM_FILE='./archive_libs/logical/q_cap/chips/chips.prt';

PART_NAME
 PC2168 'Q_CAP_0402-39PF,50V,5%,NPO,CH03906JB06':
 ROOM='NIC_P3V3_BOM2';

SECTION_NUMBER 1
 '@T6G_MB_LIB.T6G(SCH_1):PAGE344_I35@PURE_QUANTA.Q_CAP(CHIPS)':
 C_PATH='@t6g_mb_lib.t6g(sch_1):page344_i35@pure_quanta.q_cap(chips)',
 P_PATH='@t6g_mb_lib.t6g(sch_1):page141_i35@pure_quanta.q_cap(chips)',
 PATH='I35',
 DRAWING='@T6G_MB_LIB.T6G(SCH_1):PAGE344',
 TOLERANCE='5%',
 MATERIAL='NPO',
 PHYS_PAGE='141',
 XY='(-250,6175)',
 ROT='0',
 VER='1',
 PACK_TYPE='0402',
 LOCATION='PC2168',
 CDS_LIB='pure_quanta',
 CDS_PART_NAME='Q_CAP_0402-39PF,50V,5%,NPO,CH03906JB06',
 VOLTAGE='50V',
 ROOM='NIC_P3V3_BOM2',
 PART_NUMBER='CH03906JB06',
 VALUE='39PF',
 PRIM_FILE='./archive_libs/logical/q_cap/chips/chips.prt';

PART_NAME
 PC2169 'Q_CAP_C0402-1UF,25V,10%,X6S,CH5104KEB02':
 ROOM='NIC_P3V3_BOM2';

SECTION_NUMBER 1
 '@T6G_MB_LIB.T6G(SCH_1):PAGE344_I48@PURE_QUANTA.Q_CAP(CHIPS)':
 C_PATH='@t6g_mb_lib.t6g(sch_1):page344_i48@pure_quanta.q_cap(chips)',
 P_PATH='@t6g_mb_lib.t6g(sch_1):page141_i48@pure_quanta.q_cap(chips)',
 PATH='I48',
 DRAWING='@T6G_MB_LIB.T6G(SCH_1):PAGE344',
 TOLERANCE='10%',
 MATERIAL='X6S',
 PHYS_PAGE='141',
 XY='(750,6750)',
 ROT='0',
 VER='1',
 PACK_TYPE='C0402',
 LOCATION='PC2169',
 CDS_LIB='pure_quanta',
 CDS_PART_NAME='Q_CAP_C0402-1UF,25V,10%,X6S,CH5104KEB02',
 VOLTAGE='25V',
 ROOM='NIC_P3V3_BOM2',
 PART_NUMBER='CH5104KEB02',
 VALUE='1UF',
 PRIM_FILE='./archive_libs/logical/q_cap/chips/chips.prt';

PART_NAME
 PC2173 'Q_CAP_C0805-10UF,16V,10%,X6S,CH6103KEA01':
 ROOM='NIC_P3V3_BOM2';

SECTION_NUMBER 1
 '@T6G_MB_LIB.T6G(SCH_1):PAGE344_I56@PURE_QUANTA.Q_CAP(CHIPS)':
 C_PATH='@t6g_mb_lib.t6g(sch_1):page344_i56@pure_quanta.q_cap(chips)',
 P_PATH='@t6g_mb_lib.t6g(sch_1):page141_i56@pure_quanta.q_cap(chips)',
 PATH='I56',
 DRAWING='@T6G_MB_LIB.T6G(SCH_1):PAGE344',
 TOLERANCE='10%',
 MATERIAL='X6S',
 PHYS_PAGE='141',
 XY='(2900,6350)',
 ROT='0',
 VER='1',
 PACK_TYPE='C0805',
 LOCATION='PC2173',
 CDS_LIB='pure_quanta',
 CDS_PART_NAME='Q_CAP_C0805-10UF,16V,10%,X6S,CH6103KEA01',
 VOLTAGE='16V',
 ROOM='NIC_P3V3_BOM2',
 PART_NUMBER='CH6103KEA01',
 VALUE='10UF',
 PRIM_FILE='./archive_libs/logical/q_cap/chips/chips.prt';

PART_NAME
 PC2174 'Q_CAP_0402-0.1UF,25V,10%,X7R,CH4104K1B00':
 ROOM='NIC_P12V_MPS_MAM_BOM2';

SECTION_NUMBER 1
 '@T6G_MB_LIB.T6G(SCH_1):PAGE344_I40@PURE_QUANTA.Q_CAP(CHIPS)':
 C_PATH='@t6g_mb_lib.t6g(sch_1):page344_i40@pure_quanta.q_cap(chips)',
 P_PATH='@t6g_mb_lib.t6g(sch_1):page141_i40@pure_quanta.q_cap(chips)',
 PATH='I40',
 DRAWING='@T6G_MB_LIB.T6G(SCH_1):PAGE344',
 TOLERANCE='10%',
 MATERIAL='X7R',
 PHYS_PAGE='141',
 XY='(1050,3200)',
 ROT='2',
 VER='1',
 PACK_TYPE='0402',
 LOCATION='PC2174',
 CDS_LIB='pure_quanta',
 CDS_PART_NAME='Q_CAP_0402-0.1UF,25V,10%,X7R,CH4104K1B00',
 VOLTAGE='25V',
 ROOM='NIC_P12V_MPS_MAM_BOM2',
 PART_NUMBER='CH4104K1B00',
 VALUE='0.1UF',
 PRIM_FILE='./archive_libs/logical/q_cap/chips/chips.prt';

PART_NAME
 PC2181 'Q_CAP_C0402-1UF,25V,10%,X6S,CH5104KEB02':
 ROOM='HSC BOM1';

SECTION_NUMBER 1
 '@T6G_MB_LIB.T6G(SCH_1):PAGE301_I4@PURE_QUANTA.Q_CAP(CHIPS)':
 C_PATH='@t6g_mb_lib.t6g(sch_1):page301_i4@pure_quanta.q_cap(chips)',
 P_PATH='@t6g_mb_lib.t6g(sch_1):page263_i4@pure_quanta.q_cap(chips)',
 PATH='I4',
 DRAWING='@T6G_MB_LIB.T6G(SCH_1):PAGE301',
 TOLERANCE='10%',
 MATERIAL='X6S',
 PHYS_PAGE='263',
 XY='(-3475,-1425)',
 ROT='0',
 VER='1',
 PACK_TYPE='C0402',
 LOCATION='PC2181',
 CDS_LIB='pure_quanta',
 CDS_PART_NAME='Q_CAP_C0402-1UF,25V,10%,X6S,CH5104KEB02',
 VOLTAGE='25V',
 ROOM='HSC BOM1',
 PART_NUMBER='CH5104KEB02',
 VALUE='1UF',
 PRIM_FILE='./archive_libs/logical/q_cap/chips/chips.prt';

PART_NAME
 PC2182 'Q_CAP_0402-220PF,50V,10%,X7R,TMP_QCH12206KB14':
 ROOM='HSC BOM1';

SECTION_NUMBER 1
 '@T6G_MB_LIB.T6G(SCH_1):PAGE301_I24@PURE_QUANTA.Q_CAP(CHIPS)':
 C_PATH='@t6g_mb_lib.t6g(sch_1):page301_i24@pure_quanta.q_cap(chips)',
 P_PATH='@t6g_mb_lib.t6g(sch_1):page263_i24@pure_quanta.q_cap(chips)',
 PATH='I24',
 DRAWING='@T6G_MB_LIB.T6G(SCH_1):PAGE301',
 TOLERANCE='10%',
 MATERIAL='X7R',
 PHYS_PAGE='263',
 XY='(-2675,725)',
 ROT='0',
 VER='1',
 PACK_TYPE='0402',
 LOCATION='PC2182',
 CDS_LIB='pure_quanta',
 CDS_PART_NAME='Q_CAP_0402-220PF,50V,10%,X7R,TMP_QCH12206KB14',
 VOLTAGE='50V',
 ROOM='HSC BOM1',
 PART_NUMBER='TMP_QCH12206KB14',
 VALUE='220PF',
 PRIM_FILE='./archive_libs/logical/q_cap/chips/chips.prt';

PART_NAME
 PC2183 'Q_CAP_0402-220PF,50V,10%,EMPTY,TMP_QCH12206KB14':
 ROOM='HSC BOM1';

SECTION_NUMBER 1
 '@T6G_MB_LIB.T6G(SCH_1):PAGE301_I2@PURE_QUANTA.Q_CAP(CHIPS)':
 C_PATH='@t6g_mb_lib.t6g(sch_1):page301_i2@pure_quanta.q_cap(chips)',
 P_PATH='@t6g_mb_lib.t6g(sch_1):page263_i2@pure_quanta.q_cap(chips)',
 PATH='I2',
 DRAWING='@T6G_MB_LIB.T6G(SCH_1):PAGE301',
 TOLERANCE='10%',
 MATERIAL='EMPTY',
 PHYS_PAGE='263',
 XY='(-2650,-2075)',
 ROT='0',
 VER='1',
 PACK_TYPE='0402',
 LOCATION='PC2183',
 CDS_LIB='pure_quanta',
 CDS_PART_NAME='Q_CAP_0402-220PF,50V,10%,EMPTY,TMP_QCH12206KB14',
 VOLTAGE='50V',
 ROOM='HSC BOM1',
 PART_NUMBER='TMP_QCH12206KB14',
 VALUE='220PF',
 PRIM_FILE='./archive_libs/logical/q_cap/chips/chips.prt';

PART_NAME
 PC2184 'Q_CAP_0402-0.068UF,16V,10%,X7R,CH3683K1B09':
 ROOM='HSC BOM1';

SECTION_NUMBER 1
 '@T6G_MB_LIB.T6G(SCH_1):PAGE301_I47@PURE_QUANTA.Q_CAP(CHIPS)':
 C_PATH='@t6g_mb_lib.t6g(sch_1):page301_i47@pure_quanta.q_cap(chips)',
 P_PATH='@t6g_mb_lib.t6g(sch_1):page263_i47@pure_quanta.q_cap(chips)',
 PATH='I47',
 DRAWING='@T6G_MB_LIB.T6G(SCH_1):PAGE301',
 TOLERANCE='10%',
 MATERIAL='X7R',
 PHYS_PAGE='263',
 XY='(975,750)',
 ROT='0',
 VER='1',
 PACK_TYPE='0402',
 LOCATION='PC2184',
 CDS_LIB='pure_quanta',
 CDS_PART_NAME='Q_CAP_0402-0.068UF,16V,10%,X7R,CH3683K1B09',
 VOLTAGE='16V',
 ROOM='HSC BOM1',
 PART_NUMBER='CH3683K1B09',
 VALUE='0.068UF',
 PRIM_FILE='./archive_libs/logical/q_cap/chips/chips.prt';

PART_NAME
 PC2185 'Q_CAP_0402-0.068UF,16V,10%,X7R,CH3683K1B09':
 ROOM='HSC BOM1';

SECTION_NUMBER 1
 '@T6G_MB_LIB.T6G(SCH_1):PAGE301_I38@PURE_QUANTA.Q_CAP(CHIPS)':
 C_PATH='@t6g_mb_lib.t6g(sch_1):page301_i38@pure_quanta.q_cap(chips)',
 P_PATH='@t6g_mb_lib.t6g(sch_1):page263_i38@pure_quanta.q_cap(chips)',
 PATH='I38',
 DRAWING='@T6G_MB_LIB.T6G(SCH_1):PAGE301',
 TOLERANCE='10%',
 MATERIAL='X7R',
 PHYS_PAGE='263',
 XY='(975,-2050)',
 ROT='0',
 VER='1',
 PACK_TYPE='0402',
 LOCATION='PC2185',
 CDS_LIB='pure_quanta',
 CDS_PART_NAME='Q_CAP_0402-0.068UF,16V,10%,X7R,CH3683K1B09',
 VOLTAGE='16V',
 ROOM='HSC BOM1',
 PART_NUMBER='CH3683K1B09',
 VALUE='0.068UF',
 PRIM_FILE='./archive_libs/logical/q_cap/chips/chips.prt';

PART_NAME
 PC2186 'Q_CAP_C0402-1UF,25V,10%,X6S,CH5104KEB02':
 ROOM='HSC BOM1';

SECTION_NUMBER 1
 '@T6G_MB_LIB.T6G(SCH_1):PAGE267_I27@PURE_QUANTA.Q_CAP(CHIPS)':
 C_PATH='@t6g_mb_lib.t6g(sch_1):page267_i27@pure_quanta.q_cap(chips)',
 P_PATH='@t6g_mb_lib.t6g(sch_1):page262_i27@pure_quanta.q_cap(chips)',
 PATH='I27',
 DRAWING='@T6G_MB_LIB.T6G(SCH_1):PAGE267',
 TOLERANCE='10%',
 MATERIAL='X6S',
 PHYS_PAGE='262',
 XY='(-15425,3625)',
 ROT='0',
 VER='1',
 PACK_TYPE='C0402',
 LOCATION='PC2186',
 CDS_LIB='pure_quanta',
 CDS_PART_NAME='Q_CAP_C0402-1UF,25V,10%,X6S,CH5104KEB02',
 VOLTAGE='25V',
 ROOM='HSC BOM1',
 PART_NUMBER='CH5104KEB02',
 VALUE='1UF',
 PRIM_FILE='./archive_libs/logical/q_cap/chips/chips.prt';

PART_NAME
 PC2187 'Q_CAP_C0402-1UF,25V,10%,X6S,CH5104KEB02':
 ROOM='HSC BOM1';

SECTION_NUMBER 1
 '@T6G_MB_LIB.T6G(SCH_1):PAGE267_I30@PURE_QUANTA.Q_CAP(CHIPS)':
 C_PATH='@t6g_mb_lib.t6g(sch_1):page267_i30@pure_quanta.q_cap(chips)',
 P_PATH='@t6g_mb_lib.t6g(sch_1):page262_i30@pure_quanta.q_cap(chips)',
 PATH='I30',
 DRAWING='@T6G_MB_LIB.T6G(SCH_1):PAGE267',
 TOLERANCE='10%',
 MATERIAL='X6S',
 PHYS_PAGE='262',
 XY='(-14925,3600)',
 ROT='0',
 VER='1',
 PACK_TYPE='C0402',
 LOCATION='PC2187',
 CDS_LIB='pure_quanta',
 CDS_PART_NAME='Q_CAP_C0402-1UF,25V,10%,X6S,CH5104KEB02',
 VOLTAGE='25V',
 ROOM='HSC BOM1',
 PART_NUMBER='CH5104KEB02',
 VALUE='1UF',
 PRIM_FILE='./archive_libs/logical/q_cap/chips/chips.prt';

PART_NAME
 PC2188 'Q_CAP_C0402-1UF,25V,10%,X6S,CH5104KEB02':
 ROOM='HSC BOM1';

SECTION_NUMBER 1
 '@T6G_MB_LIB.T6G(SCH_1):PAGE267_I46@PURE_QUANTA.Q_CAP(CHIPS)':
 C_PATH='@t6g_mb_lib.t6g(sch_1):page267_i46@pure_quanta.q_cap(chips)',
 P_PATH='@t6g_mb_lib.t6g(sch_1):page262_i46@pure_quanta.q_cap(chips)',
 PATH='I46',
 DRAWING='@T6G_MB_LIB.T6G(SCH_1):PAGE267',
 TOLERANCE='10%',
 MATERIAL='X6S',
 PHYS_PAGE='262',
 XY='(-14225,4350)',
 ROT='0',
 VER='1',
 PACK_TYPE='C0402',
 LOCATION='PC2188',
 CDS_LIB='pure_quanta',
 CDS_PART_NAME='Q_CAP_C0402-1UF,25V,10%,X6S,CH5104KEB02',
 VOLTAGE='25V',
 ROOM='HSC BOM1',
 PART_NUMBER='CH5104KEB02',
 VALUE='1UF',
 PRIM_FILE='./archive_libs/logical/q_cap/chips/chips.prt';

PART_NAME
 PC2189 'Q_CAP_C0402-0.01UF,50V,10%,X7R,CH31006KB18':
 ROOM='HSC BOM1';

SECTION_NUMBER 1
 '@T6G_MB_LIB.T6G(SCH_1):PAGE267_I59@PURE_QUANTA.Q_CAP(CHIPS)':
 C_PATH='@t6g_mb_lib.t6g(sch_1):page267_i59@pure_quanta.q_cap(chips)',
 P_PATH='@t6g_mb_lib.t6g(sch_1):page262_i59@pure_quanta.q_cap(chips)',
 PATH='I59',
 DRAWING='@T6G_MB_LIB.T6G(SCH_1):PAGE267',
 TOLERANCE='10%',
 MATERIAL='X7R',
 PHYS_PAGE='262',
 XY='(-13175,3900)',
 ROT='0',
 VER='1',
 PACK_TYPE='C0402',
 LOCATION='PC2189',
 CDS_LIB='pure_quanta',
 CDS_PART_NAME='Q_CAP_C0402-0.01UF,50V,10%,X7R,CH31006KB18',
 VOLTAGE='50V',
 ROOM='HSC BOM1',
 PART_NUMBER='CH31006KB18',
 VALUE='0.01UF',
 PRIM_FILE='./archive_libs/logical/q_cap/chips/chips.prt';

PART_NAME
 PC2190 'Q_CAP_C0402-0.01UF,50V,10%,X7R,CH31006KB18':
 ROOM='HSC BOM1';

SECTION_NUMBER 1
 '@T6G_MB_LIB.T6G(SCH_1):PAGE267_I72@PURE_QUANTA.Q_CAP(CHIPS)':
 C_PATH='@t6g_mb_lib.t6g(sch_1):page267_i72@pure_quanta.q_cap(chips)',
 P_PATH='@t6g_mb_lib.t6g(sch_1):page262_i72@pure_quanta.q_cap(chips)',
 PATH='I72',
 DRAWING='@T6G_MB_LIB.T6G(SCH_1):PAGE267',
 TOLERANCE='10%',
 MATERIAL='X7R',
 PHYS_PAGE='262',
 XY='(-9775,3975)',
 ROT='0',
 VER='1',
 PACK_TYPE='C0402',
 LOCATION='PC2190',
 CDS_LIB='pure_quanta',
 CDS_PART_NAME='Q_CAP_C0402-0.01UF,50V,10%,X7R,CH31006KB18',
 VOLTAGE='50V',
 ROOM='HSC BOM1',
 PART_NUMBER='CH31006KB18',
 VALUE='0.01UF',
 PRIM_FILE='./archive_libs/logical/q_cap/chips/chips.prt';

PART_NAME
 PC2191 'Q_CAP_0402-0.068UF,16V,10%,X7R,CH3683K1B09':
 ROOM='HSC BOM1';

SECTION_NUMBER 1
 '@T6G_MB_LIB.T6G(SCH_1):PAGE267_I75@PURE_QUANTA.Q_CAP(CHIPS)':
 C_PATH='@t6g_mb_lib.t6g(sch_1):page267_i75@pure_quanta.q_cap(chips)',
 P_PATH='@t6g_mb_lib.t6g(sch_1):page262_i75@pure_quanta.q_cap(chips)',
 PATH='I75',
 DRAWING='@T6G_MB_LIB.T6G(SCH_1):PAGE267',
 TOLERANCE='10%',
 MATERIAL='X7R',
 PHYS_PAGE='262',
 XY='(-9500,2175)',
 ROT='0',
 VER='1',
 PACK_TYPE='0402',
 LOCATION='PC2191',
 CDS_LIB='pure_quanta',
 CDS_PART_NAME='Q_CAP_0402-0.068UF,16V,10%,X7R,CH3683K1B09',
 VOLTAGE='16V',
 ROOM='HSC BOM1',
 PART_NUMBER='CH3683K1B09',
 VALUE='0.068UF',
 PRIM_FILE='./archive_libs/logical/q_cap/chips/chips.prt';

PART_NAME
 PC2192 'Q_CAP_C0402-0.001UF,50V,10%,X7R,CH30106KB19':
 ROOM='HSC BOM1';

SECTION_NUMBER 1
 '@T6G_MB_LIB.T6G(SCH_1):PAGE267_I78@PURE_QUANTA.Q_CAP(CHIPS)':
 C_PATH='@t6g_mb_lib.t6g(sch_1):page267_i78@pure_quanta.q_cap(chips)',
 P_PATH='@t6g_mb_lib.t6g(sch_1):page262_i78@pure_quanta.q_cap(chips)',
 PATH='I78',
 DRAWING='@T6G_MB_LIB.T6G(SCH_1):PAGE267',
 TOLERANCE='10%',
 MATERIAL='X7R',
 PHYS_PAGE='262',
 XY='(-8925,2425)',
 ROT='0',
 VER='1',
 PACK_TYPE='C0402',
 LOCATION='PC2192',
 CDS_LIB='pure_quanta',
 CDS_PART_NAME='Q_CAP_C0402-0.001UF,50V,10%,X7R,CH30106KB19',
 VOLTAGE='50V',
 ROOM='HSC BOM1',
 PART_NUMBER='CH30106KB19',
 VALUE='0.001UF',
 PRIM_FILE='./archive_libs/logical/q_cap/chips/chips.prt';

PART_NAME
 PC2193 'Q_CAP_C0402-0.047UF,25V,10%,X7R,CH3474K1B04':
 ROOM='HSC BOM1';

SECTION_NUMBER 1
 '@T6G_MB_LIB.T6G(SCH_1):PAGE267_I84@PURE_QUANTA.Q_CAP(CHIPS)':
 C_PATH='@t6g_mb_lib.t6g(sch_1):page267_i84@pure_quanta.q_cap(chips)',
 P_PATH='@t6g_mb_lib.t6g(sch_1):page262_i84@pure_quanta.q_cap(chips)',
 PATH='I84',
 DRAWING='@T6G_MB_LIB.T6G(SCH_1):PAGE267',
 TOLERANCE='10%',
 MATERIAL='X7R',
 PHYS_PAGE='262',
 XY='(-8100,2850)',
 ROT='0',
 VER='1',
 PACK_TYPE='C0402',
 LOCATION='PC2193',
 CDS_LIB='pure_quanta',
 CDS_PART_NAME='Q_CAP_C0402-0.047UF,25V,10%,X7R,CH3474K1B04',
 VOLTAGE='25V',
 ROOM='HSC BOM1',
 PART_NUMBER='CH3474K1B04',
 VALUE='0.047UF',
 PRIM_FILE='./archive_libs/logical/q_cap/chips/chips.prt';

PART_NAME
 PC2196 'Q_CAP_0402-0.22UF,16V,10%,X7R,CH4223K1B00':
 ROOM='E1S_P12V_MPS_MAM_BOM2';

SECTION_NUMBER 1
 '@T6G_MB_LIB.T6G(SCH_1):PAGE323_I13@PURE_QUANTA.Q_CAP(CHIPS)':
 C_PATH='@t6g_mb_lib.t6g(sch_1):page323_i13@pure_quanta.q_cap(chips)',
 P_PATH='@t6g_mb_lib.t6g(sch_1):page147_i13@pure_quanta.q_cap(chips)',
 PATH='I13',
 DRAWING='@T6G_MB_LIB.T6G(SCH_1):PAGE323',
 TOLERANCE='10%',
 MATERIAL='X7R',
 PHYS_PAGE='147',
 XY='(-2050,975)',
 ROT='0',
 VER='1',
 PACK_TYPE='0402',
 LOCATION='PC2196',
 CDS_LIB='pure_quanta',
 CDS_PART_NAME='Q_CAP_0402-0.22UF,16V,10%,X7R,CH4223K1B00',
 VOLTAGE='16V',
 ROOM='E1S_P12V_MPS_MAM_BOM2',
 PART_NUMBER='CH4223K1B00',
 VALUE='0.22UF',
 PRIM_FILE='./archive_libs/logical/q_cap/chips/chips.prt';

PART_NAME
 PC2197 'Q_CAP_0402-39PF,50V,5%,NPO,CH03906JB06':
 ROOM='E1S_P3V3_BOM2';

SECTION_NUMBER 1
 '@T6G_MB_LIB.T6G(SCH_1):PAGE323_I3@PURE_QUANTA.Q_CAP(CHIPS)':
 C_PATH='@t6g_mb_lib.t6g(sch_1):page323_i3@pure_quanta.q_cap(chips)',
 P_PATH='@t6g_mb_lib.t6g(sch_1):page147_i3@pure_quanta.q_cap(chips)',
 PATH='I3',
 DRAWING='@T6G_MB_LIB.T6G(SCH_1):PAGE323',
 TOLERANCE='5%',
 MATERIAL='NPO',
 PHYS_PAGE='147',
 XY='(325,-1650)',
 ROT='0',
 VER='1',
 PACK_TYPE='0402',
 LOCATION='PC2197',
 CDS_LIB='pure_quanta',
 CDS_PART_NAME='Q_CAP_0402-39PF,50V,5%,NPO,CH03906JB06',
 VOLTAGE='50V',
 ROOM='E1S_P3V3_BOM2',
 PART_NUMBER='CH03906JB06',
 VALUE='39PF',
 PRIM_FILE='./archive_libs/logical/q_cap/chips/chips.prt';

PART_NAME
 PC2198 'Q_CAP_C0402-1UF,25V,10%,X6S,CH5104KEB02':
 ROOM='E1S_P12V_MPS_MAM_BOM2';

SECTION_NUMBER 1
 '@T6G_MB_LIB.T6G(SCH_1):PAGE323_I25@PURE_QUANTA.Q_CAP(CHIPS)':
 C_PATH='@t6g_mb_lib.t6g(sch_1):page323_i25@pure_quanta.q_cap(chips)',
 P_PATH='@t6g_mb_lib.t6g(sch_1):page147_i25@pure_quanta.q_cap(chips)',
 PATH='I25',
 DRAWING='@T6G_MB_LIB.T6G(SCH_1):PAGE323',
 TOLERANCE='10%',
 MATERIAL='X6S',
 PHYS_PAGE='147',
 XY='(-825,1825)',
 ROT='0',
 VER='1',
 PACK_TYPE='C0402',
 LOCATION='PC2198',
 CDS_LIB='pure_quanta',
 CDS_PART_NAME='Q_CAP_C0402-1UF,25V,10%,X6S,CH5104KEB02',
 VOLTAGE='25V',
 ROOM='E1S_P12V_MPS_MAM_BOM2',
 PART_NUMBER='CH5104KEB02',
 VALUE='1UF',
 PRIM_FILE='./archive_libs/logical/q_cap/chips/chips.prt';

PART_NAME
 PC2200 'Q_CAP_C0402-1UF,25V,10%,X6S,CH5104KEB02':
 ROOM='E1S_P3V3_BOM2';

SECTION_NUMBER 1
 '@T6G_MB_LIB.T6G(SCH_1):PAGE323_I9@PURE_QUANTA.Q_CAP(CHIPS)':
 C_PATH='@t6g_mb_lib.t6g(sch_1):page323_i9@pure_quanta.q_cap(chips)',
 P_PATH='@t6g_mb_lib.t6g(sch_1):page147_i9@pure_quanta.q_cap(chips)',
 PATH='I9',
 DRAWING='@T6G_MB_LIB.T6G(SCH_1):PAGE323',
 TOLERANCE='10%',
 MATERIAL='X6S',
 PHYS_PAGE='147',
 XY='(975,-1075)',
 ROT='0',
 VER='1',
 PACK_TYPE='C0402',
 LOCATION='PC2200',
 CDS_LIB='pure_quanta',
 CDS_PART_NAME='Q_CAP_C0402-1UF,25V,10%,X6S,CH5104KEB02',
 VOLTAGE='25V',
 ROOM='E1S_P3V3_BOM2',
 PART_NUMBER='CH5104KEB02',
 VALUE='1UF',
 PRIM_FILE='./archive_libs/logical/q_cap/chips/chips.prt';

PART_NAME
 PC2201 'Q_CAP_0402-0.068UF,16V,10%,X7R,CH3683K1B09':
 ROOM='E1S_P3V3_BOM2';

SECTION_NUMBER 1
 '@T6G_MB_LIB.T6G(SCH_1):PAGE323_I30@PURE_QUANTA.Q_CAP(CHIPS)':
 C_PATH='@t6g_mb_lib.t6g(sch_1):page323_i30@pure_quanta.q_cap(chips)',
 P_PATH='@t6g_mb_lib.t6g(sch_1):page147_i30@pure_quanta.q_cap(chips)',
 PATH='I30',
 DRAWING='@T6G_MB_LIB.T6G(SCH_1):PAGE323',
 TOLERANCE='10%',
 MATERIAL='X7R',
 PHYS_PAGE='147',
 XY='(1550,-1725)',
 ROT='0',
 VER='1',
 PACK_TYPE='0402',
 LOCATION='PC2201',
 CDS_LIB='pure_quanta',
 CDS_PART_NAME='Q_CAP_0402-0.068UF,16V,10%,X7R,CH3683K1B09',
 VOLTAGE='16V',
 ROOM='E1S_P3V3_BOM2',
 PART_NUMBER='CH3683K1B09',
 VALUE='0.068UF',
 PRIM_FILE='./archive_libs/logical/q_cap/chips/chips.prt';

PART_NAME
 PC2202 'Q_CAP_C0402-100NF,50V,10%,X7R,CH4106K1B01':
 ROOM='E1S_P12V_MPS_MAM_BOM2';

SECTION_NUMBER 1
 '@T6G_MB_LIB.T6G(SCH_1):PAGE323_I39@PURE_QUANTA.Q_CAP(CHIPS)':
 C_PATH='@t6g_mb_lib.t6g(sch_1):page323_i39@pure_quanta.q_cap(chips)',
 P_PATH='@t6g_mb_lib.t6g(sch_1):page147_i39@pure_quanta.q_cap(chips)',
 PATH='I39',
 DRAWING='@T6G_MB_LIB.T6G(SCH_1):PAGE323',
 TOLERANCE='10%',
 MATERIAL='X7R',
 PHYS_PAGE='147',
 XY='(1125,550)',
 ROT='0',
 VER='1',
 PACK_TYPE='C0402',
 LOCATION='PC2202',
 CDS_LIB='pure_quanta',
 CDS_PART_NAME='Q_CAP_C0402-100NF,50V,10%,X7R,CH4106K1B01',
 VOLTAGE='50V',
 ROOM='E1S_P12V_MPS_MAM_BOM2',
 PART_NUMBER='CH4106K1B01',
 VALUE='100NF',
 PRIM_FILE='./archive_libs/logical/q_cap/chips/chips.prt';

PART_NAME
 PC2203 'Q_CAP_0402-100PF,50V,5%,X7R,CH11006JB18':
 ROOM='E1S_P3V3_BOM2';

SECTION_NUMBER 1
 '@T6G_MB_LIB.T6G(SCH_1):PAGE323_I32@PURE_QUANTA.Q_CAP(CHIPS)':
 C_PATH='@t6g_mb_lib.t6g(sch_1):page323_i32@pure_quanta.q_cap(chips)',
 P_PATH='@t6g_mb_lib.t6g(sch_1):page147_i32@pure_quanta.q_cap(chips)',
 PATH='I32',
 DRAWING='@T6G_MB_LIB.T6G(SCH_1):PAGE323',
 TOLERANCE='5%',
 MATERIAL='X7R',
 PHYS_PAGE='147',
 XY='(3050,-1800)',
 ROT='0',
 VER='1',
 PACK_TYPE='0402',
 LOCATION='PC2203',
 CDS_LIB='pure_quanta',
 CDS_PART_NAME='Q_CAP_0402-100PF,50V,5%,X7R,CH11006JB18',
 VOLTAGE='50V',
 ROOM='E1S_P3V3_BOM2',
 PART_NUMBER='CH11006JB18',
 VALUE='100PF',
 PRIM_FILE='./archive_libs/logical/q_cap/chips/chips.prt';

PART_NAME
 PC2204 'Q_CAP_C0805-10UF,16V,10%,X6S,CH6103KEA01':
 ROOM='E1S_P3V3_BOM2';

SECTION_NUMBER 1
 '@T6G_MB_LIB.T6G(SCH_1):PAGE323_I34@PURE_QUANTA.Q_CAP(CHIPS)':
 C_PATH='@t6g_mb_lib.t6g(sch_1):page323_i34@pure_quanta.q_cap(chips)',
 P_PATH='@t6g_mb_lib.t6g(sch_1):page147_i34@pure_quanta.q_cap(chips)',
 PATH='I34',
 DRAWING='@T6G_MB_LIB.T6G(SCH_1):PAGE323',
 TOLERANCE='10%',
 MATERIAL='X6S',
 PHYS_PAGE='147',
 XY='(3650,-1575)',
 ROT='0',
 VER='1',
 PACK_TYPE='C0805',
 LOCATION='PC2204',
 CDS_LIB='pure_quanta',
 CDS_PART_NAME='Q_CAP_C0805-10UF,16V,10%,X6S,CH6103KEA01',
 VOLTAGE='16V',
 ROOM='E1S_P3V3_BOM2',
 PART_NUMBER='CH6103KEA01',
 VALUE='10UF',
 PRIM_FILE='./archive_libs/logical/q_cap/chips/chips.prt';

PART_NAME
 PC2205 'Q_CAP_C0603-2.2UF,16V,20%,X7R,CH5223M1900':
 ROOM='E1S_P12V_MPS_MAM_BOM2';

SECTION_NUMBER 1
 '@T6G_MB_LIB.T6G(SCH_1):PAGE323_I51@PURE_QUANTA.Q_CAP(CHIPS)':
 C_PATH='@t6g_mb_lib.t6g(sch_1):page323_i51@pure_quanta.q_cap(chips)',
 P_PATH='@t6g_mb_lib.t6g(sch_1):page147_i51@pure_quanta.q_cap(chips)',
 PATH='I51',
 DRAWING='@T6G_MB_LIB.T6G(SCH_1):PAGE323',
 TOLERANCE='20%',
 MATERIAL='X7R',
 PHYS_PAGE='147',
 XY='(2575,900)',
 ROT='0',
 VER='1',
 PACK_TYPE='C0603',
 LOCATION='PC2205',
 CDS_LIB='pure_quanta',
 CDS_PART_NAME='Q_CAP_C0603-2.2UF,16V,20%,X7R,CH5223M1900',
 VOLTAGE='16V',
 ROOM='E1S_P12V_MPS_MAM_BOM2',
 PART_NUMBER='CH5223M1900',
 VALUE='2.2UF',
 PRIM_FILE='./archive_libs/logical/q_cap/chips/chips.prt';

PART_NAME
 PC2206 'Q_CAP_0402-0.1UF,25V,10%,X7R,CH4104K1B00':
 ROOM='E1S_P12V_MPS_MAM_BOM2';

SECTION_NUMBER 1
 '@T6G_MB_LIB.T6G(SCH_1):PAGE323_I56@PURE_QUANTA.Q_CAP(CHIPS)':
 C_PATH='@t6g_mb_lib.t6g(sch_1):page323_i56@pure_quanta.q_cap(chips)',
 P_PATH='@t6g_mb_lib.t6g(sch_1):page147_i56@pure_quanta.q_cap(chips)',
 PATH='I56',
 DRAWING='@T6G_MB_LIB.T6G(SCH_1):PAGE323',
 TOLERANCE='10%',
 MATERIAL='X7R',
 PHYS_PAGE='147',
 XY='(2925,1750)',
 ROT='2',
 VER='1',
 PACK_TYPE='0402',
 LOCATION='PC2206',
 CDS_LIB='pure_quanta',
 CDS_PART_NAME='Q_CAP_0402-0.1UF,25V,10%,X7R,CH4104K1B00',
 VOLTAGE='25V',
 ROOM='E1S_P12V_MPS_MAM_BOM2',
 PART_NUMBER='CH4104K1B00',
 VALUE='0.1UF',
 PRIM_FILE='./archive_libs/logical/q_cap/chips/chips.prt';

PART_NAME
 PC2207 'Q_CAP_C0402-1UF,25V,10%,X6S,CH5104KEB02':;

SECTION_NUMBER 1
 '@T6G_MB_LIB.T6G(SCH_1):PAGE324_I36@PURE_QUANTA.Q_CAP(CHIPS)':
 C_PATH='@t6g_mb_lib.t6g(sch_1):page324_i36@pure_quanta.q_cap(chips)',
 P_PATH='@t6g_mb_lib.t6g(sch_1):page146_i36@pure_quanta.q_cap(chips)',
 PATH='I36',
 DRAWING='@T6G_MB_LIB.T6G(SCH_1):PAGE324',
 TOLERANCE='10%',
 MATERIAL='X6S',
 PHYS_PAGE='146',
 XY='(-475,1375)',
 ROT='0',
 VER='1',
 PACK_TYPE='C0402',
 LOCATION='PC2207',
 CDS_LIB='pure_quanta',
 CDS_PART_NAME='Q_CAP_C0402-1UF,25V,10%,X6S,CH5104KEB02',
 VOLTAGE='25V',
 PART_NUMBER='CH5104KEB02',
 VALUE='1UF',
 PRIM_FILE='./archive_libs/logical/q_cap/chips/chips.prt';

PART_NAME
 PC2208 'Q_CAP_C0402-1UF,25V,10%,X6S,CH5104KEB02':;

SECTION_NUMBER 1
 '@T6G_MB_LIB.T6G(SCH_1):PAGE324_I20@PURE_QUANTA.Q_CAP(CHIPS)':
 C_PATH='@t6g_mb_lib.t6g(sch_1):page324_i20@pure_quanta.q_cap(chips)',
 P_PATH='@t6g_mb_lib.t6g(sch_1):page146_i20@pure_quanta.q_cap(chips)',
 PATH='I20',
 DRAWING='@T6G_MB_LIB.T6G(SCH_1):PAGE324',
 TOLERANCE='10%',
 MATERIAL='X6S',
 PHYS_PAGE='146',
 XY='(-475,-1325)',
 ROT='0',
 VER='1',
 PACK_TYPE='C0402',
 LOCATION='PC2208',
 CDS_LIB='pure_quanta',
 CDS_PART_NAME='Q_CAP_C0402-1UF,25V,10%,X6S,CH5104KEB02',
 VOLTAGE='25V',
 PART_NUMBER='CH5104KEB02',
 VALUE='1UF',
 PRIM_FILE='./archive_libs/logical/q_cap/chips/chips.prt';

PART_NAME
 PC2209 'Q_CAP_C0402-1UF,25V,10%,X6S,CH5104KEB02':
 ROOM='E1S_P12V_MAM_TIC_BOM1';

SECTION_NUMBER 1
 '@T6G_MB_LIB.T6G(SCH_1):PAGE324_I64@PURE_QUANTA.Q_CAP(CHIPS)':
 C_PATH='@t6g_mb_lib.t6g(sch_1):page324_i64@pure_quanta.q_cap(chips)',
 P_PATH='@t6g_mb_lib.t6g(sch_1):page146_i64@pure_quanta.q_cap(chips)',
 PATH='I64',
 DRAWING='@T6G_MB_LIB.T6G(SCH_1):PAGE324',
 TOLERANCE='10%',
 MATERIAL='X6S',
 PHYS_PAGE='146',
 XY='(200,950)',
 ROT='0',
 VER='1',
 PACK_TYPE='C0402',
 LOCATION='PC2209',
 CDS_LIB='pure_quanta',
 CDS_PART_NAME='Q_CAP_C0402-1UF,25V,10%,X6S,CH5104KEB02',
 VOLTAGE='25V',
 ROOM='E1S_P12V_MAM_TIC_BOM1',
 PART_NUMBER='CH5104KEB02',
 VALUE='1UF',
 PRIM_FILE='./archive_libs/logical/q_cap/chips/chips.prt';

PART_NAME
 PC2210 'Q_CAP_C0402-1UF,25V,10%,X6S,CH5104KEB02':
 ROOM='E1S_P3V3_BOM1';

SECTION_NUMBER 1
 '@T6G_MB_LIB.T6G(SCH_1):PAGE324_I41@PURE_QUANTA.Q_CAP(CHIPS)':
 C_PATH='@t6g_mb_lib.t6g(sch_1):page324_i41@pure_quanta.q_cap(chips)',
 P_PATH='@t6g_mb_lib.t6g(sch_1):page146_i41@pure_quanta.q_cap(chips)',
 PATH='I41',
 DRAWING='@T6G_MB_LIB.T6G(SCH_1):PAGE324',
 TOLERANCE='10%',
 MATERIAL='X6S',
 PHYS_PAGE='146',
 XY='(200,-1750)',
 ROT='0',
 VER='1',
 PACK_TYPE='C0402',
 LOCATION='PC2210',
 CDS_LIB='pure_quanta',
 CDS_PART_NAME='Q_CAP_C0402-1UF,25V,10%,X6S,CH5104KEB02',
 VOLTAGE='25V',
 ROOM='E1S_P3V3_BOM1',
 PART_NUMBER='CH5104KEB02',
 VALUE='1UF',
 PRIM_FILE='./archive_libs/logical/q_cap/chips/chips.prt';

PART_NAME
 PC2211 'Q_CAP_C0402-1UF,25V,10%,X6S,CH5104KEB02':
 ROOM='E1S_P12V_MAM_TIC_BOM1';

SECTION_NUMBER 1
 '@T6G_MB_LIB.T6G(SCH_1):PAGE324_I61@PURE_QUANTA.Q_CAP(CHIPS)':
 C_PATH='@t6g_mb_lib.t6g(sch_1):page324_i61@pure_quanta.q_cap(chips)',
 P_PATH='@t6g_mb_lib.t6g(sch_1):page146_i61@pure_quanta.q_cap(chips)',
 PATH='I61',
 DRAWING='@T6G_MB_LIB.T6G(SCH_1):PAGE324',
 TOLERANCE='10%',
 MATERIAL='X6S',
 PHYS_PAGE='146',
 XY='(425,650)',
 ROT='1',
 VER='1',
 PACK_TYPE='C0402',
 LOCATION='PC2211',
 CDS_LIB='pure_quanta',
 CDS_PART_NAME='Q_CAP_C0402-1UF,25V,10%,X6S,CH5104KEB02',
 VOLTAGE='25V',
 ROOM='E1S_P12V_MAM_TIC_BOM1',
 PART_NUMBER='CH5104KEB02',
 VALUE='1UF',
 PRIM_FILE='./archive_libs/logical/q_cap/chips/chips.prt';

PART_NAME
 PC2212 'Q_CAP_C0402-1UF,25V,10%,X6S,CH5104KEB02':
 ROOM='E1S_P3V3_BOM1';

SECTION_NUMBER 1
 '@T6G_MB_LIB.T6G(SCH_1):PAGE324_I42@PURE_QUANTA.Q_CAP(CHIPS)':
 C_PATH='@t6g_mb_lib.t6g(sch_1):page324_i42@pure_quanta.q_cap(chips)',
 P_PATH='@t6g_mb_lib.t6g(sch_1):page146_i42@pure_quanta.q_cap(chips)',
 PATH='I42',
 DRAWING='@T6G_MB_LIB.T6G(SCH_1):PAGE324',
 TOLERANCE='10%',
 MATERIAL='X6S',
 PHYS_PAGE='146',
 XY='(425,-2050)',
 ROT='1',
 VER='1',
 PACK_TYPE='C0402',
 LOCATION='PC2212',
 CDS_LIB='pure_quanta',
 CDS_PART_NAME='Q_CAP_C0402-1UF,25V,10%,X6S,CH5104KEB02',
 VOLTAGE='25V',
 ROOM='E1S_P3V3_BOM1',
 PART_NUMBER='CH5104KEB02',
 VALUE='1UF',
 PRIM_FILE='./archive_libs/logical/q_cap/chips/chips.prt';

PART_NAME
 PC2213 'Q_CAP_C0402-0.01UF,50V,10%,EMPTY,CH31006KB18':
 ROOM='E1S_P3V3_BOM1';

SECTION_NUMBER 1
 '@T6G_MB_LIB.T6G(SCH_1):PAGE324_I46@PURE_QUANTA.Q_CAP(CHIPS)':
 C_PATH='@t6g_mb_lib.t6g(sch_1):page324_i46@pure_quanta.q_cap(chips)',
 P_PATH='@t6g_mb_lib.t6g(sch_1):page146_i46@pure_quanta.q_cap(chips)',
 PATH='I46',
 DRAWING='@T6G_MB_LIB.T6G(SCH_1):PAGE324',
 TOLERANCE='10%',
 MATERIAL='EMPTY',
 PHYS_PAGE='146',
 XY='(2275,-1725)',
 ROT='0',
 VER='1',
 PACK_TYPE='C0402',
 LOCATION='PC2213',
 CDS_LIB='pure_quanta',
 CDS_PART_NAME='Q_CAP_C0402-0.01UF,50V,10%,EMPTY,CH31006KB18',
 VOLTAGE='50V',
 ROOM='E1S_P3V3_BOM1',
 PART_NUMBER='CH31006KB18',
 VALUE='0.01UF',
 PRIM_FILE='./archive_libs/logical/q_cap/chips/chips.prt';

PART_NAME
 PC2214 'Q_CAP_C0402-0.01UF,50V,10%,EMPTY,CH31006KB18':
 ROOM='E1S_P12V_MAM_TIC_BOM1';

SECTION_NUMBER 1
 '@T6G_MB_LIB.T6G(SCH_1):PAGE324_I72@PURE_QUANTA.Q_CAP(CHIPS)':
 C_PATH='@t6g_mb_lib.t6g(sch_1):page324_i72@pure_quanta.q_cap(chips)',
 P_PATH='@t6g_mb_lib.t6g(sch_1):page146_i72@pure_quanta.q_cap(chips)',
 PATH='I72',
 DRAWING='@T6G_MB_LIB.T6G(SCH_1):PAGE324',
 TOLERANCE='10%',
 MATERIAL='EMPTY',
 PHYS_PAGE='146',
 XY='(2275,975)',
 ROT='0',
 VER='1',
 PACK_TYPE='C0402',
 LOCATION='PC2214',
 CDS_LIB='pure_quanta',
 CDS_PART_NAME='Q_CAP_C0402-0.01UF,50V,10%,EMPTY,CH31006KB18',
 VOLTAGE='50V',
 ROOM='E1S_P12V_MAM_TIC_BOM1',
 PART_NUMBER='CH31006KB18',
 VALUE='0.01UF',
 PRIM_FILE='./archive_libs/logical/q_cap/chips/chips.prt';

PART_NAME
 PC2215 'Q_CAP_C0402-3900PF,50V,10%,X7R,CH23906KB14':
 ROOM='E1S_P12V_MAM_TIC_BOM1';

SECTION_NUMBER 1
 '@T6G_MB_LIB.T6G(SCH_1):PAGE324_I69@PURE_QUANTA.Q_CAP(CHIPS)':
 C_PATH='@t6g_mb_lib.t6g(sch_1):page324_i69@pure_quanta.q_cap(chips)',
 P_PATH='@t6g_mb_lib.t6g(sch_1):page146_i69@pure_quanta.q_cap(chips)',
 PATH='I69',
 DRAWING='@T6G_MB_LIB.T6G(SCH_1):PAGE324',
 TOLERANCE='10%',
 MATERIAL='X7R',
 PHYS_PAGE='146',
 XY='(2825,750)',
 ROT='1',
 VER='1',
 PACK_TYPE='C0402',
 LOCATION='PC2215',
 CDS_LIB='pure_quanta',
 CDS_PART_NAME='Q_CAP_C0402-3900PF,50V,10%,X7R,CH23906KB14',
 VOLTAGE='50V',
 ROOM='E1S_P12V_MAM_TIC_BOM1',
 PART_NUMBER='CH23906KB14',
 VALUE='3900PF',
 PRIM_FILE='./archive_libs/logical/q_cap/chips/chips.prt';

PART_NAME
 PC2216 'Q_CAP_C0402-6800PF,50V,10%,X7R,CH2686K1B01':
 ROOM='E1S_P3V3_BOM1';

SECTION_NUMBER 1
 '@T6G_MB_LIB.T6G(SCH_1):PAGE324_I49@PURE_QUANTA.Q_CAP(CHIPS)':
 C_PATH='@t6g_mb_lib.t6g(sch_1):page324_i49@pure_quanta.q_cap(chips)',
 P_PATH='@t6g_mb_lib.t6g(sch_1):page146_i49@pure_quanta.q_cap(chips)',
 PATH='I49',
 DRAWING='@T6G_MB_LIB.T6G(SCH_1):PAGE324',
 TOLERANCE='10%',
 MATERIAL='X7R',
 PHYS_PAGE='146',
 XY='(3025,-1950)',
 ROT='1',
 VER='1',
 PACK_TYPE='C0402',
 LOCATION='PC2216',
 CDS_LIB='pure_quanta',
 CDS_PART_NAME='Q_CAP_C0402-6800PF,50V,10%,X7R,CH2686K1B01',
 VOLTAGE='50V',
 ROOM='E1S_P3V3_BOM1',
 PART_NUMBER='CH2686K1B01',
 VALUE='6800PF',
 PRIM_FILE='./archive_libs/logical/q_cap/chips/chips.prt';

PART_NAME
 PC2217 'Q_CAP_0402-0.1UF,25V,10%,X7R,CH4104K1B00':;

SECTION_NUMBER 1
 '@T6G_MB_LIB.T6G(SCH_1):PAGE324_I78@PURE_QUANTA.Q_CAP(CHIPS)':
 C_PATH='@t6g_mb_lib.t6g(sch_1):page324_i78@pure_quanta.q_cap(chips)',
 P_PATH='@t6g_mb_lib.t6g(sch_1):page146_i78@pure_quanta.q_cap(chips)',
 PATH='I78',
 DRAWING='@T6G_MB_LIB.T6G(SCH_1):PAGE324',
 TOLERANCE='10%',
 MATERIAL='X7R',
 PHYS_PAGE='146',
 XY='(3175,1575)',
 ROT='0',
 VER='1',
 PACK_TYPE='0402',
 LOCATION='PC2217',
 CDS_LIB='pure_quanta',
 CDS_PART_NAME='Q_CAP_0402-0.1UF,25V,10%,X7R,CH4104K1B00',
 VOLTAGE='25V',
 PART_NUMBER='CH4104K1B00',
 VALUE='0.1UF',
 PRIM_FILE='./archive_libs/logical/q_cap/chips/chips.prt';

PART_NAME
 PC2218 'Q_CAP_0402-0.1UF,25V,10%,X7R,CH4104K1B00':;

SECTION_NUMBER 1
 '@T6G_MB_LIB.T6G(SCH_1):PAGE324_I57@PURE_QUANTA.Q_CAP(CHIPS)':
 C_PATH='@t6g_mb_lib.t6g(sch_1):page324_i57@pure_quanta.q_cap(chips)',
 P_PATH='@t6g_mb_lib.t6g(sch_1):page146_i57@pure_quanta.q_cap(chips)',
 PATH='I57',
 DRAWING='@T6G_MB_LIB.T6G(SCH_1):PAGE324',
 TOLERANCE='10%',
 MATERIAL='X7R',
 PHYS_PAGE='146',
 XY='(3200,-1125)',
 ROT='0',
 VER='1',
 PACK_TYPE='0402',
 LOCATION='PC2218',
 CDS_LIB='pure_quanta',
 CDS_PART_NAME='Q_CAP_0402-0.1UF,25V,10%,X7R,CH4104K1B00',
 VOLTAGE='25V',
 PART_NUMBER='CH4104K1B00',
 VALUE='0.1UF',
 PRIM_FILE='./archive_libs/logical/q_cap/chips/chips.prt';

PART_NAME
 PC2219 'Q_CAP_C0805-10UF,16V,10%,X6S,CH6103KEA01':;

SECTION_NUMBER 1
 '@T6G_MB_LIB.T6G(SCH_1):PAGE324_I79@PURE_QUANTA.Q_CAP(CHIPS)':
 C_PATH='@t6g_mb_lib.t6g(sch_1):page324_i79@pure_quanta.q_cap(chips)',
 P_PATH='@t6g_mb_lib.t6g(sch_1):page146_i79@pure_quanta.q_cap(chips)',
 PATH='I79',
 DRAWING='@T6G_MB_LIB.T6G(SCH_1):PAGE324',
 TOLERANCE='10%',
 MATERIAL='X6S',
 PHYS_PAGE='146',
 XY='(3600,1575)',
 ROT='0',
 VER='1',
 PACK_TYPE='C0805',
 LOCATION='PC2219',
 CDS_LIB='pure_quanta',
 CDS_PART_NAME='Q_CAP_C0805-10UF,16V,10%,X6S,CH6103KEA01',
 VOLTAGE='16V',
 PART_NUMBER='CH6103KEA01',
 VALUE='10UF',
 PRIM_FILE='./archive_libs/logical/q_cap/chips/chips.prt';

PART_NAME
 PC2220 'Q_CAP_C0805-10UF,16V,10%,X6S,CH6103KEA01':;

SECTION_NUMBER 1
 '@T6G_MB_LIB.T6G(SCH_1):PAGE324_I58@PURE_QUANTA.Q_CAP(CHIPS)':
 C_PATH='@t6g_mb_lib.t6g(sch_1):page324_i58@pure_quanta.q_cap(chips)',
 P_PATH='@t6g_mb_lib.t6g(sch_1):page146_i58@pure_quanta.q_cap(chips)',
 PATH='I58',
 DRAWING='@T6G_MB_LIB.T6G(SCH_1):PAGE324',
 TOLERANCE='10%',
 MATERIAL='X6S',
 PHYS_PAGE='146',
 XY='(3775,-1125)',
 ROT='0',
 VER='1',
 PACK_TYPE='C0805',
 LOCATION='PC2220',
 CDS_LIB='pure_quanta',
 CDS_PART_NAME='Q_CAP_C0805-10UF,16V,10%,X6S,CH6103KEA01',
 VOLTAGE='16V',
 PART_NUMBER='CH6103KEA01',
 VALUE='10UF',
 PRIM_FILE='./archive_libs/logical/q_cap/chips/chips.prt';

PART_NAME
 PC2223 'Q_CAP_C0402-1UF,25V,10%,X6S,CH5104KEB02':
 ROOM='HSC BOM1';

SECTION_NUMBER 1
 '@T6G_MB_LIB.T6G(SCH_1):PAGE325_I4@PURE_QUANTA.Q_CAP(CHIPS)':
 C_PATH='@t6g_mb_lib.t6g(sch_1):page325_i4@pure_quanta.q_cap(chips)',
 P_PATH='@t6g_mb_lib.t6g(sch_1):page264_i4@pure_quanta.q_cap(chips)',
 PATH='I4',
 DRAWING='@T6G_MB_LIB.T6G(SCH_1):PAGE325',
 TOLERANCE='10%',
 MATERIAL='X6S',
 PHYS_PAGE='264',
 XY='(-3575,-1300)',
 ROT='0',
 VER='1',
 PACK_TYPE='C0402',
 LOCATION='PC2223',
 CDS_LIB='pure_quanta',
 CDS_PART_NAME='Q_CAP_C0402-1UF,25V,10%,X6S,CH5104KEB02',
 VOLTAGE='25V',
 ROOM='HSC BOM1',
 PART_NUMBER='CH5104KEB02',
 VALUE='1UF',
 PRIM_FILE='./archive_libs/logical/q_cap/chips/chips.prt';

PART_NAME
 PC2224 'Q_CAP_0402-220PF,50V,10%,EMPTY,TMP_QCH12206KB14':
 ROOM='HSC BOM1';

SECTION_NUMBER 1
 '@T6G_MB_LIB.T6G(SCH_1):PAGE325_I24@PURE_QUANTA.Q_CAP(CHIPS)':
 C_PATH='@t6g_mb_lib.t6g(sch_1):page325_i24@pure_quanta.q_cap(chips)',
 P_PATH='@t6g_mb_lib.t6g(sch_1):page264_i24@pure_quanta.q_cap(chips)',
 PATH='I24',
 DRAWING='@T6G_MB_LIB.T6G(SCH_1):PAGE325',
 TOLERANCE='10%',
 MATERIAL='EMPTY',
 PHYS_PAGE='264',
 XY='(-2700,825)',
 ROT='0',
 VER='1',
 PACK_TYPE='0402',
 LOCATION='PC2224',
 CDS_LIB='pure_quanta',
 CDS_PART_NAME='Q_CAP_0402-220PF,50V,10%,EMPTY,TMP_QCH12206KB14',
 VOLTAGE='50V',
 ROOM='HSC BOM1',
 PART_NUMBER='TMP_QCH12206KB14',
 VALUE='220PF',
 PRIM_FILE='./archive_libs/logical/q_cap/chips/chips.prt';

PART_NAME
 PC2225 'Q_CAP_0402-220PF,50V,10%,EMPTY,TMP_QCH12206KB14':
 ROOM='HSC BOM1';

SECTION_NUMBER 1
 '@T6G_MB_LIB.T6G(SCH_1):PAGE325_I2@PURE_QUANTA.Q_CAP(CHIPS)':
 C_PATH='@t6g_mb_lib.t6g(sch_1):page325_i2@pure_quanta.q_cap(chips)',
 P_PATH='@t6g_mb_lib.t6g(sch_1):page264_i2@pure_quanta.q_cap(chips)',
 PATH='I2',
 DRAWING='@T6G_MB_LIB.T6G(SCH_1):PAGE325',
 TOLERANCE='10%',
 MATERIAL='EMPTY',
 PHYS_PAGE='264',
 XY='(-2700,-1950)',
 ROT='0',
 VER='1',
 PACK_TYPE='0402',
 LOCATION='PC2225',
 CDS_LIB='pure_quanta',
 CDS_PART_NAME='Q_CAP_0402-220PF,50V,10%,EMPTY,TMP_QCH12206KB14',
 VOLTAGE='50V',
 ROOM='HSC BOM1',
 PART_NUMBER='TMP_QCH12206KB14',
 VALUE='220PF',
 PRIM_FILE='./archive_libs/logical/q_cap/chips/chips.prt';

PART_NAME
 PC2226 'Q_CAP_0402-0.068UF,16V,10%,X7R,CH3683K1B09':
 ROOM='HSC BOM1';

SECTION_NUMBER 1
 '@T6G_MB_LIB.T6G(SCH_1):PAGE325_I47@PURE_QUANTA.Q_CAP(CHIPS)':
 C_PATH='@t6g_mb_lib.t6g(sch_1):page325_i47@pure_quanta.q_cap(chips)',
 P_PATH='@t6g_mb_lib.t6g(sch_1):page264_i47@pure_quanta.q_cap(chips)',
 PATH='I47',
 DRAWING='@T6G_MB_LIB.T6G(SCH_1):PAGE325',
 TOLERANCE='10%',
 MATERIAL='X7R',
 PHYS_PAGE='264',
 XY='(1000,850)',
 ROT='0',
 VER='1',
 PACK_TYPE='0402',
 LOCATION='PC2226',
 CDS_LIB='pure_quanta',
 CDS_PART_NAME='Q_CAP_0402-0.068UF,16V,10%,X7R,CH3683K1B09',
 VOLTAGE='16V',
 ROOM='HSC BOM1',
 PART_NUMBER='CH3683K1B09',
 VALUE='0.068UF',
 PRIM_FILE='./archive_libs/logical/q_cap/chips/chips.prt';

PART_NAME
 PC2227 'Q_CAP_0402-0.068UF,16V,10%,X7R,CH3683K1B09':
 ROOM='HSC BOM1';

SECTION_NUMBER 1
 '@T6G_MB_LIB.T6G(SCH_1):PAGE325_I38@PURE_QUANTA.Q_CAP(CHIPS)':
 C_PATH='@t6g_mb_lib.t6g(sch_1):page325_i38@pure_quanta.q_cap(chips)',
 P_PATH='@t6g_mb_lib.t6g(sch_1):page264_i38@pure_quanta.q_cap(chips)',
 PATH='I38',
 DRAWING='@T6G_MB_LIB.T6G(SCH_1):PAGE325',
 TOLERANCE='10%',
 MATERIAL='X7R',
 PHYS_PAGE='264',
 XY='(1000,-1925)',
 ROT='0',
 VER='1',
 PACK_TYPE='0402',
 LOCATION='PC2227',
 CDS_LIB='pure_quanta',
 CDS_PART_NAME='Q_CAP_0402-0.068UF,16V,10%,X7R,CH3683K1B09',
 VOLTAGE='16V',
 ROOM='HSC BOM1',
 PART_NUMBER='CH3683K1B09',
 VALUE='0.068UF',
 PRIM_FILE='./archive_libs/logical/q_cap/chips/chips.prt';

PART_NAME
 PC2229 'Q_CAP_0402-0.22UF,16V,10%,X7R,CH4223K1B00':
 ROOM='SCM_P12V_MPS_BOM2';

SECTION_NUMBER 1
 '@T6G_MB_LIB.T6G(SCH_1):PAGE350_I8@PURE_QUANTA.Q_CAP(CHIPS)':
 C_PATH='@t6g_mb_lib.t6g(sch_1):page350_i8@pure_quanta.q_cap(chips)',
 P_PATH='@t6g_mb_lib.t6g(sch_1):page152_i8@pure_quanta.q_cap(chips)',
 PATH='I8',
 DRAWING='@T6G_MB_LIB.T6G(SCH_1):PAGE350',
 TOLERANCE='10%',
 MATERIAL='X7R',
 PHYS_PAGE='152',
 XY='(-525,11650)',
 ROT='0',
 VER='1',
 PACK_TYPE='0402',
 LOCATION='PC2229',
 CDS_LIB='pure_quanta',
 CDS_PART_NAME='Q_CAP_0402-0.22UF,16V,10%,X7R,CH4223K1B00',
 VOLTAGE='16V',
 ROOM='SCM_P12V_MPS_BOM2',
 PART_NUMBER='CH4223K1B00',
 VALUE='0.22UF',
 PRIM_FILE='./archive_libs/logical/q_cap/chips/chips.prt';

PART_NAME
 PC2230 'Q_CAP_C0402-1UF,25V,10%,X6S,CH5104KEB02':;

SECTION_NUMBER 1
 '@T6G_MB_LIB.T6G(SCH_1):PAGE350_I31@PURE_QUANTA.Q_CAP(CHIPS)':
 C_PATH='@t6g_mb_lib.t6g(sch_1):page350_i31@pure_quanta.q_cap(chips)',
 P_PATH='@t6g_mb_lib.t6g(sch_1):page152_i31@pure_quanta.q_cap(chips)',
 PATH='I31',
 DRAWING='@T6G_MB_LIB.T6G(SCH_1):PAGE350',
 TOLERANCE='10%',
 MATERIAL='X6S',
 PHYS_PAGE='152',
 XY='(325,15625)',
 ROT='0',
 VER='1',
 PACK_TYPE='C0402',
 LOCATION='PC2230',
 CDS_LIB='pure_quanta',
 CDS_PART_NAME='Q_CAP_C0402-1UF,25V,10%,X6S,CH5104KEB02',
 VOLTAGE='25V',
 PART_NUMBER='CH5104KEB02',
 VALUE='1UF',
 PRIM_FILE='./archive_libs/logical/q_cap/chips/chips.prt';

PART_NAME
 PC2231 'Q_CAP_C0402-1UF,25V,10%,X6S,CH5104KEB02':
 ROOM='SCM_P12V_MPS_BOM2';

SECTION_NUMBER 1
 '@T6G_MB_LIB.T6G(SCH_1):PAGE350_I37@PURE_QUANTA.Q_CAP(CHIPS)':
 C_PATH='@t6g_mb_lib.t6g(sch_1):page350_i37@pure_quanta.q_cap(chips)',
 P_PATH='@t6g_mb_lib.t6g(sch_1):page152_i37@pure_quanta.q_cap(chips)',
 PATH='I37',
 DRAWING='@T6G_MB_LIB.T6G(SCH_1):PAGE350',
 TOLERANCE='10%',
 MATERIAL='X6S',
 PHYS_PAGE='152',
 XY='(750,12550)',
 ROT='0',
 VER='1',
 PACK_TYPE='C0402',
 LOCATION='PC2231',
 CDS_LIB='pure_quanta',
 CDS_PART_NAME='Q_CAP_C0402-1UF,25V,10%,X6S,CH5104KEB02',
 VOLTAGE='25V',
 ROOM='SCM_P12V_MPS_BOM2',
 PART_NUMBER='CH5104KEB02',
 VALUE='1UF',
 PRIM_FILE='./archive_libs/logical/q_cap/chips/chips.prt';

PART_NAME
 PC2232 'Q_CAP_C0402-0.047UF,25V,10%,X7R,CH3474K1B04':
 ROOM='SCM_P12V_MPS_BOM2';

SECTION_NUMBER 1
 '@T6G_MB_LIB.T6G(SCH_1):PAGE350_I33@PURE_QUANTA.Q_CAP(CHIPS)':
 C_PATH='@t6g_mb_lib.t6g(sch_1):page350_i33@pure_quanta.q_cap(chips)',
 P_PATH='@t6g_mb_lib.t6g(sch_1):page152_i33@pure_quanta.q_cap(chips)',
 PATH='I33',
 DRAWING='@T6G_MB_LIB.T6G(SCH_1):PAGE350',
 TOLERANCE='10%',
 MATERIAL='X7R',
 PHYS_PAGE='152',
 XY='(825,11475)',
 ROT='0',
 VER='1',
 PACK_TYPE='C0402',
 LOCATION='PC2232',
 CDS_LIB='pure_quanta',
 CDS_PART_NAME='Q_CAP_C0402-0.047UF,25V,10%,X7R,CH3474K1B04',
 VOLTAGE='25V',
 ROOM='SCM_P12V_MPS_BOM2',
 PART_NUMBER='CH3474K1B04',
 VALUE='0.047UF',
 PRIM_FILE='./archive_libs/logical/q_cap/chips/chips.prt';

PART_NAME
 PC2233 'Q_CAP_C0402-1UF,25V,10%,X6S,CH5104KEB02':
 ROOM='SCM_P12V_MAM_BOM1';

SECTION_NUMBER 1
 '@T6G_MB_LIB.T6G(SCH_1):PAGE350_I66@PURE_QUANTA.Q_CAP(CHIPS)':
 C_PATH='@t6g_mb_lib.t6g(sch_1):page350_i66@pure_quanta.q_cap(chips)',
 P_PATH='@t6g_mb_lib.t6g(sch_1):page152_i66@pure_quanta.q_cap(chips)',
 PATH='I66',
 DRAWING='@T6G_MB_LIB.T6G(SCH_1):PAGE350',
 TOLERANCE='10%',
 MATERIAL='X6S',
 PHYS_PAGE='152',
 XY='(1000,15200)',
 ROT='0',
 VER='1',
 PACK_TYPE='C0402',
 LOCATION='PC2233',
 CDS_LIB='pure_quanta',
 CDS_PART_NAME='Q_CAP_C0402-1UF,25V,10%,X6S,CH5104KEB02',
 VOLTAGE='25V',
 ROOM='SCM_P12V_MAM_BOM1',
 PART_NUMBER='CH5104KEB02',
 VALUE='1UF',
 PRIM_FILE='./archive_libs/logical/q_cap/chips/chips.prt';

PART_NAME
 PC2234 'Q_CAP_C0402-1UF,25V,10%,X6S,CH5104KEB02':
 ROOM='SCM_P12V_MAM_BOM1';

SECTION_NUMBER 1
 '@T6G_MB_LIB.T6G(SCH_1):PAGE350_I67@PURE_QUANTA.Q_CAP(CHIPS)':
 C_PATH='@t6g_mb_lib.t6g(sch_1):page350_i67@pure_quanta.q_cap(chips)',
 P_PATH='@t6g_mb_lib.t6g(sch_1):page152_i67@pure_quanta.q_cap(chips)',
 PATH='I67',
 DRAWING='@T6G_MB_LIB.T6G(SCH_1):PAGE350',
 TOLERANCE='10%',
 MATERIAL='X6S',
 PHYS_PAGE='152',
 XY='(1225,14900)',
 ROT='1',
 VER='1',
 PACK_TYPE='C0402',
 LOCATION='PC2234',
 CDS_LIB='pure_quanta',
 CDS_PART_NAME='Q_CAP_C0402-1UF,25V,10%,X6S,CH5104KEB02',
 VOLTAGE='25V',
 ROOM='SCM_P12V_MAM_BOM1',
 PART_NUMBER='CH5104KEB02',
 VALUE='1UF',
 PRIM_FILE='./archive_libs/logical/q_cap/chips/chips.prt';

PART_NAME
 PC2235 'Q_CAP_C0402-100NF,50V,10%,X7R,CH4106K1B01':
 ROOM='SCM_P12V_MPS_BOM2';

SECTION_NUMBER 1
 '@T6G_MB_LIB.T6G(SCH_1):PAGE350_I45@PURE_QUANTA.Q_CAP(CHIPS)':
 C_PATH='@t6g_mb_lib.t6g(sch_1):page350_i45@pure_quanta.q_cap(chips)',
 P_PATH='@t6g_mb_lib.t6g(sch_1):page152_i45@pure_quanta.q_cap(chips)',
 PATH='I45',
 DRAWING='@T6G_MB_LIB.T6G(SCH_1):PAGE350',
 TOLERANCE='10%',
 MATERIAL='X7R',
 PHYS_PAGE='152',
 XY='(2600,11300)',
 ROT='0',
 VER='1',
 PACK_TYPE='C0402',
 LOCATION='PC2235',
 CDS_LIB='pure_quanta',
 CDS_PART_NAME='Q_CAP_C0402-100NF,50V,10%,X7R,CH4106K1B01',
 VOLTAGE='50V',
 ROOM='SCM_P12V_MPS_BOM2',
 PART_NUMBER='CH4106K1B01',
 VALUE='100NF',
 PRIM_FILE='./archive_libs/logical/q_cap/chips/chips.prt';

PART_NAME
 PC2236 'Q_CAP_C0402-0.01UF,50V,10%,EMPTY,CH31006KB18':
 ROOM='SCM_P12V_MAM_BOM1';

SECTION_NUMBER 1
 '@T6G_MB_LIB.T6G(SCH_1):PAGE350_I71@PURE_QUANTA.Q_CAP(CHIPS)':
 C_PATH='@t6g_mb_lib.t6g(sch_1):page350_i71@pure_quanta.q_cap(chips)',
 P_PATH='@t6g_mb_lib.t6g(sch_1):page152_i71@pure_quanta.q_cap(chips)',
 PATH='I71',
 DRAWING='@T6G_MB_LIB.T6G(SCH_1):PAGE350',
 TOLERANCE='10%',
 MATERIAL='EMPTY',
 PHYS_PAGE='152',
 XY='(3075,15225)',
 ROT='0',
 VER='1',
 PACK_TYPE='C0402',
 LOCATION='PC2236',
 CDS_LIB='pure_quanta',
 CDS_PART_NAME='Q_CAP_C0402-0.01UF,50V,10%,EMPTY,CH31006KB18',
 VOLTAGE='50V',
 ROOM='SCM_P12V_MAM_BOM1',
 PART_NUMBER='CH31006KB18',
 VALUE='0.01UF',
 PRIM_FILE='./archive_libs/logical/q_cap/chips/chips.prt';

PART_NAME
 PC2237 'Q_CAP_C0402-3900PF,50V,10%,X7R,CH23906KB14':
 ROOM='SCM_P12V_MAM_BOM1';

SECTION_NUMBER 1
 '@T6G_MB_LIB.T6G(SCH_1):PAGE350_I72@PURE_QUANTA.Q_CAP(CHIPS)':
 C_PATH='@t6g_mb_lib.t6g(sch_1):page350_i72@pure_quanta.q_cap(chips)',
 P_PATH='@t6g_mb_lib.t6g(sch_1):page152_i72@pure_quanta.q_cap(chips)',
 PATH='I72',
 DRAWING='@T6G_MB_LIB.T6G(SCH_1):PAGE350',
 TOLERANCE='10%',
 MATERIAL='X7R',
 PHYS_PAGE='152',
 XY='(3675,15000)',
 ROT='1',
 VER='1',
 PACK_TYPE='C0402',
 LOCATION='PC2237',
 CDS_LIB='pure_quanta',
 CDS_PART_NAME='Q_CAP_C0402-3900PF,50V,10%,X7R,CH23906KB14',
 VOLTAGE='50V',
 ROOM='SCM_P12V_MAM_BOM1',
 PART_NUMBER='CH23906KB14',
 VALUE='3900PF',
 PRIM_FILE='./archive_libs/logical/q_cap/chips/chips.prt';

PART_NAME
 PC2238 'Q_CAP_0402-0.1UF,25V,10%,X7R,CH4104K1B00':;

SECTION_NUMBER 1
 '@T6G_MB_LIB.T6G(SCH_1):PAGE350_I80@PURE_QUANTA.Q_CAP(CHIPS)':
 C_PATH='@t6g_mb_lib.t6g(sch_1):page350_i80@pure_quanta.q_cap(chips)',
 P_PATH='@t6g_mb_lib.t6g(sch_1):page152_i80@pure_quanta.q_cap(chips)',
 PATH='I80',
 DRAWING='@T6G_MB_LIB.T6G(SCH_1):PAGE350',
 TOLERANCE='10%',
 MATERIAL='X7R',
 PHYS_PAGE='152',
 XY='(3975,15825)',
 ROT='0',
 VER='1',
 PACK_TYPE='0402',
 LOCATION='PC2238',
 CDS_LIB='pure_quanta',
 CDS_PART_NAME='Q_CAP_0402-0.1UF,25V,10%,X7R,CH4104K1B00',
 VOLTAGE='25V',
 PART_NUMBER='CH4104K1B00',
 VALUE='0.1UF',
 PRIM_FILE='./archive_libs/logical/q_cap/chips/chips.prt';

PART_NAME
 PC2239 'Q_CAP_C0603-2.2UF,16V,20%,X7R,CH5223M1900':
 ROOM='SCM_P12V_MPS_BOM2';

SECTION_NUMBER 1
 '@T6G_MB_LIB.T6G(SCH_1):PAGE350_I52@PURE_QUANTA.Q_CAP(CHIPS)':
 C_PATH='@t6g_mb_lib.t6g(sch_1):page350_i52@pure_quanta.q_cap(chips)',
 P_PATH='@t6g_mb_lib.t6g(sch_1):page152_i52@pure_quanta.q_cap(chips)',
 PATH='I52',
 DRAWING='@T6G_MB_LIB.T6G(SCH_1):PAGE350',
 TOLERANCE='20%',
 MATERIAL='X7R',
 PHYS_PAGE='152',
 XY='(4150,11625)',
 ROT='0',
 VER='1',
 PACK_TYPE='C0603',
 LOCATION='PC2239',
 CDS_LIB='pure_quanta',
 CDS_PART_NAME='Q_CAP_C0603-2.2UF,16V,20%,X7R,CH5223M1900',
 VOLTAGE='16V',
 ROOM='SCM_P12V_MPS_BOM2',
 PART_NUMBER='CH5223M1900',
 VALUE='2.2UF',
 PRIM_FILE='./archive_libs/logical/q_cap/chips/chips.prt';

PART_NAME
 PC2240 'Q_CAP_C0805-10UF,16V,10%,X6S,CH6103KEA01':;

SECTION_NUMBER 1
 '@T6G_MB_LIB.T6G(SCH_1):PAGE350_I81@PURE_QUANTA.Q_CAP(CHIPS)':
 C_PATH='@t6g_mb_lib.t6g(sch_1):page350_i81@pure_quanta.q_cap(chips)',
 P_PATH='@t6g_mb_lib.t6g(sch_1):page152_i81@pure_quanta.q_cap(chips)',
 PATH='I81',
 DRAWING='@T6G_MB_LIB.T6G(SCH_1):PAGE350',
 TOLERANCE='10%',
 MATERIAL='X6S',
 PHYS_PAGE='152',
 XY='(4400,15825)',
 ROT='0',
 VER='1',
 PACK_TYPE='C0805',
 LOCATION='PC2240',
 CDS_LIB='pure_quanta',
 CDS_PART_NAME='Q_CAP_C0805-10UF,16V,10%,X6S,CH6103KEA01',
 VOLTAGE='16V',
 PART_NUMBER='CH6103KEA01',
 VALUE='10UF',
 PRIM_FILE='./archive_libs/logical/q_cap/chips/chips.prt';

PART_NAME
 PC2241 'Q_CAP_0402-0.1UF,25V,10%,X7R,CH4104K1B00':
 ROOM='SCM_P12V_MPS_BOM2';

SECTION_NUMBER 1
 '@T6G_MB_LIB.T6G(SCH_1):PAGE350_I56@PURE_QUANTA.Q_CAP(CHIPS)':
 C_PATH='@t6g_mb_lib.t6g(sch_1):page350_i56@pure_quanta.q_cap(chips)',
 P_PATH='@t6g_mb_lib.t6g(sch_1):page152_i56@pure_quanta.q_cap(chips)',
 PATH='I56',
 DRAWING='@T6G_MB_LIB.T6G(SCH_1):PAGE350',
 TOLERANCE='10%',
 MATERIAL='X7R',
 PHYS_PAGE='152',
 XY='(4500,12475)',
 ROT='2',
 VER='1',
 PACK_TYPE='0402',
 LOCATION='PC2241',
 CDS_LIB='pure_quanta',
 CDS_PART_NAME='Q_CAP_0402-0.1UF,25V,10%,X7R,CH4104K1B00',
 VOLTAGE='25V',
 ROOM='SCM_P12V_MPS_BOM2',
 PART_NUMBER='CH4104K1B00',
 VALUE='0.1UF',
 PRIM_FILE='./archive_libs/logical/q_cap/chips/chips.prt';

PART_NAME
 PC2242 'Q_CAP_C0805-22UF,16V,20%,X6S,CH6223MEA01':;

SECTION_NUMBER 1
 '@T6G_MB_LIB.T6G(SCH_1):PAGE350_I84@PURE_QUANTA.Q_CAP(CHIPS)':
 C_PATH='@t6g_mb_lib.t6g(sch_1):page350_i84@pure_quanta.q_cap(chips)',
 P_PATH='@t6g_mb_lib.t6g(sch_1):page152_i84@pure_quanta.q_cap(chips)',
 PATH='I84',
 DRAWING='@T6G_MB_LIB.T6G(SCH_1):PAGE350',
 TOLERANCE='20%',
 MATERIAL='X6S',
 PHYS_PAGE='152',
 XY='(4800,15825)',
 ROT='0',
 VER='1',
 PACK_TYPE='C0805',
 LOCATION='PC2242',
 CDS_LIB='pure_quanta',
 CDS_PART_NAME='Q_CAP_C0805-22UF,16V,20%,X6S,CH6223MEA01',
 VOLTAGE='16V',
 PART_NUMBER='CH6223MEA01',
 VALUE='22UF',
 PRIM_FILE='./archive_libs/logical/q_cap/chips/chips.prt';

PART_NAME
 PC2260 'Q_CAP_C0805-22UF,16V,20%,X6S,CH6223MEA01':;

SECTION_NUMBER 1
 '@T6G_MB_LIB.T6G(SCH_1):PAGE245_I26@PURE_QUANTA.Q_CAP(CHIPS)':
 C_PATH='@t6g_mb_lib.t6g(sch_1):page245_i26@pure_quanta.q_cap(chips)',
 P_PATH='@t6g_mb_lib.t6g(sch_1):page190_i26@pure_quanta.q_cap(chips)',
 PATH='I26',
 DRAWING='@T6G_MB_LIB.T6G(SCH_1):PAGE245',
 TOLERANCE='20%',
 MATERIAL='X6S',
 PHYS_PAGE='190',
 XY='(-4050,450)',
 ROT='0',
 VER='1',
 PACK_TYPE='C0805',
 LOCATION='PC2260',
 CDS_LIB='pure_quanta',
 CDS_PART_NAME='Q_CAP_C0805-22UF,16V,20%,X6S,CH6223MEA01',
 VOLTAGE='16V',
 PART_NUMBER='CH6223MEA01',
 VALUE='22UF',
 PRIM_FILE='./archive_libs/logical/q_cap/chips/chips.prt';

PART_NAME
 PC2261 'Q_CAP_C0805-22UF,16V,20%,X6S,CH6223MEA01':;

SECTION_NUMBER 1
 '@T6G_MB_LIB.T6G(SCH_1):PAGE245_I27@PURE_QUANTA.Q_CAP(CHIPS)':
 C_PATH='@t6g_mb_lib.t6g(sch_1):page245_i27@pure_quanta.q_cap(chips)',
 P_PATH='@t6g_mb_lib.t6g(sch_1):page190_i27@pure_quanta.q_cap(chips)',
 PATH='I27',
 DRAWING='@T6G_MB_LIB.T6G(SCH_1):PAGE245',
 TOLERANCE='20%',
 MATERIAL='X6S',
 PHYS_PAGE='190',
 XY='(-3725,450)',
 ROT='0',
 VER='1',
 PACK_TYPE='C0805',
 LOCATION='PC2261',
 CDS_LIB='pure_quanta',
 CDS_PART_NAME='Q_CAP_C0805-22UF,16V,20%,X6S,CH6223MEA01',
 VOLTAGE='16V',
 PART_NUMBER='CH6223MEA01',
 VALUE='22UF',
 PRIM_FILE='./archive_libs/logical/q_cap/chips/chips.prt';

PART_NAME
 PC2262 'Q_CAP_C0805-22UF,16V,20%,X6S,CH6223MEA01':;

SECTION_NUMBER 1
 '@T6G_MB_LIB.T6G(SCH_1):PAGE245_I31@PURE_QUANTA.Q_CAP(CHIPS)':
 C_PATH='@t6g_mb_lib.t6g(sch_1):page245_i31@pure_quanta.q_cap(chips)',
 P_PATH='@t6g_mb_lib.t6g(sch_1):page190_i31@pure_quanta.q_cap(chips)',
 PATH='I31',
 DRAWING='@T6G_MB_LIB.T6G(SCH_1):PAGE245',
 TOLERANCE='20%',
 MATERIAL='X6S',
 PHYS_PAGE='190',
 XY='(-3400,450)',
 ROT='0',
 VER='1',
 PACK_TYPE='C0805',
 LOCATION='PC2262',
 CDS_LIB='pure_quanta',
 CDS_PART_NAME='Q_CAP_C0805-22UF,16V,20%,X6S,CH6223MEA01',
 VOLTAGE='16V',
 PART_NUMBER='CH6223MEA01',
 VALUE='22UF',
 PRIM_FILE='./archive_libs/logical/q_cap/chips/chips.prt';

PART_NAME
 PC2263 'Q_CAP_C0805-22UF,16V,20%,X6S,CH6223MEA01':;

SECTION_NUMBER 1
 '@T6G_MB_LIB.T6G(SCH_1):PAGE245_I33@PURE_QUANTA.Q_CAP(CHIPS)':
 C_PATH='@t6g_mb_lib.t6g(sch_1):page245_i33@pure_quanta.q_cap(chips)',
 P_PATH='@t6g_mb_lib.t6g(sch_1):page190_i33@pure_quanta.q_cap(chips)',
 PATH='I33',
 DRAWING='@T6G_MB_LIB.T6G(SCH_1):PAGE245',
 TOLERANCE='20%',
 MATERIAL='X6S',
 PHYS_PAGE='190',
 XY='(-3075,450)',
 ROT='0',
 VER='1',
 PACK_TYPE='C0805',
 LOCATION='PC2263',
 CDS_LIB='pure_quanta',
 CDS_PART_NAME='Q_CAP_C0805-22UF,16V,20%,X6S,CH6223MEA01',
 VOLTAGE='16V',
 PART_NUMBER='CH6223MEA01',
 VALUE='22UF',
 PRIM_FILE='./archive_libs/logical/q_cap/chips/chips.prt';

PART_NAME
 PC2280 'Q_CAP_C0805-10UF,16V,10%,X6S,CH6103KEA01':;

SECTION_NUMBER 1
 '@T6G_MB_LIB.T6G(SCH_1):PAGE324_I80@PURE_QUANTA.Q_CAP(CHIPS)':
 C_PATH='@t6g_mb_lib.t6g(sch_1):page324_i80@pure_quanta.q_cap(chips)',
 P_PATH='@t6g_mb_lib.t6g(sch_1):page146_i80@pure_quanta.q_cap(chips)',
 PATH='I80',
 DRAWING='@T6G_MB_LIB.T6G(SCH_1):PAGE324',
 TOLERANCE='10%',
 MATERIAL='X6S',
 PHYS_PAGE='146',
 XY='(4000,1575)',
 ROT='0',
 VER='1',
 PACK_TYPE='C0805',
 LOCATION='PC2280',
 CDS_LIB='pure_quanta',
 CDS_PART_NAME='Q_CAP_C0805-10UF,16V,10%,X6S,CH6103KEA01',
 VOLTAGE='16V',
 PART_NUMBER='CH6103KEA01',
 VALUE='10UF',
 PRIM_FILE='./archive_libs/logical/q_cap/chips/chips.prt';

PART_NAME
 PC2281 'Q_CAP_C0402-0.047UF,25V,10%,X7R,CH3474K1B04':
 ROOM='E1S_P12V_MPS_MAM_BOM2';

SECTION_NUMBER 1
 '@T6G_MB_LIB.T6G(SCH_1):PAGE323_I22@PURE_QUANTA.Q_CAP(CHIPS)':
 C_PATH='@t6g_mb_lib.t6g(sch_1):page323_i22@pure_quanta.q_cap(chips)',
 P_PATH='@t6g_mb_lib.t6g(sch_1):page147_i22@pure_quanta.q_cap(chips)',
 PATH='I22',
 DRAWING='@T6G_MB_LIB.T6G(SCH_1):PAGE323',
 TOLERANCE='10%',
 MATERIAL='X7R',
 PHYS_PAGE='147',
 XY='(-750,750)',
 ROT='0',
 VER='1',
 PACK_TYPE='C0402',
 LOCATION='PC2281',
 CDS_LIB='pure_quanta',
 CDS_PART_NAME='Q_CAP_C0402-0.047UF,25V,10%,X7R,CH3474K1B04',
 VOLTAGE='25V',
 ROOM='E1S_P12V_MPS_MAM_BOM2',
 PART_NUMBER='CH3474K1B04',
 VALUE='0.047UF',
 PRIM_FILE='./archive_libs/logical/q_cap/chips/chips.prt';

PART_NAME
 PC2340 'Q_CAP_C0402-560PF,50V,10%,X7R,CH1566K1B09':
 ROOM='SCM_P12V_MPS_BOM2';

SECTION_NUMBER 1
 '@T6G_MB_LIB.T6G(SCH_1):PAGE350_I6@PURE_QUANTA.Q_CAP(CHIPS)':
 C_PATH='@t6g_mb_lib.t6g(sch_1):page350_i6@pure_quanta.q_cap(chips)',
 P_PATH='@t6g_mb_lib.t6g(sch_1):page152_i6@pure_quanta.q_cap(chips)',
 PATH='I6',
 DRAWING='@T6G_MB_LIB.T6G(SCH_1):PAGE350',
 TOLERANCE='10%',
 MATERIAL='X7R',
 PHYS_PAGE='152',
 XY='(350,11250)',
 ROT='0',
 VER='1',
 PACK_TYPE='C0402',
 LOCATION='PC2340',
 CDS_LIB='pure_quanta',
 CDS_PART_NAME='Q_CAP_C0402-560PF,50V,10%,X7R,CH1566K1B09',
 VOLTAGE='50V',
 ROOM='SCM_P12V_MPS_BOM2',
 PART_NUMBER='CH1566K1B09',
 VALUE='560PF',
 PRIM_FILE='./archive_libs/logical/q_cap/chips/chips.prt';

PART_NAME
 PC2341 'Q_CAP_C0402-560PF,50V,10%,X7R,CH1566K1B09':
 ROOM='E1S_P12V_MPS_MAM_BOM2';

SECTION_NUMBER 1
 '@T6G_MB_LIB.T6G(SCH_1):PAGE323_I17@PURE_QUANTA.Q_CAP(CHIPS)':
 C_PATH='@t6g_mb_lib.t6g(sch_1):page323_i17@pure_quanta.q_cap(chips)',
 P_PATH='@t6g_mb_lib.t6g(sch_1):page147_i17@pure_quanta.q_cap(chips)',
 PATH='I17',
 DRAWING='@T6G_MB_LIB.T6G(SCH_1):PAGE323',
 TOLERANCE='10%',
 MATERIAL='X7R',
 PHYS_PAGE='147',
 XY='(-1275,575)',
 ROT='0',
 VER='1',
 PACK_TYPE='C0402',
 LOCATION='PC2341',
 CDS_LIB='pure_quanta',
 CDS_PART_NAME='Q_CAP_C0402-560PF,50V,10%,X7R,CH1566K1B09',
 VOLTAGE='50V',
 ROOM='E1S_P12V_MPS_MAM_BOM2',
 PART_NUMBER='CH1566K1B09',
 VALUE='560PF',
 PRIM_FILE='./archive_libs/logical/q_cap/chips/chips.prt';

PART_NAME
 PC2342 'Q_CAP_C0805-22UF,16V,20%,X6S,CH6223MEA01':;

SECTION_NUMBER 1
 '@T6G_MB_LIB.T6G(SCH_1):PAGE245_I34@PURE_QUANTA.Q_CAP(CHIPS)':
 C_PATH='@t6g_mb_lib.t6g(sch_1):page245_i34@pure_quanta.q_cap(chips)',
 P_PATH='@t6g_mb_lib.t6g(sch_1):page190_i34@pure_quanta.q_cap(chips)',
 PATH='I34',
 DRAWING='@T6G_MB_LIB.T6G(SCH_1):PAGE245',
 TOLERANCE='20%',
 MATERIAL='X6S',
 PHYS_PAGE='190',
 XY='(-2750,450)',
 ROT='0',
 VER='1',
 PACK_TYPE='C0805',
 LOCATION='PC2342',
 CDS_LIB='pure_quanta',
 CDS_PART_NAME='Q_CAP_C0805-22UF,16V,20%,X6S,CH6223MEA01',
 VOLTAGE='16V',
 PART_NUMBER='CH6223MEA01',
 VALUE='22UF',
 PRIM_FILE='./archive_libs/logical/q_cap/chips/chips.prt';

PART_NAME
 PC2343 'Q_CAP_C0805-22UF,16V,20%,X6S,CH6223MEA01':;

SECTION_NUMBER 1
 '@T6G_MB_LIB.T6G(SCH_1):PAGE245_I37@PURE_QUANTA.Q_CAP(CHIPS)':
 C_PATH='@t6g_mb_lib.t6g(sch_1):page245_i37@pure_quanta.q_cap(chips)',
 P_PATH='@t6g_mb_lib.t6g(sch_1):page190_i37@pure_quanta.q_cap(chips)',
 PATH='I37',
 DRAWING='@T6G_MB_LIB.T6G(SCH_1):PAGE245',
 TOLERANCE='20%',
 MATERIAL='X6S',
 PHYS_PAGE='190',
 XY='(-2425,450)',
 ROT='0',
 VER='1',
 PACK_TYPE='C0805',
 LOCATION='PC2343',
 CDS_LIB='pure_quanta',
 CDS_PART_NAME='Q_CAP_C0805-22UF,16V,20%,X6S,CH6223MEA01',
 VOLTAGE='16V',
 PART_NUMBER='CH6223MEA01',
 VALUE='22UF',
 PRIM_FILE='./archive_libs/logical/q_cap/chips/chips.prt';

PART_NAME
 PC2344 'Q_CAP_C0805-22UF,16V,20%,X6S,CH6223MEA01':;

SECTION_NUMBER 1
 '@T6G_MB_LIB.T6G(SCH_1):PAGE245_I38@PURE_QUANTA.Q_CAP(CHIPS)':
 C_PATH='@t6g_mb_lib.t6g(sch_1):page245_i38@pure_quanta.q_cap(chips)',
 P_PATH='@t6g_mb_lib.t6g(sch_1):page190_i38@pure_quanta.q_cap(chips)',
 PATH='I38',
 DRAWING='@T6G_MB_LIB.T6G(SCH_1):PAGE245',
 TOLERANCE='20%',
 MATERIAL='X6S',
 PHYS_PAGE='190',
 XY='(-2100,450)',
 ROT='0',
 VER='1',
 PACK_TYPE='C0805',
 LOCATION='PC2344',
 CDS_LIB='pure_quanta',
 CDS_PART_NAME='Q_CAP_C0805-22UF,16V,20%,X6S,CH6223MEA01',
 VOLTAGE='16V',
 PART_NUMBER='CH6223MEA01',
 VALUE='22UF',
 PRIM_FILE='./archive_libs/logical/q_cap/chips/chips.prt';

PART_NAME
 PC2347 'Q_CAP_0402-1NF,50V,10%,EMPTY,CH21006KB16':
 ROOM='HSC BOM1';

SECTION_NUMBER 1
 '@T6G_MB_LIB.T6G(SCH_1):PAGE301_I30@PURE_QUANTA.Q_CAP(CHIPS)':
 C_PATH='@t6g_mb_lib.t6g(sch_1):page301_i30@pure_quanta.q_cap(chips)',
 P_PATH='@t6g_mb_lib.t6g(sch_1):page263_i30@pure_quanta.q_cap(chips)',
 PATH='I30',
 DRAWING='@T6G_MB_LIB.T6G(SCH_1):PAGE301',
 TOLERANCE='10%',
 MATERIAL='EMPTY',
 PHYS_PAGE='263',
 XY='(-2000,725)',
 ROT='0',
 VER='1',
 PACK_TYPE='0402',
 LOCATION='PC2347',
 CDS_LIB='pure_quanta',
 CDS_PART_NAME='Q_CAP_0402-1NF,50V,10%,EMPTY,CH21006KB16',
 VOLTAGE='50V',
 ROOM='HSC BOM1',
 PART_NUMBER='CH21006KB16',
 VALUE='1NF',
 PRIM_FILE='./archive_libs/logical/q_cap/chips/chips.prt';

PART_NAME
 PC2348 'Q_CAP_0402-1NF,50V,10%,EMPTY,CH21006KB16':
 ROOM='HSC BOM1';

SECTION_NUMBER 1
 '@T6G_MB_LIB.T6G(SCH_1):PAGE301_I12@PURE_QUANTA.Q_CAP(CHIPS)':
 C_PATH='@t6g_mb_lib.t6g(sch_1):page301_i12@pure_quanta.q_cap(chips)',
 P_PATH='@t6g_mb_lib.t6g(sch_1):page263_i12@pure_quanta.q_cap(chips)',
 PATH='I12',
 DRAWING='@T6G_MB_LIB.T6G(SCH_1):PAGE301',
 TOLERANCE='10%',
 MATERIAL='EMPTY',
 PHYS_PAGE='263',
 XY='(-1975,-2075)',
 ROT='0',
 VER='1',
 PACK_TYPE='0402',
 LOCATION='PC2348',
 CDS_LIB='pure_quanta',
 CDS_PART_NAME='Q_CAP_0402-1NF,50V,10%,EMPTY,CH21006KB16',
 VOLTAGE='50V',
 ROOM='HSC BOM1',
 PART_NUMBER='CH21006KB16',
 VALUE='1NF',
 PRIM_FILE='./archive_libs/logical/q_cap/chips/chips.prt';

PART_NAME
 PC2349 'Q_CAP_0402-1NF,50V,10%,EMPTY,CH21006KB16':
 ROOM='HSC BOM1';

SECTION_NUMBER 1
 '@T6G_MB_LIB.T6G(SCH_1):PAGE325_I12@PURE_QUANTA.Q_CAP(CHIPS)':
 C_PATH='@t6g_mb_lib.t6g(sch_1):page325_i12@pure_quanta.q_cap(chips)',
 P_PATH='@t6g_mb_lib.t6g(sch_1):page264_i12@pure_quanta.q_cap(chips)',
 PATH='I12',
 DRAWING='@T6G_MB_LIB.T6G(SCH_1):PAGE325',
 TOLERANCE='10%',
 MATERIAL='EMPTY',
 PHYS_PAGE='264',
 XY='(-1975,-1950)',
 ROT='0',
 VER='1',
 PACK_TYPE='0402',
 LOCATION='PC2349',
 CDS_LIB='pure_quanta',
 CDS_PART_NAME='Q_CAP_0402-1NF,50V,10%,EMPTY,CH21006KB16',
 VOLTAGE='50V',
 ROOM='HSC BOM1',
 PART_NUMBER='CH21006KB16',
 VALUE='1NF',
 PRIM_FILE='./archive_libs/logical/q_cap/chips/chips.prt';

PART_NAME
 PC2350 'Q_CAP_0402-1NF,50V,10%,EMPTY,CH21006KB16':
 ROOM='HSC BOM1';

SECTION_NUMBER 1
 '@T6G_MB_LIB.T6G(SCH_1):PAGE325_I30@PURE_QUANTA.Q_CAP(CHIPS)':
 C_PATH='@t6g_mb_lib.t6g(sch_1):page325_i30@pure_quanta.q_cap(chips)',
 P_PATH='@t6g_mb_lib.t6g(sch_1):page264_i30@pure_quanta.q_cap(chips)',
 PATH='I30',
 DRAWING='@T6G_MB_LIB.T6G(SCH_1):PAGE325',
 TOLERANCE='10%',
 MATERIAL='EMPTY',
 PHYS_PAGE='264',
 XY='(-1950,825)',
 ROT='0',
 VER='1',
 PACK_TYPE='0402',
 LOCATION='PC2350',
 CDS_LIB='pure_quanta',
 CDS_PART_NAME='Q_CAP_0402-1NF,50V,10%,EMPTY,CH21006KB16',
 VOLTAGE='50V',
 ROOM='HSC BOM1',
 PART_NUMBER='CH21006KB16',
 VALUE='1NF',
 PRIM_FILE='./archive_libs/logical/q_cap/chips/chips.prt';

PART_NAME
 PC3272 'Q_CAP_C0402-1UF,25V,10%,X6S,CH5104KEB02':
 ROOM='HSC BOM1';

SECTION_NUMBER 1
 '@T6G_MB_LIB.T6G(SCH_1):PAGE325_I20@PURE_QUANTA.Q_CAP(CHIPS)':
 C_PATH='@t6g_mb_lib.t6g(sch_1):page325_i20@pure_quanta.q_cap(chips)',
 P_PATH='@t6g_mb_lib.t6g(sch_1):page264_i20@pure_quanta.q_cap(chips)',
 PATH='I20',
 DRAWING='@T6G_MB_LIB.T6G(SCH_1):PAGE325',
 TOLERANCE='10%',
 MATERIAL='X6S',
 PHYS_PAGE='264',
 XY='(-3600,1475)',
 ROT='0',
 VER='1',
 PACK_TYPE='C0402',
 LOCATION='PC3272',
 CDS_LIB='pure_quanta',
 CDS_PART_NAME='Q_CAP_C0402-1UF,25V,10%,X6S,CH5104KEB02',
 VOLTAGE='25V',
 ROOM='HSC BOM1',
 PART_NUMBER='CH5104KEB02',
 VALUE='1UF',
 PRIM_FILE='./archive_libs/logical/q_cap/chips/chips.prt';

PART_NAME
 PC4056 'Q_CAP_C0402-3900PF,50V,10%,X7R,CH23906KB14':
 ROOM='NIC_P12V_MAM_TIC_BOM1';

SECTION_NUMBER 1
 '@T6G_MB_LIB.T6G(SCH_1):PAGE338_I77@PURE_QUANTA.Q_CAP(CHIPS)':
 C_PATH='@t6g_mb_lib.t6g(sch_1):page338_i77@pure_quanta.q_cap(chips)',
 P_PATH='@t6g_mb_lib.t6g(sch_1):page134_i77@pure_quanta.q_cap(chips)',
 PATH='I77',
 DRAWING='@T6G_MB_LIB.T6G(SCH_1):PAGE338',
 TOLERANCE='10%',
 MATERIAL='X7R',
 PHYS_PAGE='134',
 XY='(9075,10825)',
 ROT='1',
 VER='1',
 PACK_TYPE='C0402',
 LOCATION='PC4056',
 CDS_LIB='pure_quanta',
 CDS_PART_NAME='Q_CAP_C0402-3900PF,50V,10%,X7R,CH23906KB14',
 VOLTAGE='50V',
 ROOM='NIC_P12V_MAM_TIC_BOM1',
 PART_NUMBER='CH23906KB14',
 VALUE='3900PF',
 PRIM_FILE='./archive_libs/logical/q_cap/chips/chips.prt';

PART_NAME
 PC5328 'Q_CAP_C0402-1UF,25V,10%,X6S,CH5104KEB02':;

SECTION_NUMBER 1
 '@T6G_MB_LIB.T6G(SCH_1):PAGE338_I62@PURE_QUANTA.Q_CAP(CHIPS)':
 C_PATH='@t6g_mb_lib.t6g(sch_1):page338_i62@pure_quanta.q_cap(chips)',
 P_PATH='@t6g_mb_lib.t6g(sch_1):page134_i62@pure_quanta.q_cap(chips)',
 PATH='I62',
 DRAWING='@T6G_MB_LIB.T6G(SCH_1):PAGE338',
 TOLERANCE='10%',
 MATERIAL='X6S',
 PHYS_PAGE='134',
 XY='(5900,13500)',
 ROT='0',
 VER='1',
 PACK_TYPE='C0402',
 LOCATION='PC5328',
 CDS_LIB='pure_quanta',
 CDS_PART_NAME='Q_CAP_C0402-1UF,25V,10%,X6S,CH5104KEB02',
 VOLTAGE='25V',
 PART_NUMBER='CH5104KEB02',
 VALUE='1UF',
 PRIM_FILE='./archive_libs/logical/q_cap/chips/chips.prt';

PART_NAME
 PC6000 'Q_CAP_C0402-0.1UF,25V,10%,X6S,CH4104KEB00':;

SECTION_NUMBER 1
 '@T6G_MB_LIB.T6G(SCH_1):PAGE167_I8@PURE_QUANTA.Q_CAP(CHIPS)':
 C_PATH='@t6g_mb_lib.t6g(sch_1):page167_i8@pure_quanta.q_cap(chips)',
 P_PATH='@t6g_mb_lib.t6g(sch_1):page192_i8@pure_quanta.q_cap(chips)',
 PATH='I8',
 DRAWING='@T6G_MB_LIB.T6G(SCH_1):PAGE167',
 TOLERANCE='10%',
 MATERIAL='X6S',
 PHYS_PAGE='192',
 XY='(-10550,4450)',
 ROT='0',
 VER='1',
 PACK_TYPE='C0402',
 LOCATION='PC6000',
 CDS_LIB='pure_quanta',
 CDS_PART_NAME='Q_CAP_C0402-0.1UF,25V,10%,X6S,CH4104KEB00',
 VOLTAGE='25V',
 PART_NUMBER='CH4104KEB00',
 VALUE='0.1UF',
 PRIM_FILE='./archive_libs/logical/q_cap/chips/chips.prt';

PART_NAME
 PC6001 'Q_CAP_C0402-0.1UF,25V,10%,X6S,CH4104KEB00':;

SECTION_NUMBER 1
 '@T6G_MB_LIB.T6G(SCH_1):PAGE184_I5@PURE_QUANTA.Q_CAP(CHIPS)':
 C_PATH='@t6g_mb_lib.t6g(sch_1):page184_i5@pure_quanta.q_cap(chips)',
 P_PATH='@t6g_mb_lib.t6g(sch_1):page209_i5@pure_quanta.q_cap(chips)',
 PATH='I5',
 DRAWING='@T6G_MB_LIB.T6G(SCH_1):PAGE184',
 TOLERANCE='10%',
 MATERIAL='X6S',
 PHYS_PAGE='209',
 XY='(-9225,4150)',
 ROT='0',
 VER='1',
 PACK_TYPE='C0402',
 LOCATION='PC6001',
 CDS_LIB='pure_quanta',
 CDS_PART_NAME='Q_CAP_C0402-0.1UF,25V,10%,X6S,CH4104KEB00',
 VOLTAGE='25V',
 PART_NUMBER='CH4104KEB00',
 VALUE='0.1UF',
 PRIM_FILE='./archive_libs/logical/q_cap/chips/chips.prt';

PART_NAME
 PC6002 'Q_CAP_0402-0.1UF,25V,10%,X7R,CH4104K1B00':
 SIGNAL_MODEL='DEFAULT_CAPACITOR_100000PF_2_1';

SECTION_NUMBER 1
 '@T6G_MB_LIB.T6G(SCH_1):PAGE201_I3@PURE_QUANTA.Q_CAP(CHIPS)':
 C_PATH='@t6g_mb_lib.t6g(sch_1):page201_i3@pure_quanta.q_cap(chips)',
 P_PATH='@t6g_mb_lib.t6g(sch_1):page226_i3@pure_quanta.q_cap(chips)',
 PATH='I3',
 DRAWING='@T6G_MB_LIB.T6G(SCH_1):PAGE201',
 TOLERANCE='10%',
 MATERIAL='X7R',
 PHYS_PAGE='226',
 XY='(-8800,4575)',
 ROT='0',
 VER='1',
 PACK_TYPE='0402',
 LOCATION='PC6002',
 CDS_LIB='pure_quanta',
 CDS_PART_NAME='Q_CAP_0402-0.1UF,25V,10%,X7R,CH4104K1B00',
 SIGNAL_MODEL='DEFAULT_CAPACITOR_100000PF_2_1',
 VOLTAGE='25V',
 PART_NUMBER='CH4104K1B00',
 VALUE='0.1UF',
 PRIM_FILE='./archive_libs/logical/q_cap/chips/chips.prt';

PART_NAME
 PC6003 'Q_CAP_0402-0.1UF,25V,10%,X7R,CH4104K1B00':;

SECTION_NUMBER 1
 '@T6G_MB_LIB.T6G(SCH_1):PAGE183_I79@PURE_QUANTA.Q_CAP(CHIPS)':
 C_PATH='@t6g_mb_lib.t6g(sch_1):page183_i79@pure_quanta.q_cap(chips)',
 P_PATH='@t6g_mb_lib.t6g(sch_1):page208_i79@pure_quanta.q_cap(chips)',
 PATH='I79',
 DRAWING='@T6G_MB_LIB.T6G(SCH_1):PAGE183',
 TOLERANCE='10%',
 MATERIAL='X7R',
 PHYS_PAGE='208',
 XY='(-2275,5300)',
 ROT='0',
 VER='1',
 PACK_TYPE='0402',
 LOCATION='PC6003',
 CDS_LIB='pure_quanta',
 CDS_PART_NAME='Q_CAP_0402-0.1UF,25V,10%,X7R,CH4104K1B00',
 VOLTAGE='25V',
 PART_NUMBER='CH4104K1B00',
 VALUE='0.1UF',
 PRIM_FILE='./archive_libs/logical/q_cap/chips/chips.prt';

PART_NAME
 PC6004 'Q_CAP_0402-0.1UF,25V,10%,X7R,CH4104K1B00':;

SECTION_NUMBER 1
 '@T6G_MB_LIB.T6G(SCH_1):PAGE186_I74@PURE_QUANTA.Q_CAP(CHIPS)':
 C_PATH='@t6g_mb_lib.t6g(sch_1):page186_i74@pure_quanta.q_cap(chips)',
 P_PATH='@t6g_mb_lib.t6g(sch_1):page211_i74@pure_quanta.q_cap(chips)',
 PATH='I74',
 DRAWING='@T6G_MB_LIB.T6G(SCH_1):PAGE186',
 TOLERANCE='10%',
 MATERIAL='X7R',
 PHYS_PAGE='211',
 XY='(-2550,5350)',
 ROT='0',
 VER='1',
 PACK_TYPE='0402',
 LOCATION='PC6004',
 CDS_LIB='pure_quanta',
 CDS_PART_NAME='Q_CAP_0402-0.1UF,25V,10%,X7R,CH4104K1B00',
 VOLTAGE='25V',
 PART_NUMBER='CH4104K1B00',
 VALUE='0.1UF',
 PRIM_FILE='./archive_libs/logical/q_cap/chips/chips.prt';

PART_NAME
 PC6005 'Q_CAP_C0402-0.01UF,25V,10%,EMPTY,CH3104K1B11':;

SECTION_NUMBER 1
 '@T6G_MB_LIB.T6G(SCH_1):PAGE184_I34@PURE_QUANTA.Q_CAP(CHIPS)':
 C_PATH='@t6g_mb_lib.t6g(sch_1):page184_i34@pure_quanta.q_cap(chips)',
 P_PATH='@t6g_mb_lib.t6g(sch_1):page209_i34@pure_quanta.q_cap(chips)',
 PATH='I34',
 DRAWING='@T6G_MB_LIB.T6G(SCH_1):PAGE184',
 TOLERANCE='10%',
 MATERIAL='EMPTY',
 PHYS_PAGE='209',
 XY='(-3150,2175)',
 ROT='0',
 VER='1',
 PACK_TYPE='C0402',
 LOCATION='PC6005',
 CDS_LIB='pure_quanta',
 CDS_PART_NAME='Q_CAP_C0402-0.01UF,25V,10%,EMPTY,CH3104K1B11',
 VOLTAGE='25V',
 PART_NUMBER='CH3104K1B11',
 VALUE='0.01UF',
 PRIM_FILE='./archive_libs/logical/q_cap/chips/chips.prt';

PART_NAME
 PC6006 'Q_CAP_C0402-0.01UF,25V,10%,EMPTY,CH3104K1B11':;

SECTION_NUMBER 1
 '@T6G_MB_LIB.T6G(SCH_1):PAGE201_I34@PURE_QUANTA.Q_CAP(CHIPS)':
 C_PATH='@t6g_mb_lib.t6g(sch_1):page201_i34@pure_quanta.q_cap(chips)',
 P_PATH='@t6g_mb_lib.t6g(sch_1):page226_i34@pure_quanta.q_cap(chips)',
 PATH='I34',
 DRAWING='@T6G_MB_LIB.T6G(SCH_1):PAGE201',
 TOLERANCE='10%',
 MATERIAL='EMPTY',
 PHYS_PAGE='226',
 XY='(-2750,2625)',
 ROT='0',
 VER='1',
 PACK_TYPE='C0402',
 LOCATION='PC6006',
 CDS_LIB='pure_quanta',
 CDS_PART_NAME='Q_CAP_C0402-0.01UF,25V,10%,EMPTY,CH3104K1B11',
 VOLTAGE='25V',
 PART_NUMBER='CH3104K1B11',
 VALUE='0.01UF',
 PRIM_FILE='./archive_libs/logical/q_cap/chips/chips.prt';

PART_NAME
 PC6007 'Q_CAP_0402-0.1UF,25V,10%,X7R,CH4104K1B00':;

SECTION_NUMBER 1
 '@T6G_MB_LIB.T6G(SCH_1):PAGE190_I77@PURE_QUANTA.Q_CAP(CHIPS)':
 C_PATH='@t6g_mb_lib.t6g(sch_1):page190_i77@pure_quanta.q_cap(chips)',
 P_PATH='@t6g_mb_lib.t6g(sch_1):page215_i77@pure_quanta.q_cap(chips)',
 PATH='I77',
 DRAWING='@T6G_MB_LIB.T6G(SCH_1):PAGE190',
 TOLERANCE='10%',
 MATERIAL='X7R',
 PHYS_PAGE='215',
 XY='(-2625,5625)',
 ROT='0',
 VER='1',
 PACK_TYPE='0402',
 LOCATION='PC6007',
 CDS_LIB='pure_quanta',
 CDS_PART_NAME='Q_CAP_0402-0.1UF,25V,10%,X7R,CH4104K1B00',
 VOLTAGE='25V',
 PART_NUMBER='CH4104K1B00',
 VALUE='0.1UF',
 PRIM_FILE='./archive_libs/logical/q_cap/chips/chips.prt';

PART_NAME
 PC6008 'Q_CAP_C0402-1UF,25V,10%,X6S,CH5104KEB02':;

SECTION_NUMBER 1
 '@T6G_MB_LIB.T6G(SCH_1):PAGE315_I13@PURE_QUANTA.Q_CAP(CHIPS)':
 C_PATH='@t6g_mb_lib.t6g(sch_1):page315_i13@pure_quanta.q_cap(chips)',
 P_PATH='@t6g_mb_lib.t6g(sch_1):page269_i13@pure_quanta.q_cap(chips)',
 PATH='I13',
 DRAWING='@T6G_MB_LIB.T6G(SCH_1):PAGE315',
 TOLERANCE='10%',
 MATERIAL='X6S',
 PHYS_PAGE='269',
 XY='(-2225,1375)',
 ROT='0',
 VER='1',
 PACK_TYPE='C0402',
 LOCATION='PC6008',
 CDS_LIB='pure_quanta',
 CDS_PART_NAME='Q_CAP_C0402-1UF,25V,10%,X6S,CH5104KEB02',
 VOLTAGE='25V',
 PART_NUMBER='CH5104KEB02',
 VALUE='1UF',
 PRIM_FILE='./archive_libs/logical/q_cap/chips/chips.prt';

PART_NAME
 PC6009 'Q_CAP_C0402-1UF,25V,10%,X6S,CH5104KEB02':;

SECTION_NUMBER 1
 '@T6G_MB_LIB.T6G(SCH_1):PAGE380_I7@PURE_QUANTA.Q_CAP(CHIPS)':
 C_PATH='@t6g_mb_lib.t6g(sch_1):page380_i7@pure_quanta.q_cap(chips)',
 P_PATH='@t6g_mb_lib.t6g(sch_1):page270_i7@pure_quanta.q_cap(chips)',
 PATH='I7',
 DRAWING='@T6G_MB_LIB.T6G(SCH_1):PAGE380',
 TOLERANCE='10%',
 MATERIAL='X6S',
 PHYS_PAGE='270',
 XY='(-5800,1350)',
 ROT='0',
 VER='1',
 PACK_TYPE='C0402',
 LOCATION='PC6009',
 CDS_LIB='pure_quanta',
 CDS_PART_NAME='Q_CAP_C0402-1UF,25V,10%,X6S,CH5104KEB02',
 VOLTAGE='25V',
 PART_NUMBER='CH5104KEB02',
 VALUE='1UF',
 PRIM_FILE='./archive_libs/logical/q_cap/chips/chips.prt';

PART_NAME
 PC6010 'Q_CAP_C0402-1UF,25V,10%,X6S,CH5104KEB02':;

SECTION_NUMBER 1
 '@T6G_MB_LIB.T6G(SCH_1):PAGE315_I19@PURE_QUANTA.Q_CAP(CHIPS)':
 C_PATH='@t6g_mb_lib.t6g(sch_1):page315_i19@pure_quanta.q_cap(chips)',
 P_PATH='@t6g_mb_lib.t6g(sch_1):page269_i19@pure_quanta.q_cap(chips)',
 PATH='I19',
 DRAWING='@T6G_MB_LIB.T6G(SCH_1):PAGE315',
 TOLERANCE='10%',
 MATERIAL='X6S',
 PHYS_PAGE='269',
 XY='(-2125,2525)',
 ROT='0',
 VER='1',
 PACK_TYPE='C0402',
 LOCATION='PC6010',
 CDS_LIB='pure_quanta',
 CDS_PART_NAME='Q_CAP_C0402-1UF,25V,10%,X6S,CH5104KEB02',
 VOLTAGE='25V',
 PART_NUMBER='CH5104KEB02',
 VALUE='1UF',
 PRIM_FILE='./archive_libs/logical/q_cap/chips/chips.prt';

PART_NAME
 PC6011 'Q_CAP_C0402-1UF,25V,10%,X6S,CH5104KEB02':;

SECTION_NUMBER 1
 '@T6G_MB_LIB.T6G(SCH_1):PAGE380_I12@PURE_QUANTA.Q_CAP(CHIPS)':
 C_PATH='@t6g_mb_lib.t6g(sch_1):page380_i12@pure_quanta.q_cap(chips)',
 P_PATH='@t6g_mb_lib.t6g(sch_1):page270_i12@pure_quanta.q_cap(chips)',
 PATH='I12',
 DRAWING='@T6G_MB_LIB.T6G(SCH_1):PAGE380',
 TOLERANCE='10%',
 MATERIAL='X6S',
 PHYS_PAGE='270',
 XY='(-5700,2500)',
 ROT='0',
 VER='1',
 PACK_TYPE='C0402',
 LOCATION='PC6011',
 CDS_LIB='pure_quanta',
 CDS_PART_NAME='Q_CAP_C0402-1UF,25V,10%,X6S,CH5104KEB02',
 VOLTAGE='25V',
 PART_NUMBER='CH5104KEB02',
 VALUE='1UF',
 PRIM_FILE='./archive_libs/logical/q_cap/chips/chips.prt';

PART_NAME
 PC6012 'Q_CAP_C0805-22UF,16V,20%,X6S,CH6223MEA01':;

SECTION_NUMBER 1
 '@T6G_MB_LIB.T6G(SCH_1):PAGE315_I8@PURE_QUANTA.Q_CAP(CHIPS)':
 C_PATH='@t6g_mb_lib.t6g(sch_1):page315_i8@pure_quanta.q_cap(chips)',
 P_PATH='@t6g_mb_lib.t6g(sch_1):page269_i8@pure_quanta.q_cap(chips)',
 PATH='I8',
 DRAWING='@T6G_MB_LIB.T6G(SCH_1):PAGE315',
 TOLERANCE='20%',
 MATERIAL='X6S',
 PHYS_PAGE='269',
 XY='(-3325,2525)',
 ROT='0',
 VER='1',
 PACK_TYPE='C0805',
 LOCATION='PC6012',
 CDS_LIB='pure_quanta',
 CDS_PART_NAME='Q_CAP_C0805-22UF,16V,20%,X6S,CH6223MEA01',
 VOLTAGE='16V',
 PART_NUMBER='CH6223MEA01',
 VALUE='22UF',
 PRIM_FILE='./archive_libs/logical/q_cap/chips/chips.prt';

PART_NAME
 PC6013 'Q_CAP_C0805-22UF,16V,20%,X6S,CH6223MEA01':;

SECTION_NUMBER 1
 '@T6G_MB_LIB.T6G(SCH_1):PAGE380_I3@PURE_QUANTA.Q_CAP(CHIPS)':
 C_PATH='@t6g_mb_lib.t6g(sch_1):page380_i3@pure_quanta.q_cap(chips)',
 P_PATH='@t6g_mb_lib.t6g(sch_1):page270_i3@pure_quanta.q_cap(chips)',
 PATH='I3',
 DRAWING='@T6G_MB_LIB.T6G(SCH_1):PAGE380',
 TOLERANCE='20%',
 MATERIAL='X6S',
 PHYS_PAGE='270',
 XY='(-6900,2500)',
 ROT='0',
 VER='1',
 PACK_TYPE='C0805',
 LOCATION='PC6013',
 CDS_LIB='pure_quanta',
 CDS_PART_NAME='Q_CAP_C0805-22UF,16V,20%,X6S,CH6223MEA01',
 VOLTAGE='16V',
 PART_NUMBER='CH6223MEA01',
 VALUE='22UF',
 PRIM_FILE='./archive_libs/logical/q_cap/chips/chips.prt';

PART_NAME
 PC6014 'Q_CAP_C0805-22UF,16V,20%,X6S,CH6223MEA01':;

SECTION_NUMBER 1
 '@T6G_MB_LIB.T6G(SCH_1):PAGE315_I10@PURE_QUANTA.Q_CAP(CHIPS)':
 C_PATH='@t6g_mb_lib.t6g(sch_1):page315_i10@pure_quanta.q_cap(chips)',
 P_PATH='@t6g_mb_lib.t6g(sch_1):page269_i10@pure_quanta.q_cap(chips)',
 PATH='I10',
 DRAWING='@T6G_MB_LIB.T6G(SCH_1):PAGE315',
 TOLERANCE='20%',
 MATERIAL='X6S',
 PHYS_PAGE='269',
 XY='(-2725,2525)',
 ROT='0',
 VER='1',
 PACK_TYPE='C0805',
 LOCATION='PC6014',
 CDS_LIB='pure_quanta',
 CDS_PART_NAME='Q_CAP_C0805-22UF,16V,20%,X6S,CH6223MEA01',
 VOLTAGE='16V',
 PART_NUMBER='CH6223MEA01',
 VALUE='22UF',
 PRIM_FILE='./archive_libs/logical/q_cap/chips/chips.prt';

PART_NAME
 PC6015 'Q_CAP_C0805-22UF,16V,20%,X6S,CH6223MEA01':;

SECTION_NUMBER 1
 '@T6G_MB_LIB.T6G(SCH_1):PAGE380_I10@PURE_QUANTA.Q_CAP(CHIPS)':
 C_PATH='@t6g_mb_lib.t6g(sch_1):page380_i10@pure_quanta.q_cap(chips)',
 P_PATH='@t6g_mb_lib.t6g(sch_1):page270_i10@pure_quanta.q_cap(chips)',
 PATH='I10',
 DRAWING='@T6G_MB_LIB.T6G(SCH_1):PAGE380',
 TOLERANCE='20%',
 MATERIAL='X6S',
 PHYS_PAGE='270',
 XY='(-6300,2500)',
 ROT='0',
 VER='1',
 PACK_TYPE='C0805',
 LOCATION='PC6015',
 CDS_LIB='pure_quanta',
 CDS_PART_NAME='Q_CAP_C0805-22UF,16V,20%,X6S,CH6223MEA01',
 VOLTAGE='16V',
 PART_NUMBER='CH6223MEA01',
 VALUE='22UF',
 PRIM_FILE='./archive_libs/logical/q_cap/chips/chips.prt';

PART_NAME
 PC6016 'Q_CAP_0402-3300PF,50V,10%,X7R,TMP_QCH2336K1B12':;

SECTION_NUMBER 1
 '@T6G_MB_LIB.T6G(SCH_1):PAGE380_I17@PURE_QUANTA.Q_CAP(CHIPS)':
 C_PATH='@t6g_mb_lib.t6g(sch_1):page380_i17@pure_quanta.q_cap(chips)',
 P_PATH='@t6g_mb_lib.t6g(sch_1):page270_i17@pure_quanta.q_cap(chips)',
 PATH='I17',
 DRAWING='@T6G_MB_LIB.T6G(SCH_1):PAGE380',
 TOLERANCE='10%',
 MATERIAL='X7R',
 PHYS_PAGE='270',
 XY='(-3700,1025)',
 ROT='0',
 VER='1',
 PACK_TYPE='0402',
 LOCATION='PC6016',
 CDS_LIB='pure_quanta',
 CDS_PART_NAME='Q_CAP_0402-3300PF,50V,10%,X7R,TMP_QCH2336K1B12',
 VOLTAGE='50V',
 PART_NUMBER='TMP_QCH2336K1B12',
 VALUE='3300PF',
 PRIM_FILE='./archive_libs/logical/q_cap/chips/chips.prt';

PART_NAME
 PC6017 'Q_CAP_C0402-0.22UF,25V,10%,X7R,CH4224K1B01':;

SECTION_NUMBER 1
 '@T6G_MB_LIB.T6G(SCH_1):PAGE380_I18@PURE_QUANTA.Q_CAP(CHIPS)':
 C_PATH='@t6g_mb_lib.t6g(sch_1):page380_i18@pure_quanta.q_cap(chips)',
 P_PATH='@t6g_mb_lib.t6g(sch_1):page270_i18@pure_quanta.q_cap(chips)',
 PATH='I18',
 DRAWING='@T6G_MB_LIB.T6G(SCH_1):PAGE380',
 TOLERANCE='10%',
 MATERIAL='X7R',
 PHYS_PAGE='270',
 XY='(-3200,2175)',
 ROT='0',
 VER='1',
 PACK_TYPE='C0402',
 LOCATION='PC6017',
 CDS_LIB='pure_quanta',
 CDS_PART_NAME='Q_CAP_C0402-0.22UF,25V,10%,X7R,CH4224K1B01',
 VOLTAGE='25V',
 PART_NUMBER='CH4224K1B01',
 VALUE='0.22UF',
 PRIM_FILE='./archive_libs/logical/q_cap/chips/chips.prt';

PART_NAME
 PC6018 'Q_CAP_C0805-22UF,4V,20%,X6S,CH622KMEA03':;

SECTION_NUMBER 1
 '@T6G_MB_LIB.T6G(SCH_1):PAGE380_I33@PURE_QUANTA.Q_CAP(CHIPS)':
 C_PATH='@t6g_mb_lib.t6g(sch_1):page380_i33@pure_quanta.q_cap(chips)',
 P_PATH='@t6g_mb_lib.t6g(sch_1):page270_i33@pure_quanta.q_cap(chips)',
 PATH='I33',
 DRAWING='@T6G_MB_LIB.T6G(SCH_1):PAGE380',
 TOLERANCE='20%',
 MATERIAL='X6S',
 PHYS_PAGE='270',
 XY='(-800,1800)',
 ROT='0',
 VER='1',
 PACK_TYPE='C0805',
 LOCATION='PC6018',
 CDS_LIB='pure_quanta',
 CDS_PART_NAME='Q_CAP_C0805-22UF,4V,20%,X6S,CH622KMEA03',
 VOLTAGE='4V',
 PART_NUMBER='CH622KMEA03',
 VALUE='22UF',
 PRIM_FILE='./archive_libs/logical/q_cap/chips/chips.prt';

PART_NAME
 PC6019 'Q_CAP_0402-330PF,50V,10%,X7R,CH1336K1B02':;

SECTION_NUMBER 1
 '@T6G_MB_LIB.T6G(SCH_1):PAGE315_I26@PURE_QUANTA.Q_CAP(CHIPS)':
 C_PATH='@t6g_mb_lib.t6g(sch_1):page315_i26@pure_quanta.q_cap(chips)',
 P_PATH='@t6g_mb_lib.t6g(sch_1):page269_i26@pure_quanta.q_cap(chips)',
 PATH='I26',
 DRAWING='@T6G_MB_LIB.T6G(SCH_1):PAGE315',
 TOLERANCE='10%',
 MATERIAL='X7R',
 PHYS_PAGE='269',
 XY='(1525,825)',
 ROT='0',
 VER='2',
 PACK_TYPE='0402',
 LOCATION='PC6019',
 CDS_LIB='pure_quanta',
 CDS_PART_NAME='Q_CAP_0402-330PF,50V,10%,X7R,CH1336K1B02',
 VOLTAGE='50V',
 PART_NUMBER='CH1336K1B02',
 VALUE='330PF',
 PRIM_FILE='./archive_libs/logical/q_cap/chips/chips.prt';

PART_NAME
 PC6020 'Q_CAP_C0402-100NF,50V,10%,X7R,CH4106K1B01':;

SECTION_NUMBER 1
 '@T6G_MB_LIB.T6G(SCH_1):PAGE315_I5@PURE_QUANTA.Q_CAP(CHIPS)':
 C_PATH='@t6g_mb_lib.t6g(sch_1):page315_i5@pure_quanta.q_cap(chips)',
 P_PATH='@t6g_mb_lib.t6g(sch_1):page269_i5@pure_quanta.q_cap(chips)',
 PATH='I5',
 DRAWING='@T6G_MB_LIB.T6G(SCH_1):PAGE315',
 TOLERANCE='10%',
 MATERIAL='X7R',
 PHYS_PAGE='269',
 XY='(-4125,2525)',
 ROT='0',
 VER='1',
 PACK_TYPE='C0402',
 LOCATION='PC6020',
 CDS_LIB='pure_quanta',
 CDS_PART_NAME='Q_CAP_C0402-100NF,50V,10%,X7R,CH4106K1B01',
 VOLTAGE='50V',
 PART_NUMBER='CH4106K1B01',
 VALUE='100NF',
 PRIM_FILE='./archive_libs/logical/q_cap/chips/chips.prt';

PART_NAME
 PC6021 'Q_CAP_C0402-100NF,50V,10%,X7R,CH4106K1B01':;

SECTION_NUMBER 1
 '@T6G_MB_LIB.T6G(SCH_1):PAGE315_I27@PURE_QUANTA.Q_CAP(CHIPS)':
 C_PATH='@t6g_mb_lib.t6g(sch_1):page315_i27@pure_quanta.q_cap(chips)',
 P_PATH='@t6g_mb_lib.t6g(sch_1):page269_i27@pure_quanta.q_cap(chips)',
 PATH='I27',
 DRAWING='@T6G_MB_LIB.T6G(SCH_1):PAGE315',
 TOLERANCE='10%',
 MATERIAL='X7R',
 PHYS_PAGE='269',
 XY='(1025,1825)',
 ROT='0',
 VER='1',
 PACK_TYPE='C0402',
 LOCATION='PC6021',
 CDS_LIB='pure_quanta',
 CDS_PART_NAME='Q_CAP_C0402-100NF,50V,10%,X7R,CH4106K1B01',
 VOLTAGE='50V',
 PART_NUMBER='CH4106K1B01',
 VALUE='100NF',
 PRIM_FILE='./archive_libs/logical/q_cap/chips/chips.prt';

PART_NAME
 PC6022 'Q_CAP_C0402-100NF,50V,10%,X7R,CH4106K1B01':;

SECTION_NUMBER 1
 '@T6G_MB_LIB.T6G(SCH_1):PAGE380_I23@PURE_QUANTA.Q_CAP(CHIPS)':
 C_PATH='@t6g_mb_lib.t6g(sch_1):page380_i23@pure_quanta.q_cap(chips)',
 P_PATH='@t6g_mb_lib.t6g(sch_1):page270_i23@pure_quanta.q_cap(chips)',
 PATH='I23',
 DRAWING='@T6G_MB_LIB.T6G(SCH_1):PAGE380',
 TOLERANCE='10%',
 MATERIAL='X7R',
 PHYS_PAGE='270',
 XY='(-2550,1800)',
 ROT='0',
 VER='1',
 PACK_TYPE='C0402',
 LOCATION='PC6022',
 CDS_LIB='pure_quanta',
 CDS_PART_NAME='Q_CAP_C0402-100NF,50V,10%,X7R,CH4106K1B01',
 VOLTAGE='50V',
 PART_NUMBER='CH4106K1B01',
 VALUE='100NF',
 PRIM_FILE='./archive_libs/logical/q_cap/chips/chips.prt';

PART_NAME
 PC6023 'Q_CAP_C0402-100NF,50V,10%,X7R,CH4106K1B01':;

SECTION_NUMBER 1
 '@T6G_MB_LIB.T6G(SCH_1):PAGE380_I35@PURE_QUANTA.Q_CAP(CHIPS)':
 C_PATH='@t6g_mb_lib.t6g(sch_1):page380_i35@pure_quanta.q_cap(chips)',
 P_PATH='@t6g_mb_lib.t6g(sch_1):page270_i35@pure_quanta.q_cap(chips)',
 PATH='I35',
 DRAWING='@T6G_MB_LIB.T6G(SCH_1):PAGE380',
 TOLERANCE='10%',
 MATERIAL='X7R',
 PHYS_PAGE='270',
 XY='(-7700,2500)',
 ROT='0',
 VER='1',
 PACK_TYPE='C0402',
 LOCATION='PC6023',
 CDS_LIB='pure_quanta',
 CDS_PART_NAME='Q_CAP_C0402-100NF,50V,10%,X7R,CH4106K1B01',
 VOLTAGE='50V',
 PART_NUMBER='CH4106K1B01',
 VALUE='100NF',
 PRIM_FILE='./archive_libs/logical/q_cap/chips/chips.prt';

PART_NAME
 PC6024 'Q_CAP_C0805-22UF,4V,20%,X6S,CH622KMEA03':;

SECTION_NUMBER 1
 '@T6G_MB_LIB.T6G(SCH_1):PAGE380_I28@PURE_QUANTA.Q_CAP(CHIPS)':
 C_PATH='@t6g_mb_lib.t6g(sch_1):page380_i28@pure_quanta.q_cap(chips)',
 P_PATH='@t6g_mb_lib.t6g(sch_1):page270_i28@pure_quanta.q_cap(chips)',
 PATH='I28',
 DRAWING='@T6G_MB_LIB.T6G(SCH_1):PAGE380',
 TOLERANCE='20%',
 MATERIAL='X6S',
 PHYS_PAGE='270',
 XY='(-2150,1800)',
 ROT='0',
 VER='1',
 PACK_TYPE='C0805',
 LOCATION='PC6024',
 CDS_LIB='pure_quanta',
 CDS_PART_NAME='Q_CAP_C0805-22UF,4V,20%,X6S,CH622KMEA03',
 VOLTAGE='4V',
 PART_NUMBER='CH622KMEA03',
 VALUE='22UF',
 PRIM_FILE='./archive_libs/logical/q_cap/chips/chips.prt';

PART_NAME
 PC6025 'Q_CAP_C0805-22UF,4V,20%,X6S,CH622KMEA03':;

SECTION_NUMBER 1
 '@T6G_MB_LIB.T6G(SCH_1):PAGE380_I29@PURE_QUANTA.Q_CAP(CHIPS)':
 C_PATH='@t6g_mb_lib.t6g(sch_1):page380_i29@pure_quanta.q_cap(chips)',
 P_PATH='@t6g_mb_lib.t6g(sch_1):page270_i29@pure_quanta.q_cap(chips)',
 PATH='I29',
 DRAWING='@T6G_MB_LIB.T6G(SCH_1):PAGE380',
 TOLERANCE='20%',
 MATERIAL='X6S',
 PHYS_PAGE='270',
 XY='(-1725,1800)',
 ROT='0',
 VER='1',
 PACK_TYPE='C0805',
 LOCATION='PC6025',
 CDS_LIB='pure_quanta',
 CDS_PART_NAME='Q_CAP_C0805-22UF,4V,20%,X6S,CH622KMEA03',
 VOLTAGE='4V',
 PART_NUMBER='CH622KMEA03',
 VALUE='22UF',
 PRIM_FILE='./archive_libs/logical/q_cap/chips/chips.prt';

PART_NAME
 PC6026 'Q_CAP_C0805-22UF,4V,20%,X6S,CH622KMEA03':;

SECTION_NUMBER 1
 '@T6G_MB_LIB.T6G(SCH_1):PAGE380_I32@PURE_QUANTA.Q_CAP(CHIPS)':
 C_PATH='@t6g_mb_lib.t6g(sch_1):page380_i32@pure_quanta.q_cap(chips)',
 P_PATH='@t6g_mb_lib.t6g(sch_1):page270_i32@pure_quanta.q_cap(chips)',
 PATH='I32',
 DRAWING='@T6G_MB_LIB.T6G(SCH_1):PAGE380',
 TOLERANCE='20%',
 MATERIAL='X6S',
 PHYS_PAGE='270',
 XY='(-1300,1800)',
 ROT='0',
 VER='1',
 PACK_TYPE='C0805',
 LOCATION='PC6026',
 CDS_LIB='pure_quanta',
 CDS_PART_NAME='Q_CAP_C0805-22UF,4V,20%,X6S,CH622KMEA03',
 VOLTAGE='4V',
 PART_NUMBER='CH622KMEA03',
 VALUE='22UF',
 PRIM_FILE='./archive_libs/logical/q_cap/chips/chips.prt';

PART_NAME
 PC6500 'Q_CAP_C0402-0.1UF,25V,10%,X6S,CH4104KEB00':;

SECTION_NUMBER 1
 '@T6G_MB_LIB.T6G(SCH_1):PAGE469_I4@PURE_QUANTA.Q_CAP(CHIPS)':
 C_PATH='@t6g_mb_lib.t6g(sch_1):page469_i4@pure_quanta.q_cap(chips)',
 P_PATH='@t6g_mb_lib.t6g(sch_1):page360_i4@pure_quanta.q_cap(chips)',
 PATH='I4',
 DRAWING='@T6G_MB_LIB.T6G(SCH_1):PAGE469',
 TOLERANCE='10%',
 MATERIAL='X6S',
 PHYS_PAGE='360',
 XY='(-9100,3975)',
 ROT='0',
 VER='1',
 PACK_TYPE='C0402',
 LOCATION='PC6500',
 CDS_LIB='pure_quanta',
 CDS_PART_NAME='Q_CAP_C0402-0.1UF,25V,10%,X6S,CH4104KEB00',
 VOLTAGE='25V',
 PART_NUMBER='CH4104KEB00',
 VALUE='0.1UF',
 PRIM_FILE='./archive_libs/logical/q_cap/chips/chips.prt';

PART_NAME
 PC6501 'Q_CAP_C0805-22UF,16V,20%,X6S,CH6223MEA01':;

SECTION_NUMBER 1
 '@T6G_MB_LIB.T6G(SCH_1):PAGE469_I16@PURE_QUANTA.Q_CAP(CHIPS)':
 C_PATH='@t6g_mb_lib.t6g(sch_1):page469_i16@pure_quanta.q_cap(chips)',
 P_PATH='@t6g_mb_lib.t6g(sch_1):page360_i16@pure_quanta.q_cap(chips)',
 PATH='I16',
 DRAWING='@T6G_MB_LIB.T6G(SCH_1):PAGE469',
 TOLERANCE='20%',
 MATERIAL='X6S',
 PHYS_PAGE='360',
 XY='(-7975,3975)',
 ROT='0',
 VER='1',
 PACK_TYPE='C0805',
 LOCATION='PC6501',
 CDS_LIB='pure_quanta',
 CDS_PART_NAME='Q_CAP_C0805-22UF,16V,20%,X6S,CH6223MEA01',
 VOLTAGE='16V',
 PART_NUMBER='CH6223MEA01',
 VALUE='22UF',
 PRIM_FILE='./archive_libs/logical/q_cap/chips/chips.prt';

PART_NAME
 PC6502 'Q_CAP_C0805-22UF,16V,20%,X6S,CH6223MEA01':;

SECTION_NUMBER 1
 '@T6G_MB_LIB.T6G(SCH_1):PAGE469_I17@PURE_QUANTA.Q_CAP(CHIPS)':
 C_PATH='@t6g_mb_lib.t6g(sch_1):page469_i17@pure_quanta.q_cap(chips)',
 P_PATH='@t6g_mb_lib.t6g(sch_1):page360_i17@pure_quanta.q_cap(chips)',
 PATH='I17',
 DRAWING='@T6G_MB_LIB.T6G(SCH_1):PAGE469',
 TOLERANCE='20%',
 MATERIAL='X6S',
 PHYS_PAGE='360',
 XY='(-7750,3975)',
 ROT='0',
 VER='1',
 PACK_TYPE='C0805',
 LOCATION='PC6502',
 CDS_LIB='pure_quanta',
 CDS_PART_NAME='Q_CAP_C0805-22UF,16V,20%,X6S,CH6223MEA01',
 VOLTAGE='16V',
 PART_NUMBER='CH6223MEA01',
 VALUE='22UF',
 PRIM_FILE='./archive_libs/logical/q_cap/chips/chips.prt';

PART_NAME
 PC6503 'Q_CAP_C0805-22UF,16V,20%,X6S,CH6223MEA01':;

SECTION_NUMBER 1
 '@T6G_MB_LIB.T6G(SCH_1):PAGE469_I18@PURE_QUANTA.Q_CAP(CHIPS)':
 C_PATH='@t6g_mb_lib.t6g(sch_1):page469_i18@pure_quanta.q_cap(chips)',
 P_PATH='@t6g_mb_lib.t6g(sch_1):page360_i18@pure_quanta.q_cap(chips)',
 PATH='I18',
 DRAWING='@T6G_MB_LIB.T6G(SCH_1):PAGE469',
 TOLERANCE='20%',
 MATERIAL='X6S',
 PHYS_PAGE='360',
 XY='(-7550,3975)',
 ROT='0',
 VER='1',
 PACK_TYPE='C0805',
 LOCATION='PC6503',
 CDS_LIB='pure_quanta',
 CDS_PART_NAME='Q_CAP_C0805-22UF,16V,20%,X6S,CH6223MEA01',
 VOLTAGE='16V',
 PART_NUMBER='CH6223MEA01',
 VALUE='22UF',
 PRIM_FILE='./archive_libs/logical/q_cap/chips/chips.prt';

PART_NAME
 PC6504 'Q_CAP_C0805-22UF,16V,20%,X6S,CH6223MEA01':;

SECTION_NUMBER 1
 '@T6G_MB_LIB.T6G(SCH_1):PAGE469_I22@PURE_QUANTA.Q_CAP(CHIPS)':
 C_PATH='@t6g_mb_lib.t6g(sch_1):page469_i22@pure_quanta.q_cap(chips)',
 P_PATH='@t6g_mb_lib.t6g(sch_1):page360_i22@pure_quanta.q_cap(chips)',
 PATH='I22',
 DRAWING='@T6G_MB_LIB.T6G(SCH_1):PAGE469',
 TOLERANCE='20%',
 MATERIAL='X6S',
 PHYS_PAGE='360',
 XY='(-7350,3975)',
 ROT='0',
 VER='1',
 PACK_TYPE='C0805',
 LOCATION='PC6504',
 CDS_LIB='pure_quanta',
 CDS_PART_NAME='Q_CAP_C0805-22UF,16V,20%,X6S,CH6223MEA01',
 VOLTAGE='16V',
 PART_NUMBER='CH6223MEA01',
 VALUE='22UF',
 PRIM_FILE='./archive_libs/logical/q_cap/chips/chips.prt';

PART_NAME
 PC6505 'Q_CAP_C0402-1UF,25V,10%,X6S,CH5104KEB02':;

SECTION_NUMBER 1
 '@T6G_MB_LIB.T6G(SCH_1):PAGE469_I23@PURE_QUANTA.Q_CAP(CHIPS)':
 C_PATH='@t6g_mb_lib.t6g(sch_1):page469_i23@pure_quanta.q_cap(chips)',
 P_PATH='@t6g_mb_lib.t6g(sch_1):page360_i23@pure_quanta.q_cap(chips)',
 PATH='I23',
 DRAWING='@T6G_MB_LIB.T6G(SCH_1):PAGE469',
 TOLERANCE='10%',
 MATERIAL='X6S',
 PHYS_PAGE='360',
 XY='(-7150,3975)',
 ROT='0',
 VER='1',
 PACK_TYPE='C0402',
 LOCATION='PC6505',
 CDS_LIB='pure_quanta',
 CDS_PART_NAME='Q_CAP_C0402-1UF,25V,10%,X6S,CH5104KEB02',
 VOLTAGE='25V',
 PART_NUMBER='CH5104KEB02',
 VALUE='1UF',
 PRIM_FILE='./archive_libs/logical/q_cap/chips/chips.prt';

PART_NAME
 PC6506 'Q_CAP_C0402-1UF,25V,10%,X6S,CH5104KEB02':
 SIGNAL_MODEL='DEFAULT_CAPACITOR_100000PF_2_1';

SECTION_NUMBER 1
 '@T6G_MB_LIB.T6G(SCH_1):PAGE469_I12@PURE_QUANTA.Q_CAP(CHIPS)':
 C_PATH='@t6g_mb_lib.t6g(sch_1):page469_i12@pure_quanta.q_cap(chips)',
 P_PATH='@t6g_mb_lib.t6g(sch_1):page360_i12@pure_quanta.q_cap(chips)',
 PATH='I12',
 DRAWING='@T6G_MB_LIB.T6G(SCH_1):PAGE469',
 SEC_TYPE='C0402',
 TOLERANCE='10%',
 MATERIAL='X6S',
 PHYS_PAGE='360',
 XY='(-7450,2375)',
 ROT='2',
 VER='1',
 PACK_TYPE='C0402',
 LOCATION='PC6506',
 SEC='1',
 CDS_LIB='pure_quanta',
 CDS_PART_NAME='Q_CAP_C0402-1UF,25V,10%,X6S,CH5104KEB02',
 SIGNAL_MODEL='DEFAULT_CAPACITOR_100000PF_2_1',
 VOLTAGE='25V',
 PART_NUMBER='CH5104KEB02',
 VALUE='1UF',
 PRIM_FILE='./archive_libs/logical/q_cap/chips/chips.prt';

PART_NAME
 PC6507 'Q_CAP_0402-0.22UF,16V,10%,X7R,CH4223K1B00':;

SECTION_NUMBER 1
 '@T6G_MB_LIB.T6G(SCH_1):PAGE469_I32@PURE_QUANTA.Q_CAP(CHIPS)':
 C_PATH='@t6g_mb_lib.t6g(sch_1):page469_i32@pure_quanta.q_cap(chips)',
 P_PATH='@t6g_mb_lib.t6g(sch_1):page360_i32@pure_quanta.q_cap(chips)',
 PATH='I32',
 DRAWING='@T6G_MB_LIB.T6G(SCH_1):PAGE469',
 SEC_TYPE='0402',
 TOLERANCE='10%',
 MATERIAL='X7R',
 PHYS_PAGE='360',
 XY='(-4025,3550)',
 ROT='0',
 VER='1',
 PACK_TYPE='0402',
 LOCATION='PC6507',
 SEC='1',
 CDS_LIB='pure_quanta',
 CDS_PART_NAME='Q_CAP_0402-0.22UF,16V,10%,X7R,CH4223K1B00',
 VOLTAGE='16V',
 PART_NUMBER='CH4223K1B00',
 VALUE='0.22UF',
 PRIM_FILE='./archive_libs/logical/q_cap/chips/chips.prt';

PART_NAME
 PC6508 'Q_CAP_C0805-22UF,4V,20%,X6S,CH622KMEA03':;

SECTION_NUMBER 1
 '@T6G_MB_LIB.T6G(SCH_1):PAGE469_I38@PURE_QUANTA.Q_CAP(CHIPS)':
 C_PATH='@t6g_mb_lib.t6g(sch_1):page469_i38@pure_quanta.q_cap(chips)',
 P_PATH='@t6g_mb_lib.t6g(sch_1):page360_i38@pure_quanta.q_cap(chips)',
 PATH='I38',
 DRAWING='@T6G_MB_LIB.T6G(SCH_1):PAGE469',
 TOLERANCE='20%',
 MATERIAL='X6S',
 PHYS_PAGE='360',
 XY='(-2800,3150)',
 ROT='0',
 VER='1',
 PACK_TYPE='C0805',
 LOCATION='PC6508',
 CDS_LIB='pure_quanta',
 CDS_PART_NAME='Q_CAP_C0805-22UF,4V,20%,X6S,CH622KMEA03',
 VOLTAGE='4V',
 PART_NUMBER='CH622KMEA03',
 VALUE='22UF',
 PRIM_FILE='./archive_libs/logical/q_cap/chips/chips.prt';

PART_NAME
 PC6509 'Q_CAP_C0805-22UF,4V,20%,X6S,CH622KMEA03':;

SECTION_NUMBER 1
 '@T6G_MB_LIB.T6G(SCH_1):PAGE469_I39@PURE_QUANTA.Q_CAP(CHIPS)':
 C_PATH='@t6g_mb_lib.t6g(sch_1):page469_i39@pure_quanta.q_cap(chips)',
 P_PATH='@t6g_mb_lib.t6g(sch_1):page360_i39@pure_quanta.q_cap(chips)',
 PATH='I39',
 DRAWING='@T6G_MB_LIB.T6G(SCH_1):PAGE469',
 TOLERANCE='20%',
 MATERIAL='X6S',
 PHYS_PAGE='360',
 XY='(-2425,3150)',
 ROT='0',
 VER='1',
 PACK_TYPE='C0805',
 LOCATION='PC6509',
 CDS_LIB='pure_quanta',
 CDS_PART_NAME='Q_CAP_C0805-22UF,4V,20%,X6S,CH622KMEA03',
 VOLTAGE='4V',
 PART_NUMBER='CH622KMEA03',
 VALUE='22UF',
 PRIM_FILE='./archive_libs/logical/q_cap/chips/chips.prt';

PART_NAME
 PC6510 'Q_CAP_C0805-22UF,4V,20%,X6S,CH622KMEA03':;

SECTION_NUMBER 1
 '@T6G_MB_LIB.T6G(SCH_1):PAGE469_I40@PURE_QUANTA.Q_CAP(CHIPS)':
 C_PATH='@t6g_mb_lib.t6g(sch_1):page469_i40@pure_quanta.q_cap(chips)',
 P_PATH='@t6g_mb_lib.t6g(sch_1):page360_i40@pure_quanta.q_cap(chips)',
 PATH='I40',
 DRAWING='@T6G_MB_LIB.T6G(SCH_1):PAGE469',
 TOLERANCE='20%',
 MATERIAL='X6S',
 PHYS_PAGE='360',
 XY='(-2150,3150)',
 ROT='0',
 VER='1',
 PACK_TYPE='C0805',
 LOCATION='PC6510',
 CDS_LIB='pure_quanta',
 CDS_PART_NAME='Q_CAP_C0805-22UF,4V,20%,X6S,CH622KMEA03',
 VOLTAGE='4V',
 PART_NUMBER='CH622KMEA03',
 VALUE='22UF',
 PRIM_FILE='./archive_libs/logical/q_cap/chips/chips.prt';

PART_NAME
 PC6511 'Q_CAP_C0805-22UF,4V,20%,X6S,CH622KMEA03':;

SECTION_NUMBER 1
 '@T6G_MB_LIB.T6G(SCH_1):PAGE469_I44@PURE_QUANTA.Q_CAP(CHIPS)':
 C_PATH='@t6g_mb_lib.t6g(sch_1):page469_i44@pure_quanta.q_cap(chips)',
 P_PATH='@t6g_mb_lib.t6g(sch_1):page360_i44@pure_quanta.q_cap(chips)',
 PATH='I44',
 DRAWING='@T6G_MB_LIB.T6G(SCH_1):PAGE469',
 TOLERANCE='20%',
 MATERIAL='X6S',
 PHYS_PAGE='360',
 XY='(-1875,3150)',
 ROT='0',
 VER='1',
 PACK_TYPE='C0805',
 LOCATION='PC6511',
 CDS_LIB='pure_quanta',
 CDS_PART_NAME='Q_CAP_C0805-22UF,4V,20%,X6S,CH622KMEA03',
 VOLTAGE='4V',
 PART_NUMBER='CH622KMEA03',
 VALUE='22UF',
 PRIM_FILE='./archive_libs/logical/q_cap/chips/chips.prt';

PART_NAME
 PC6512 'Q_CAP_C0805-22UF,4V,20%,X6S,CH622KMEA03':;

SECTION_NUMBER 1
 '@T6G_MB_LIB.T6G(SCH_1):PAGE469_I52@PURE_QUANTA.Q_CAP(CHIPS)':
 C_PATH='@t6g_mb_lib.t6g(sch_1):page469_i52@pure_quanta.q_cap(chips)',
 P_PATH='@t6g_mb_lib.t6g(sch_1):page360_i52@pure_quanta.q_cap(chips)',
 PATH='I52',
 DRAWING='@T6G_MB_LIB.T6G(SCH_1):PAGE469',
 TOLERANCE='20%',
 MATERIAL='X6S',
 PHYS_PAGE='360',
 XY='(-1575,3150)',
 ROT='0',
 VER='1',
 PACK_TYPE='C0805',
 LOCATION='PC6512',
 CDS_LIB='pure_quanta',
 CDS_PART_NAME='Q_CAP_C0805-22UF,4V,20%,X6S,CH622KMEA03',
 VOLTAGE='4V',
 PART_NUMBER='CH622KMEA03',
 VALUE='22UF',
 PRIM_FILE='./archive_libs/logical/q_cap/chips/chips.prt';

PART_NAME
 PC6513 'Q_CAPP_SMLF-390UF,2.5V,20%,ALUM,CC7390JMZ13':;

SECTION_NUMBER 1
 '@T6G_MB_LIB.T6G(SCH_1):PAGE469_I46@PURE_QUANTA.Q_CAPP(CHIPS)':
 C_PATH='@t6g_mb_lib.t6g(sch_1):page469_i46@pure_quanta.q_capp(chips)',
 P_PATH='@t6g_mb_lib.t6g(sch_1):page360_i46@pure_quanta.q_capp(chips)',
 PATH='I46',
 DRAWING='@T6G_MB_LIB.T6G(SCH_1):PAGE469',
 TOLERANCE='20%',
 MATERIAL='ALUM',
 PHYS_PAGE='360',
 XY='(-1300,3150)',
 ROT='0',
 VER='1',
 PACK_TYPE='SMLF',
 LOCATION='PC6513',
 CDS_LIB='pure_quanta',
 CDS_PART_NAME='Q_CAPP_SMLF-390UF,2.5V,20%,ALUM,CC7390JMZ13',
 VOLTAGE='2.5V',
 PART_NUMBER='CC7390JMZ13',
 VALUE='390UF',
 PRIM_FILE='./archive_libs/logical/q_capp/chips/chips.prt';

PART_NAME
 PC6514 'Q_CAP_0402-0.1UF,25V,10%,X7R,CH4104K1B00':;

SECTION_NUMBER 1
 '@T6G_MB_LIB.T6G(SCH_1):PAGE469_I49@PURE_QUANTA.Q_CAP(CHIPS)':
 C_PATH='@t6g_mb_lib.t6g(sch_1):page469_i49@pure_quanta.q_cap(chips)',
 P_PATH='@t6g_mb_lib.t6g(sch_1):page360_i49@pure_quanta.q_cap(chips)',
 PATH='I49',
 DRAWING='@T6G_MB_LIB.T6G(SCH_1):PAGE469',
 SEC_TYPE='0402',
 TOLERANCE='10%',
 MATERIAL='X7R',
 PHYS_PAGE='360',
 XY='(-675,3150)',
 ROT='0',
 VER='1',
 PACK_TYPE='0402',
 LOCATION='PC6514',
 SEC='1',
 CDS_LIB='pure_quanta',
 CDS_PART_NAME='Q_CAP_0402-0.1UF,25V,10%,X7R,CH4104K1B00',
 VOLTAGE='25V',
 PART_NUMBER='CH4104K1B00',
 VALUE='0.1UF',
 PRIM_FILE='./archive_libs/logical/q_cap/chips/chips.prt';

PART_NAME
 PC6515 'Q_CAP_0402-150PF,50V,5%,NPO,TMP_QCH11506JB08':;

SECTION_NUMBER 1
 '@T6G_MB_LIB.T6G(SCH_1):PAGE469_I34@PURE_QUANTA.Q_CAP(CHIPS)':
 C_PATH='@t6g_mb_lib.t6g(sch_1):page469_i34@pure_quanta.q_cap(chips)',
 P_PATH='@t6g_mb_lib.t6g(sch_1):page360_i34@pure_quanta.q_cap(chips)',
 PATH='I34',
 DRAWING='@T6G_MB_LIB.T6G(SCH_1):PAGE469',
 TOLERANCE='5%',
 MATERIAL='NPO',
 PHYS_PAGE='360',
 XY='(-3450,2625)',
 ROT='0',
 VER='2',
 PACK_TYPE='0402',
 LOCATION='PC6515',
 CDS_LIB='pure_quanta',
 CDS_PART_NAME='Q_CAP_0402-150PF,50V,5%,NPO,TMP_QCH11506JB08',
 VOLTAGE='50V',
 PART_NUMBER='TMP_QCH11506JB08',
 VALUE='150PF',
 PRIM_FILE='./archive_libs/logical/q_cap/chips/chips.prt';

PART_NAME
 PC6518 'Q_CAP_0402-0.1UF,25V,10%,X7R,CH4104K1B00':;

SECTION_NUMBER 1
 '@T6G_MB_LIB.T6G(SCH_1):PAGE469_I26@PURE_QUANTA.Q_CAP(CHIPS)':
 C_PATH='@t6g_mb_lib.t6g(sch_1):page469_i26@pure_quanta.q_cap(chips)',
 P_PATH='@t6g_mb_lib.t6g(sch_1):page360_i26@pure_quanta.q_cap(chips)',
 PATH='I26',
 DRAWING='@T6G_MB_LIB.T6G(SCH_1):PAGE469',
 TOLERANCE='10%',
 MATERIAL='X7R',
 PHYS_PAGE='360',
 XY='(-4875,2525)',
 ROT='0',
 VER='1',
 PACK_TYPE='0402',
 LOCATION='PC6518',
 CDS_LIB='pure_quanta',
 CDS_PART_NAME='Q_CAP_0402-0.1UF,25V,10%,X7R,CH4104K1B00',
 VOLTAGE='25V',
 PART_NUMBER='CH4104K1B00',
 VALUE='0.1UF',
 PRIM_FILE='./archive_libs/logical/q_cap/chips/chips.prt';

PART_NAME
 PC6519 'Q_CAP_C0402-0.1UF,25V,10%,X6S,CH4104KEB00':;

SECTION_NUMBER 1
 '@T6G_MB_LIB.T6G(SCH_1):PAGE470_I3@PURE_QUANTA.Q_CAP(CHIPS)':
 C_PATH='@t6g_mb_lib.t6g(sch_1):page470_i3@pure_quanta.q_cap(chips)',
 P_PATH='@t6g_mb_lib.t6g(sch_1):page361_i3@pure_quanta.q_cap(chips)',
 PATH='I3',
 DRAWING='@T6G_MB_LIB.T6G(SCH_1):PAGE470',
 TOLERANCE='10%',
 MATERIAL='X6S',
 PHYS_PAGE='361',
 XY='(-9150,4025)',
 ROT='0',
 VER='1',
 PACK_TYPE='C0402',
 LOCATION='PC6519',
 CDS_LIB='pure_quanta',
 CDS_PART_NAME='Q_CAP_C0402-0.1UF,25V,10%,X6S,CH4104KEB00',
 VOLTAGE='25V',
 PART_NUMBER='CH4104KEB00',
 VALUE='0.1UF',
 PRIM_FILE='./archive_libs/logical/q_cap/chips/chips.prt';

PART_NAME
 PC6520 'Q_CAP_C0805-22UF,16V,20%,X6S,CH6223MEA01':;

SECTION_NUMBER 1
 '@T6G_MB_LIB.T6G(SCH_1):PAGE470_I16@PURE_QUANTA.Q_CAP(CHIPS)':
 C_PATH='@t6g_mb_lib.t6g(sch_1):page470_i16@pure_quanta.q_cap(chips)',
 P_PATH='@t6g_mb_lib.t6g(sch_1):page361_i16@pure_quanta.q_cap(chips)',
 PATH='I16',
 DRAWING='@T6G_MB_LIB.T6G(SCH_1):PAGE470',
 TOLERANCE='20%',
 MATERIAL='X6S',
 PHYS_PAGE='361',
 XY='(-8075,4000)',
 ROT='0',
 VER='1',
 PACK_TYPE='C0805',
 LOCATION='PC6520',
 CDS_LIB='pure_quanta',
 CDS_PART_NAME='Q_CAP_C0805-22UF,16V,20%,X6S,CH6223MEA01',
 VOLTAGE='16V',
 PART_NUMBER='CH6223MEA01',
 VALUE='22UF',
 PRIM_FILE='./archive_libs/logical/q_cap/chips/chips.prt';

PART_NAME
 PC6521 'Q_CAP_C0805-22UF,16V,20%,X6S,CH6223MEA01':;

SECTION_NUMBER 1
 '@T6G_MB_LIB.T6G(SCH_1):PAGE470_I17@PURE_QUANTA.Q_CAP(CHIPS)':
 C_PATH='@t6g_mb_lib.t6g(sch_1):page470_i17@pure_quanta.q_cap(chips)',
 P_PATH='@t6g_mb_lib.t6g(sch_1):page361_i17@pure_quanta.q_cap(chips)',
 PATH='I17',
 DRAWING='@T6G_MB_LIB.T6G(SCH_1):PAGE470',
 TOLERANCE='20%',
 MATERIAL='X6S',
 PHYS_PAGE='361',
 XY='(-7850,4000)',
 ROT='0',
 VER='1',
 PACK_TYPE='C0805',
 LOCATION='PC6521',
 CDS_LIB='pure_quanta',
 CDS_PART_NAME='Q_CAP_C0805-22UF,16V,20%,X6S,CH6223MEA01',
 VOLTAGE='16V',
 PART_NUMBER='CH6223MEA01',
 VALUE='22UF',
 PRIM_FILE='./archive_libs/logical/q_cap/chips/chips.prt';

PART_NAME
 PC6522 'Q_CAP_C0805-22UF,16V,20%,X6S,CH6223MEA01':;

SECTION_NUMBER 1
 '@T6G_MB_LIB.T6G(SCH_1):PAGE470_I18@PURE_QUANTA.Q_CAP(CHIPS)':
 C_PATH='@t6g_mb_lib.t6g(sch_1):page470_i18@pure_quanta.q_cap(chips)',
 P_PATH='@t6g_mb_lib.t6g(sch_1):page361_i18@pure_quanta.q_cap(chips)',
 PATH='I18',
 DRAWING='@T6G_MB_LIB.T6G(SCH_1):PAGE470',
 TOLERANCE='20%',
 MATERIAL='X6S',
 PHYS_PAGE='361',
 XY='(-7675,4000)',
 ROT='0',
 VER='1',
 PACK_TYPE='C0805',
 LOCATION='PC6522',
 CDS_LIB='pure_quanta',
 CDS_PART_NAME='Q_CAP_C0805-22UF,16V,20%,X6S,CH6223MEA01',
 VOLTAGE='16V',
 PART_NUMBER='CH6223MEA01',
 VALUE='22UF',
 PRIM_FILE='./archive_libs/logical/q_cap/chips/chips.prt';

PART_NAME
 PC6523 'Q_CAP_C0805-22UF,16V,20%,X6S,CH6223MEA01':;

SECTION_NUMBER 1
 '@T6G_MB_LIB.T6G(SCH_1):PAGE470_I22@PURE_QUANTA.Q_CAP(CHIPS)':
 C_PATH='@t6g_mb_lib.t6g(sch_1):page470_i22@pure_quanta.q_cap(chips)',
 P_PATH='@t6g_mb_lib.t6g(sch_1):page361_i22@pure_quanta.q_cap(chips)',
 PATH='I22',
 DRAWING='@T6G_MB_LIB.T6G(SCH_1):PAGE470',
 TOLERANCE='20%',
 MATERIAL='X6S',
 PHYS_PAGE='361',
 XY='(-7450,4000)',
 ROT='0',
 VER='1',
 PACK_TYPE='C0805',
 LOCATION='PC6523',
 CDS_LIB='pure_quanta',
 CDS_PART_NAME='Q_CAP_C0805-22UF,16V,20%,X6S,CH6223MEA01',
 VOLTAGE='16V',
 PART_NUMBER='CH6223MEA01',
 VALUE='22UF',
 PRIM_FILE='./archive_libs/logical/q_cap/chips/chips.prt';

PART_NAME
 PC6524 'Q_CAP_C0402-1UF,25V,10%,X6S,CH5104KEB02':;

SECTION_NUMBER 1
 '@T6G_MB_LIB.T6G(SCH_1):PAGE470_I23@PURE_QUANTA.Q_CAP(CHIPS)':
 C_PATH='@t6g_mb_lib.t6g(sch_1):page470_i23@pure_quanta.q_cap(chips)',
 P_PATH='@t6g_mb_lib.t6g(sch_1):page361_i23@pure_quanta.q_cap(chips)',
 PATH='I23',
 DRAWING='@T6G_MB_LIB.T6G(SCH_1):PAGE470',
 TOLERANCE='10%',
 MATERIAL='X6S',
 PHYS_PAGE='361',
 XY='(-7250,4000)',
 ROT='0',
 VER='1',
 PACK_TYPE='C0402',
 LOCATION='PC6524',
 CDS_LIB='pure_quanta',
 CDS_PART_NAME='Q_CAP_C0402-1UF,25V,10%,X6S,CH5104KEB02',
 VOLTAGE='25V',
 PART_NUMBER='CH5104KEB02',
 VALUE='1UF',
 PRIM_FILE='./archive_libs/logical/q_cap/chips/chips.prt';

PART_NAME
 PC6525 'Q_CAP_C0402-1UF,25V,10%,X6S,CH5104KEB02':
 SIGNAL_MODEL='DEFAULT_CAPACITOR_100000PF_2_1';

SECTION_NUMBER 1
 '@T6G_MB_LIB.T6G(SCH_1):PAGE470_I12@PURE_QUANTA.Q_CAP(CHIPS)':
 C_PATH='@t6g_mb_lib.t6g(sch_1):page470_i12@pure_quanta.q_cap(chips)',
 P_PATH='@t6g_mb_lib.t6g(sch_1):page361_i12@pure_quanta.q_cap(chips)',
 PATH='I12',
 DRAWING='@T6G_MB_LIB.T6G(SCH_1):PAGE470',
 SEC_TYPE='C0402',
 TOLERANCE='10%',
 MATERIAL='X6S',
 PHYS_PAGE='361',
 XY='(-7500,2425)',
 ROT='2',
 VER='1',
 PACK_TYPE='C0402',
 LOCATION='PC6525',
 SEC='1',
 CDS_LIB='pure_quanta',
 CDS_PART_NAME='Q_CAP_C0402-1UF,25V,10%,X6S,CH5104KEB02',
 SIGNAL_MODEL='DEFAULT_CAPACITOR_100000PF_2_1',
 VOLTAGE='25V',
 PART_NUMBER='CH5104KEB02',
 VALUE='1UF',
 PRIM_FILE='./archive_libs/logical/q_cap/chips/chips.prt';

PART_NAME
 PC6526 'Q_CAP_0402-0.22UF,16V,10%,X7R,CH4223K1B00':;

SECTION_NUMBER 1
 '@T6G_MB_LIB.T6G(SCH_1):PAGE470_I35@PURE_QUANTA.Q_CAP(CHIPS)':
 C_PATH='@t6g_mb_lib.t6g(sch_1):page470_i35@pure_quanta.q_cap(chips)',
 P_PATH='@t6g_mb_lib.t6g(sch_1):page361_i35@pure_quanta.q_cap(chips)',
 PATH='I35',
 DRAWING='@T6G_MB_LIB.T6G(SCH_1):PAGE470',
 SEC_TYPE='0402',
 TOLERANCE='10%',
 MATERIAL='X7R',
 PHYS_PAGE='361',
 XY='(-3925,3625)',
 ROT='0',
 VER='1',
 PACK_TYPE='0402',
 LOCATION='PC6526',
 SEC='1',
 CDS_LIB='pure_quanta',
 CDS_PART_NAME='Q_CAP_0402-0.22UF,16V,10%,X7R,CH4223K1B00',
 VOLTAGE='16V',
 PART_NUMBER='CH4223K1B00',
 VALUE='0.22UF',
 PRIM_FILE='./archive_libs/logical/q_cap/chips/chips.prt';

PART_NAME
 PC6527 'Q_CAP_C0805-22UF,4V,20%,X6S,CH622KMEA03':;

SECTION_NUMBER 1
 '@T6G_MB_LIB.T6G(SCH_1):PAGE470_I38@PURE_QUANTA.Q_CAP(CHIPS)':
 C_PATH='@t6g_mb_lib.t6g(sch_1):page470_i38@pure_quanta.q_cap(chips)',
 P_PATH='@t6g_mb_lib.t6g(sch_1):page361_i38@pure_quanta.q_cap(chips)',
 PATH='I38',
 DRAWING='@T6G_MB_LIB.T6G(SCH_1):PAGE470',
 TOLERANCE='20%',
 MATERIAL='X6S',
 PHYS_PAGE='361',
 XY='(-2850,3200)',
 ROT='0',
 VER='1',
 PACK_TYPE='C0805',
 LOCATION='PC6527',
 CDS_LIB='pure_quanta',
 CDS_PART_NAME='Q_CAP_C0805-22UF,4V,20%,X6S,CH622KMEA03',
 VOLTAGE='4V',
 PART_NUMBER='CH622KMEA03',
 VALUE='22UF',
 PRIM_FILE='./archive_libs/logical/q_cap/chips/chips.prt';

PART_NAME
 PC6528 'Q_CAP_C0805-22UF,4V,20%,X6S,CH622KMEA03':;

SECTION_NUMBER 1
 '@T6G_MB_LIB.T6G(SCH_1):PAGE470_I41@PURE_QUANTA.Q_CAP(CHIPS)':
 C_PATH='@t6g_mb_lib.t6g(sch_1):page470_i41@pure_quanta.q_cap(chips)',
 P_PATH='@t6g_mb_lib.t6g(sch_1):page361_i41@pure_quanta.q_cap(chips)',
 PATH='I41',
 DRAWING='@T6G_MB_LIB.T6G(SCH_1):PAGE470',
 TOLERANCE='20%',
 MATERIAL='X6S',
 PHYS_PAGE='361',
 XY='(-2425,3200)',
 ROT='0',
 VER='1',
 PACK_TYPE='C0805',
 LOCATION='PC6528',
 CDS_LIB='pure_quanta',
 CDS_PART_NAME='Q_CAP_C0805-22UF,4V,20%,X6S,CH622KMEA03',
 VOLTAGE='4V',
 PART_NUMBER='CH622KMEA03',
 VALUE='22UF',
 PRIM_FILE='./archive_libs/logical/q_cap/chips/chips.prt';

PART_NAME
 PC6529 'Q_CAP_C0805-22UF,4V,20%,X6S,CH622KMEA03':;

SECTION_NUMBER 1
 '@T6G_MB_LIB.T6G(SCH_1):PAGE470_I42@PURE_QUANTA.Q_CAP(CHIPS)':
 C_PATH='@t6g_mb_lib.t6g(sch_1):page470_i42@pure_quanta.q_cap(chips)',
 P_PATH='@t6g_mb_lib.t6g(sch_1):page361_i42@pure_quanta.q_cap(chips)',
 PATH='I42',
 DRAWING='@T6G_MB_LIB.T6G(SCH_1):PAGE470',
 TOLERANCE='20%',
 MATERIAL='X6S',
 PHYS_PAGE='361',
 XY='(-2150,3200)',
 ROT='0',
 VER='1',
 PACK_TYPE='C0805',
 LOCATION='PC6529',
 CDS_LIB='pure_quanta',
 CDS_PART_NAME='Q_CAP_C0805-22UF,4V,20%,X6S,CH622KMEA03',
 VOLTAGE='4V',
 PART_NUMBER='CH622KMEA03',
 VALUE='22UF',
 PRIM_FILE='./archive_libs/logical/q_cap/chips/chips.prt';

PART_NAME
 PC6530 'Q_CAP_C0805-22UF,4V,20%,X6S,CH622KMEA03':;

SECTION_NUMBER 1
 '@T6G_MB_LIB.T6G(SCH_1):PAGE470_I44@PURE_QUANTA.Q_CAP(CHIPS)':
 C_PATH='@t6g_mb_lib.t6g(sch_1):page470_i44@pure_quanta.q_cap(chips)',
 P_PATH='@t6g_mb_lib.t6g(sch_1):page361_i44@pure_quanta.q_cap(chips)',
 PATH='I44',
 DRAWING='@T6G_MB_LIB.T6G(SCH_1):PAGE470',
 TOLERANCE='20%',
 MATERIAL='X6S',
 PHYS_PAGE='361',
 XY='(-1900,3200)',
 ROT='0',
 VER='1',
 PACK_TYPE='C0805',
 LOCATION='PC6530',
 CDS_LIB='pure_quanta',
 CDS_PART_NAME='Q_CAP_C0805-22UF,4V,20%,X6S,CH622KMEA03',
 VOLTAGE='4V',
 PART_NUMBER='CH622KMEA03',
 VALUE='22UF',
 PRIM_FILE='./archive_libs/logical/q_cap/chips/chips.prt';

PART_NAME
 PC6531 'Q_CAP_C0805-22UF,4V,20%,X6S,CH622KMEA03':;

SECTION_NUMBER 1
 '@T6G_MB_LIB.T6G(SCH_1):PAGE470_I45@PURE_QUANTA.Q_CAP(CHIPS)':
 C_PATH='@t6g_mb_lib.t6g(sch_1):page470_i45@pure_quanta.q_cap(chips)',
 P_PATH='@t6g_mb_lib.t6g(sch_1):page361_i45@pure_quanta.q_cap(chips)',
 PATH='I45',
 DRAWING='@T6G_MB_LIB.T6G(SCH_1):PAGE470',
 TOLERANCE='20%',
 MATERIAL='X6S',
 PHYS_PAGE='361',
 XY='(-1625,3200)',
 ROT='0',
 VER='1',
 PACK_TYPE='C0805',
 LOCATION='PC6531',
 CDS_LIB='pure_quanta',
 CDS_PART_NAME='Q_CAP_C0805-22UF,4V,20%,X6S,CH622KMEA03',
 VOLTAGE='4V',
 PART_NUMBER='CH622KMEA03',
 VALUE='22UF',
 PRIM_FILE='./archive_libs/logical/q_cap/chips/chips.prt';

PART_NAME
 PC6532 'Q_CAPP_SMLF-390UF,2.5V,20%,ALUM,CC7390JMZ13':;

SECTION_NUMBER 1
 '@T6G_MB_LIB.T6G(SCH_1):PAGE470_I46@PURE_QUANTA.Q_CAPP(CHIPS)':
 C_PATH='@t6g_mb_lib.t6g(sch_1):page470_i46@pure_quanta.q_capp(chips)',
 P_PATH='@t6g_mb_lib.t6g(sch_1):page361_i46@pure_quanta.q_capp(chips)',
 PATH='I46',
 DRAWING='@T6G_MB_LIB.T6G(SCH_1):PAGE470',
 TOLERANCE='20%',
 MATERIAL='ALUM',
 PHYS_PAGE='361',
 XY='(-1350,3200)',
 ROT='0',
 VER='1',
 PACK_TYPE='SMLF',
 LOCATION='PC6532',
 CDS_LIB='pure_quanta',
 CDS_PART_NAME='Q_CAPP_SMLF-390UF,2.5V,20%,ALUM,CC7390JMZ13',
 VOLTAGE='2.5V',
 PART_NUMBER='CC7390JMZ13',
 VALUE='390UF',
 PRIM_FILE='./archive_libs/logical/q_capp/chips/chips.prt';

PART_NAME
 PC6533 'Q_CAP_0402-0.1UF,25V,10%,X7R,CH4104K1B00':;

SECTION_NUMBER 1
 '@T6G_MB_LIB.T6G(SCH_1):PAGE470_I49@PURE_QUANTA.Q_CAP(CHIPS)':
 C_PATH='@t6g_mb_lib.t6g(sch_1):page470_i49@pure_quanta.q_cap(chips)',
 P_PATH='@t6g_mb_lib.t6g(sch_1):page361_i49@pure_quanta.q_cap(chips)',
 PATH='I49',
 DRAWING='@T6G_MB_LIB.T6G(SCH_1):PAGE470',
 SEC_TYPE='0402',
 TOLERANCE='10%',
 MATERIAL='X7R',
 PHYS_PAGE='361',
 XY='(-750,3200)',
 ROT='0',
 VER='1',
 PACK_TYPE='0402',
 LOCATION='PC6533',
 SEC='1',
 CDS_LIB='pure_quanta',
 CDS_PART_NAME='Q_CAP_0402-0.1UF,25V,10%,X7R,CH4104K1B00',
 VOLTAGE='25V',
 PART_NUMBER='CH4104K1B00',
 VALUE='0.1UF',
 PRIM_FILE='./archive_libs/logical/q_cap/chips/chips.prt';

PART_NAME
 PC6534 'Q_CAP_0402-150PF,50V,5%,NPO,TMP_QCH11506JB08':;

SECTION_NUMBER 1
 '@T6G_MB_LIB.T6G(SCH_1):PAGE470_I33@PURE_QUANTA.Q_CAP(CHIPS)':
 C_PATH='@t6g_mb_lib.t6g(sch_1):page470_i33@pure_quanta.q_cap(chips)',
 P_PATH='@t6g_mb_lib.t6g(sch_1):page361_i33@pure_quanta.q_cap(chips)',
 PATH='I33',
 DRAWING='@T6G_MB_LIB.T6G(SCH_1):PAGE470',
 TOLERANCE='5%',
 MATERIAL='NPO',
 PHYS_PAGE='361',
 XY='(-3500,2675)',
 ROT='0',
 VER='2',
 PACK_TYPE='0402',
 LOCATION='PC6534',
 CDS_LIB='pure_quanta',
 CDS_PART_NAME='Q_CAP_0402-150PF,50V,5%,NPO,TMP_QCH11506JB08',
 VOLTAGE='50V',
 PART_NUMBER='TMP_QCH11506JB08',
 VALUE='150PF',
 PRIM_FILE='./archive_libs/logical/q_cap/chips/chips.prt';

PART_NAME
 PC6537 'Q_CAP_0402-0.1UF,25V,10%,X7R,CH4104K1B00':;

SECTION_NUMBER 1
 '@T6G_MB_LIB.T6G(SCH_1):PAGE470_I25@PURE_QUANTA.Q_CAP(CHIPS)':
 C_PATH='@t6g_mb_lib.t6g(sch_1):page470_i25@pure_quanta.q_cap(chips)',
 P_PATH='@t6g_mb_lib.t6g(sch_1):page361_i25@pure_quanta.q_cap(chips)',
 PATH='I25',
 DRAWING='@T6G_MB_LIB.T6G(SCH_1):PAGE470',
 TOLERANCE='10%',
 MATERIAL='X7R',
 PHYS_PAGE='361',
 XY='(-4925,2575)',
 ROT='0',
 VER='1',
 PACK_TYPE='0402',
 LOCATION='PC6537',
 CDS_LIB='pure_quanta',
 CDS_PART_NAME='Q_CAP_0402-0.1UF,25V,10%,X7R,CH4104K1B00',
 VOLTAGE='25V',
 PART_NUMBER='CH4104K1B00',
 VALUE='0.1UF',
 PRIM_FILE='./archive_libs/logical/q_cap/chips/chips.prt';

PART_NAME
 PC6540 'Q_CAP_0402-3300PF,50V,10%,X7R,TMP_QCH2336K1B12':;

SECTION_NUMBER 1
 '@T6G_MB_LIB.T6G(SCH_1):PAGE475_I121@PURE_QUANTA.Q_CAP(CHIPS)':
 C_PATH='@t6g_mb_lib.t6g(sch_1):page475_i121@pure_quanta.q_cap(chips)',
 P_PATH='@t6g_mb_lib.t6g(sch_1):page362_i121@pure_quanta.q_cap(chips)',
 PATH='I121',
 DRAWING='@T6G_MB_LIB.T6G(SCH_1):PAGE475',
 SEC_TYPE='0402',
 TOLERANCE='10%',
 MATERIAL='X7R',
 PHYS_PAGE='362',
 XY='(-8450,5700)',
 ROT='0',
 VER='1',
 PACK_TYPE='0402',
 LOCATION='PC6540',
 SEC='1',
 CDS_LIB='pure_quanta',
 CDS_PART_NAME='Q_CAP_0402-3300PF,50V,10%,X7R,TMP_QCH2336K1B12',
 VOLTAGE='50V',
 PART_NUMBER='TMP_QCH2336K1B12',
 VALUE='3300PF',
 PRIM_FILE='./archive_libs/logical/q_cap/chips/chips.prt';

PART_NAME
 PC6543 'Q_CAP_C0402-100NF,50V,10%,X7R,CH4106K1B01':;

SECTION_NUMBER 1
 '@T6G_MB_LIB.T6G(SCH_1):PAGE477_I74@PURE_QUANTA.Q_CAP(CHIPS)':
 C_PATH='@t6g_mb_lib.t6g(sch_1):page477_i74@pure_quanta.q_cap(chips)',
 P_PATH='@t6g_mb_lib.t6g(sch_1):page364_i74@pure_quanta.q_cap(chips)',
 PATH='I74',
 DRAWING='@T6G_MB_LIB.T6G(SCH_1):PAGE477',
 TOLERANCE='10%',
 MATERIAL='X7R',
 PHYS_PAGE='364',
 XY='(-2875,5975)',
 ROT='0',
 VER='1',
 PACK_TYPE='C0402',
 LOCATION='PC6543',
 CDS_LIB='pure_quanta',
 CDS_PART_NAME='Q_CAP_C0402-100NF,50V,10%,X7R,CH4106K1B01',
 VOLTAGE='50V',
 PART_NUMBER='CH4106K1B01',
 VALUE='100NF',
 PRIM_FILE='./archive_libs/logical/q_cap/chips/chips.prt';

PART_NAME
 PC6544 'Q_CAP_C0402-1UF,16V,10%,X6S,CH5103KEB01':;

SECTION_NUMBER 1
 '@T6G_MB_LIB.T6G(SCH_1):PAGE477_I75@PURE_QUANTA.Q_CAP(CHIPS)':
 C_PATH='@t6g_mb_lib.t6g(sch_1):page477_i75@pure_quanta.q_cap(chips)',
 P_PATH='@t6g_mb_lib.t6g(sch_1):page364_i75@pure_quanta.q_cap(chips)',
 PATH='I75',
 DRAWING='@T6G_MB_LIB.T6G(SCH_1):PAGE477',
 TOLERANCE='10%',
 MATERIAL='X6S',
 PHYS_PAGE='364',
 XY='(-2475,5975)',
 ROT='0',
 VER='1',
 PACK_TYPE='C0402',
 LOCATION='PC6544',
 CDS_LIB='pure_quanta',
 CDS_PART_NAME='Q_CAP_C0402-1UF,16V,10%,X6S,CH5103KEB01',
 VOLTAGE='16V',
 PART_NUMBER='CH5103KEB01',
 VALUE='1UF',
 PRIM_FILE='./archive_libs/logical/q_cap/chips/chips.prt';

PART_NAME
 PC6545 'Q_CAP_C0402-1UF,16V,10%,X6S,CH5103KEB01':;

SECTION_NUMBER 1
 '@T6G_MB_LIB.T6G(SCH_1):PAGE477_I73@PURE_QUANTA.Q_CAP(CHIPS)':
 C_PATH='@t6g_mb_lib.t6g(sch_1):page477_i73@pure_quanta.q_cap(chips)',
 P_PATH='@t6g_mb_lib.t6g(sch_1):page364_i73@pure_quanta.q_cap(chips)',
 PATH='I73',
 DRAWING='@T6G_MB_LIB.T6G(SCH_1):PAGE477',
 TOLERANCE='10%',
 MATERIAL='X6S',
 PHYS_PAGE='364',
 XY='(-2475,5500)',
 ROT='0',
 VER='1',
 PACK_TYPE='C0402',
 LOCATION='PC6545',
 CDS_LIB='pure_quanta',
 CDS_PART_NAME='Q_CAP_C0402-1UF,16V,10%,X6S,CH5103KEB01',
 VOLTAGE='16V',
 PART_NUMBER='CH5103KEB01',
 VALUE='1UF',
 PRIM_FILE='./archive_libs/logical/q_cap/chips/chips.prt';

PART_NAME
 PC6546 'Q_CAP_C0402-10UF,6.3V,20%,X6S,CH6101MEB03':;

SECTION_NUMBER 1
 '@T6G_MB_LIB.T6G(SCH_1):PAGE477_I72@PURE_QUANTA.Q_CAP(CHIPS)':
 C_PATH='@t6g_mb_lib.t6g(sch_1):page477_i72@pure_quanta.q_cap(chips)',
 P_PATH='@t6g_mb_lib.t6g(sch_1):page364_i72@pure_quanta.q_cap(chips)',
 PATH='I72',
 DRAWING='@T6G_MB_LIB.T6G(SCH_1):PAGE477',
 TOLERANCE='20%',
 MATERIAL='X6S',
 PHYS_PAGE='364',
 XY='(-2875,5500)',
 ROT='0',
 VER='1',
 PACK_TYPE='C0402',
 LOCATION='PC6546',
 CDS_LIB='pure_quanta',
 CDS_PART_NAME='Q_CAP_C0402-10UF,6.3V,20%,X6S,CH6101MEB03',
 VOLTAGE='6.3V',
 PART_NUMBER='CH6101MEB03',
 VALUE='10UF',
 PRIM_FILE='./archive_libs/logical/q_cap/chips/chips.prt';

PART_NAME
 PC6550_09P0_1 'Q_CAP_C0402-2.2UF,10V,10%,X6S,CH5222KEB01':;

SECTION_NUMBER 1
 '@T6G_MB_LIB.T6G(SCH_1):PAGE476_I47@PURE_QUANTA.Q_CAP(CHIPS)':
 C_PATH='@t6g_mb_lib.t6g(sch_1):page476_i47@pure_quanta.q_cap(chips)',
 P_PATH='@t6g_mb_lib.t6g(sch_1):page363_i47@pure_quanta.q_cap(chips)',
 PATH='I47',
 DRAWING='@T6G_MB_LIB.T6G(SCH_1):PAGE476',
 BOM_COST='VR_DIMM ',
 TOLERANCE='10%',
 MATERIAL='X6S',
 PHYS_PAGE='363',
 XY='(-5200,-5500)',
 ROT='0',
 VER='1',
 PACK_TYPE='C0402',
 LOCATION='PC6550_09P0_1',
 CDS_LIB='pure_quanta',
 CDS_PART_NAME='Q_CAP_C0402-2.2UF,10V,10%,X6S,CH5222KEB01',
 VOLTAGE='10V',
 PART_NUMBER='CH5222KEB01',
 VALUE='2.2UF',
 PRIM_FILE='./archive_libs/logical/q_cap/chips/chips.prt';

PART_NAME
 PC6551_09P0_2 'Q_CAP_C0402-2.2UF,10V,10%,X6S,CH5222KEB01':;

SECTION_NUMBER 1
 '@T6G_MB_LIB.T6G(SCH_1):PAGE476_I267@PURE_QUANTA.Q_CAP(CHIPS)':
 C_PATH='@t6g_mb_lib.t6g(sch_1):page476_i267@pure_quanta.q_cap(chips)',
 P_PATH='@t6g_mb_lib.t6g(sch_1):page363_i267@pure_quanta.q_cap(chips)',
 PATH='I267',
 DRAWING='@T6G_MB_LIB.T6G(SCH_1):PAGE476',
 BOM_COST='VR_DIMM ',
 TOLERANCE='10%',
 MATERIAL='X6S',
 PHYS_PAGE='363',
 XY='(-5075,-8400)',
 ROT='0',
 VER='1',
 PACK_TYPE='C0402',
 LOCATION='PC6551_09P0_2',
 CDS_LIB='pure_quanta',
 CDS_PART_NAME='Q_CAP_C0402-2.2UF,10V,10%,X6S,CH5222KEB01',
 VOLTAGE='10V',
 PART_NUMBER='CH5222KEB01',
 VALUE='2.2UF',
 PRIM_FILE='./archive_libs/logical/q_cap/chips/chips.prt';

PART_NAME
 PC6552 'Q_CAP_C0402-2.2UF,10V,10%,X6S,CH5222KEB01':;

SECTION_NUMBER 1
 '@T6G_MB_LIB.T6G(SCH_1):PAGE476_I48@PURE_QUANTA.Q_CAP(CHIPS)':
 C_PATH='@t6g_mb_lib.t6g(sch_1):page476_i48@pure_quanta.q_cap(chips)',
 P_PATH='@t6g_mb_lib.t6g(sch_1):page363_i48@pure_quanta.q_cap(chips)',
 PATH='I48',
 DRAWING='@T6G_MB_LIB.T6G(SCH_1):PAGE476',
 BOM_COST='VR_DIMM ',
 TOLERANCE='10%',
 MATERIAL='X6S',
 PHYS_PAGE='363',
 XY='(-5900,-6025)',
 ROT='0',
 VER='1',
 PACK_TYPE='C0402',
 LOCATION='PC6552',
 CDS_LIB='pure_quanta',
 CDS_PART_NAME='Q_CAP_C0402-2.2UF,10V,10%,X6S,CH5222KEB01',
 VOLTAGE='10V',
 PART_NUMBER='CH5222KEB01',
 VALUE='2.2UF',
 PRIM_FILE='./archive_libs/logical/q_cap/chips/chips.prt';

PART_NAME
 PC6553_1 'Q_CAP_C0402-100NF,50V,10%,X7R,CH4106K1B01':;

SECTION_NUMBER 1
 '@T6G_MB_LIB.T6G(SCH_1):PAGE476_I68@PURE_QUANTA.Q_CAP(CHIPS)':
 C_PATH='@t6g_mb_lib.t6g(sch_1):page476_i68@pure_quanta.q_cap(chips)',
 P_PATH='@t6g_mb_lib.t6g(sch_1):page363_i68@pure_quanta.q_cap(chips)',
 PATH='I68',
 DRAWING='@T6G_MB_LIB.T6G(SCH_1):PAGE476',
 BOM_COST='VR_CPU',
 TOLERANCE='10%',
 MATERIAL='X7R',
 PHYS_PAGE='363',
 XY='(-6650,-6875)',
 ROT='0',
 VER='1',
 PACK_TYPE='C0402',
 LOCATION='PC6553_1',
 CDS_LIB='pure_quanta',
 CDS_PART_NAME='Q_CAP_C0402-100NF,50V,10%,X7R,CH4106K1B01',
 VOLTAGE='50V',
 PART_NUMBER='CH4106K1B01',
 VALUE='100NF',
 PRIM_FILE='./archive_libs/logical/q_cap/chips/chips.prt';

PART_NAME
 PC6554_1 'Q_CAP_C0402-1UF,25V,10%,X6S,CH5104KEB02':;

SECTION_NUMBER 1
 '@T6G_MB_LIB.T6G(SCH_1):PAGE476_I29@PURE_QUANTA.Q_CAP(CHIPS)':
 C_PATH='@t6g_mb_lib.t6g(sch_1):page476_i29@pure_quanta.q_cap(chips)',
 P_PATH='@t6g_mb_lib.t6g(sch_1):page363_i29@pure_quanta.q_cap(chips)',
 PATH='I29',
 DRAWING='@T6G_MB_LIB.T6G(SCH_1):PAGE476',
 BOM_COST='VR_DIMM ',
 TOLERANCE='10%',
 MATERIAL='X6S',
 PHYS_PAGE='363',
 XY='(-2500,-5650)',
 ROT='0',
 VER='1',
 PACK_TYPE='C0402',
 LOCATION='PC6554_1',
 CDS_LIB='pure_quanta',
 CDS_PART_NAME='Q_CAP_C0402-1UF,25V,10%,X6S,CH5104KEB02',
 VOLTAGE='25V',
 PART_NUMBER='CH5104KEB02',
 VALUE='1UF',
 PRIM_FILE='./archive_libs/logical/q_cap/chips/chips.prt';

PART_NAME
 PC6555_1 'Q_CAP_0402-3300PF,50V,10%,X7R,TMP_QCH2336K1B12':;

SECTION_NUMBER 1
 '@T6G_MB_LIB.T6G(SCH_1):PAGE476_I6@PURE_QUANTA.Q_CAP(CHIPS)':
 C_PATH='@t6g_mb_lib.t6g(sch_1):page476_i6@pure_quanta.q_cap(chips)',
 P_PATH='@t6g_mb_lib.t6g(sch_1):page363_i6@pure_quanta.q_cap(chips)',
 PATH='I6',
 DRAWING='@T6G_MB_LIB.T6G(SCH_1):PAGE476',
 BOM_COST='VR_DIMM ',
 TOLERANCE='10%',
 MATERIAL='X7R',
 PHYS_PAGE='363',
 XY='(-3000,-5650)',
 ROT='0',
 VER='1',
 PACK_TYPE='0402',
 LOCATION='PC6555_1',
 CDS_LIB='pure_quanta',
 CDS_PART_NAME='Q_CAP_0402-3300PF,50V,10%,X7R,TMP_QCH2336K1B12',
 VOLTAGE='50V',
 PART_NUMBER='TMP_QCH2336K1B12',
 VALUE='3300PF',
 PRIM_FILE='./archive_libs/logical/q_cap/chips/chips.prt';

PART_NAME
 PC6556_1 'Q_CAP_C0805-22UF,16V,20%,X6S,CH6223MEA01':
 REUSE_ID='41';

SECTION_NUMBER 1
 '@T6G_MB_LIB.T6G(SCH_1):PAGE476_I27@PURE_QUANTA.Q_CAP(CHIPS)':
 C_PATH='@t6g_mb_lib.t6g(sch_1):page476_i27@pure_quanta.q_cap(chips)',
 P_PATH='@t6g_mb_lib.t6g(sch_1):page363_i27@pure_quanta.q_cap(chips)',
 PATH='I27',
 DRAWING='@T6G_MB_LIB.T6G(SCH_1):PAGE476',
 BOM_COST='VR_DIMM ',
 TOLERANCE='20%',
 MATERIAL='X6S',
 PHYS_PAGE='363',
 XY='(-2000,-5650)',
 ROT='0',
 VER='1',
 PACK_TYPE='C0805',
 LOCATION='PC6556_1',
 CDS_LIB='pure_quanta',
 CDS_PART_NAME='Q_CAP_C0805-22UF,16V,20%,X6S,CH6223MEA01',
 REUSE_ID='41',
 VOLTAGE='16V',
 PART_NUMBER='CH6223MEA01',
 VALUE='22UF',
 PRIM_FILE='./archive_libs/logical/q_cap/chips/chips.prt';

PART_NAME
 PC6557_1 'Q_CAP_C0805-22UF,16V,20%,X6S,CH6223MEA01':
 REUSE_ID='41';

SECTION_NUMBER 1
 '@T6G_MB_LIB.T6G(SCH_1):PAGE476_I24@PURE_QUANTA.Q_CAP(CHIPS)':
 C_PATH='@t6g_mb_lib.t6g(sch_1):page476_i24@pure_quanta.q_cap(chips)',
 P_PATH='@t6g_mb_lib.t6g(sch_1):page363_i24@pure_quanta.q_cap(chips)',
 PATH='I24',
 DRAWING='@T6G_MB_LIB.T6G(SCH_1):PAGE476',
 BOM_COST='VR_DIMM ',
 TOLERANCE='20%',
 MATERIAL='X6S',
 PHYS_PAGE='363',
 XY='(-1500,-5650)',
 ROT='0',
 VER='1',
 PACK_TYPE='C0805',
 LOCATION='PC6557_1',
 CDS_LIB='pure_quanta',
 CDS_PART_NAME='Q_CAP_C0805-22UF,16V,20%,X6S,CH6223MEA01',
 REUSE_ID='41',
 VOLTAGE='16V',
 PART_NUMBER='CH6223MEA01',
 VALUE='22UF',
 PRIM_FILE='./archive_libs/logical/q_cap/chips/chips.prt';

PART_NAME
 PC6558_1 'Q_CAP_C0805-22UF,16V,20%,X6S,CH6223MEA01':
 REUSE_ID='41';

SECTION_NUMBER 1
 '@T6G_MB_LIB.T6G(SCH_1):PAGE476_I21@PURE_QUANTA.Q_CAP(CHIPS)':
 C_PATH='@t6g_mb_lib.t6g(sch_1):page476_i21@pure_quanta.q_cap(chips)',
 P_PATH='@t6g_mb_lib.t6g(sch_1):page363_i21@pure_quanta.q_cap(chips)',
 PATH='I21',
 DRAWING='@T6G_MB_LIB.T6G(SCH_1):PAGE476',
 BOM_COST='VR_DIMM ',
 TOLERANCE='20%',
 MATERIAL='X6S',
 PHYS_PAGE='363',
 XY='(-1025,-5650)',
 ROT='0',
 VER='1',
 PACK_TYPE='C0805',
 LOCATION='PC6558_1',
 CDS_LIB='pure_quanta',
 CDS_PART_NAME='Q_CAP_C0805-22UF,16V,20%,X6S,CH6223MEA01',
 REUSE_ID='41',
 VOLTAGE='16V',
 PART_NUMBER='CH6223MEA01',
 VALUE='22UF',
 PRIM_FILE='./archive_libs/logical/q_cap/chips/chips.prt';

PART_NAME
 PC6559_1 'Q_CAP_C0805-22UF,16V,20%,X6S,CH6223MEA01':
 REUSE_ID='41';

SECTION_NUMBER 1
 '@T6G_MB_LIB.T6G(SCH_1):PAGE476_I210@PURE_QUANTA.Q_CAP(CHIPS)':
 C_PATH='@t6g_mb_lib.t6g(sch_1):page476_i210@pure_quanta.q_cap(chips)',
 P_PATH='@t6g_mb_lib.t6g(sch_1):page363_i210@pure_quanta.q_cap(chips)',
 PATH='I210',
 DRAWING='@T6G_MB_LIB.T6G(SCH_1):PAGE476',
 SEC_TYPE='C0805',
 BOM_COST='VR_DIMM ',
 TOLERANCE='20%',
 MATERIAL='X6S',
 PHYS_PAGE='363',
 XY='(-650,-5650)',
 ROT='0',
 VER='1',
 PACK_TYPE='C0805',
 LOCATION='PC6559_1',
 SEC='1',
 CDS_LIB='pure_quanta',
 CDS_PART_NAME='Q_CAP_C0805-22UF,16V,20%,X6S,CH6223MEA01',
 REUSE_ID='41',
 VOLTAGE='16V',
 PART_NUMBER='CH6223MEA01',
 VALUE='22UF',
 PRIM_FILE='./archive_libs/logical/q_cap/chips/chips.prt';

PART_NAME
 PC6560 'Q_CAP_C0805-22UF,16V,20%,X6S,CH6223MEA01':;

SECTION_NUMBER 1
 '@T6G_MB_LIB.T6G(SCH_1):PAGE476_I217@PURE_QUANTA.Q_CAP(CHIPS)':
 C_PATH='@t6g_mb_lib.t6g(sch_1):page476_i217@pure_quanta.q_cap(chips)',
 P_PATH='@t6g_mb_lib.t6g(sch_1):page363_i217@pure_quanta.q_cap(chips)',
 PATH='I217',
 DRAWING='@T6G_MB_LIB.T6G(SCH_1):PAGE476',
 SEC_TYPE='C0805',
 TOLERANCE='20%',
 MATERIAL='X6S',
 PHYS_PAGE='363',
 XY='(-250,-5700)',
 ROT='0',
 VER='1',
 PACK_TYPE='C0805',
 LOCATION='PC6560',
 SEC='1',
 CDS_LIB='pure_quanta',
 CDS_PART_NAME='Q_CAP_C0805-22UF,16V,20%,X6S,CH6223MEA01',
 VOLTAGE='16V',
 PART_NUMBER='CH6223MEA01',
 VALUE='22UF',
 PRIM_FILE='./archive_libs/logical/q_cap/chips/chips.prt';

PART_NAME
 PC6561 'Q_CAPP_SMLF-100UF,16V,20%,OSCON,CC71003MZ30':;

SECTION_NUMBER 1
 '@T6G_MB_LIB.T6G(SCH_1):PAGE476_I209@PURE_QUANTA.Q_CAPP(CHIPS)':
 C_PATH='@t6g_mb_lib.t6g(sch_1):page476_i209@pure_quanta.q_capp(chips)',
 P_PATH='@t6g_mb_lib.t6g(sch_1):page363_i209@pure_quanta.q_capp(chips)',
 PATH='I209',
 DRAWING='@T6G_MB_LIB.T6G(SCH_1):PAGE476',
 TOLERANCE='20%',
 MATERIAL='OSCON',
 PHYS_PAGE='363',
 XY='(600,-5675)',
 ROT='0',
 VER='1',
 PACK_TYPE='SMLF',
 LOCATION='PC6561',
 CDS_LIB='pure_quanta',
 CDS_PART_NAME='Q_CAPP_SMLF-100UF,16V,20%,OSCON,CC71003MZ30',
 VOLTAGE='16V',
 PART_NUMBER='CC71003MZ30',
 VALUE='100UF',
 PRIM_FILE='./archive_libs/logical/q_capp/chips/chips.prt';

PART_NAME
 PC6562 'Q_CAP_0402-0.1UF,25V,10%,X7R,CH4104K1B00':;

SECTION_NUMBER 1
 '@T6G_MB_LIB.T6G(SCH_1):PAGE476_I291@PURE_QUANTA.Q_CAP(CHIPS)':
 C_PATH='@t6g_mb_lib.t6g(sch_1):page476_i291@pure_quanta.q_cap(chips)',
 P_PATH='@t6g_mb_lib.t6g(sch_1):page363_i291@pure_quanta.q_cap(chips)',
 PATH='I291',
 DRAWING='@T6G_MB_LIB.T6G(SCH_1):PAGE476',
 TOLERANCE='10%',
 MATERIAL='X7R',
 PHYS_PAGE='363',
 XY='(2000,-5675)',
 ROT='0',
 VER='1',
 PACK_TYPE='0402',
 LOCATION='PC6562',
 CDS_LIB='pure_quanta',
 CDS_PART_NAME='Q_CAP_0402-0.1UF,25V,10%,X7R,CH4104K1B00',
 VOLTAGE='25V',
 PART_NUMBER='CH4104K1B00',
 VALUE='0.1UF',
 PRIM_FILE='./archive_libs/logical/q_cap/chips/chips.prt';

PART_NAME
 PC6563 'Q_CAP_C0402-100NF,50V,10%,X7R,CH4106K1B01':
 REUSE_ID='55';

SECTION_NUMBER 1
 '@T6G_MB_LIB.T6G(SCH_1):PAGE476_I30@PURE_QUANTA.Q_CAP(CHIPS)':
 C_PATH='@t6g_mb_lib.t6g(sch_1):page476_i30@pure_quanta.q_cap(chips)',
 P_PATH='@t6g_mb_lib.t6g(sch_1):page363_i30@pure_quanta.q_cap(chips)',
 PATH='I30',
 DRAWING='@T6G_MB_LIB.T6G(SCH_1):PAGE476',
 BOM_COST='VR_DIMM ',
 TOLERANCE='10%',
 MATERIAL='X7R',
 PHYS_PAGE='363',
 XY='(-1125,-6100)',
 ROT='0',
 VER='2',
 PACK_TYPE='C0402',
 LOCATION='PC6563',
 CDS_LIB='pure_quanta',
 CDS_PART_NAME='Q_CAP_C0402-100NF,50V,10%,X7R,CH4106K1B01',
 REUSE_ID='55',
 VOLTAGE='50V',
 PART_NUMBER='CH4106K1B01',
 VALUE='100NF',
 PRIM_FILE='./archive_libs/logical/q_cap/chips/chips.prt';

PART_NAME
 PC6564 'Q_CAP_C0402-560PF,50V,10%,EMPTY,CH1566K1B09':;

SECTION_NUMBER 1
 '@T6G_MB_LIB.T6G(SCH_1):PAGE476_I285@PURE_QUANTA.Q_CAP(CHIPS)':
 C_PATH='@t6g_mb_lib.t6g(sch_1):page476_i285@pure_quanta.q_cap(chips)',
 P_PATH='@t6g_mb_lib.t6g(sch_1):page363_i285@pure_quanta.q_cap(chips)',
 PATH='I285',
 DRAWING='@T6G_MB_LIB.T6G(SCH_1):PAGE476',
 TOLERANCE='10%',
 MATERIAL='EMPTY',
 PHYS_PAGE='363',
 XY='(-2400,-6650)',
 ROT='0',
 VER='1',
 PACK_TYPE='C0402',
 LOCATION='PC6564',
 CDS_LIB='pure_quanta',
 CDS_PART_NAME='Q_CAP_C0402-560PF,50V,10%,EMPTY,CH1566K1B09',
 VOLTAGE='50V',
 PART_NUMBER='CH1566K1B09',
 VALUE='560PF',
 PRIM_FILE='./archive_libs/logical/q_cap/chips/chips.prt';

PART_NAME
 PC6565 'Q_CAP_C0402-100NF,50V,10%,X7R,CH4106K1B01':;

SECTION_NUMBER 1
 '@T6G_MB_LIB.T6G(SCH_1):PAGE476_I33@PURE_QUANTA.Q_CAP(CHIPS)':
 C_PATH='@t6g_mb_lib.t6g(sch_1):page476_i33@pure_quanta.q_cap(chips)',
 P_PATH='@t6g_mb_lib.t6g(sch_1):page363_i33@pure_quanta.q_cap(chips)',
 PATH='I33',
 DRAWING='@T6G_MB_LIB.T6G(SCH_1):PAGE476',
 BOM_COST='VR_DIMM ',
 TOLERANCE='10%',
 MATERIAL='X7R',
 PHYS_PAGE='363',
 XY='(-1150,-6600)',
 ROT='0',
 VER='1',
 PACK_TYPE='C0402',
 LOCATION='PC6565',
 CDS_LIB='pure_quanta',
 CDS_PART_NAME='Q_CAP_C0402-100NF,50V,10%,X7R,CH4106K1B01',
 VOLTAGE='50V',
 PART_NUMBER='CH4106K1B01',
 VALUE='100NF',
 PRIM_FILE='./archive_libs/logical/q_cap/chips/chips.prt';

PART_NAME
 PC6566_1 'Q_CAP_C0805-22UF,4V,20%,X6S,CH622KMEA03':;

SECTION_NUMBER 1
 '@T6G_MB_LIB.T6G(SCH_1):PAGE476_I202@PURE_QUANTA.Q_CAP(CHIPS)':
 C_PATH='@t6g_mb_lib.t6g(sch_1):page476_i202@pure_quanta.q_cap(chips)',
 P_PATH='@t6g_mb_lib.t6g(sch_1):page363_i202@pure_quanta.q_cap(chips)',
 PATH='I202',
 DRAWING='@T6G_MB_LIB.T6G(SCH_1):PAGE476',
 TOLERANCE='20%',
 MATERIAL='X6S',
 PHYS_PAGE='363',
 XY='(-825,-6600)',
 ROT='0',
 VER='1',
 PACK_TYPE='C0805',
 LOCATION='PC6566_1',
 CDS_LIB='pure_quanta',
 CDS_PART_NAME='Q_CAP_C0805-22UF,4V,20%,X6S,CH622KMEA03',
 VOLTAGE='4V',
 PART_NUMBER='CH622KMEA03',
 VALUE='22UF',
 PRIM_FILE='./archive_libs/logical/q_cap/chips/chips.prt';

PART_NAME
 PC6567_1 'Q_CAP_C0805-22UF,4V,20%,X6S,CH622KMEA03':;

SECTION_NUMBER 1
 '@T6G_MB_LIB.T6G(SCH_1):PAGE476_I223@PURE_QUANTA.Q_CAP(CHIPS)':
 C_PATH='@t6g_mb_lib.t6g(sch_1):page476_i223@pure_quanta.q_cap(chips)',
 P_PATH='@t6g_mb_lib.t6g(sch_1):page363_i223@pure_quanta.q_cap(chips)',
 PATH='I223',
 DRAWING='@T6G_MB_LIB.T6G(SCH_1):PAGE476',
 TOLERANCE='20%',
 MATERIAL='X6S',
 PHYS_PAGE='363',
 XY='(-600,-6600)',
 ROT='0',
 VER='1',
 PACK_TYPE='C0805',
 LOCATION='PC6567_1',
 CDS_LIB='pure_quanta',
 CDS_PART_NAME='Q_CAP_C0805-22UF,4V,20%,X6S,CH622KMEA03',
 VOLTAGE='4V',
 PART_NUMBER='CH622KMEA03',
 VALUE='22UF',
 PRIM_FILE='./archive_libs/logical/q_cap/chips/chips.prt';

PART_NAME
 PC6568 'Q_CAPP_SMLF-470UF,2.5V,20%,SPCAP,CH747LM8818':;

SECTION_NUMBER 1
 '@T6G_MB_LIB.T6G(SCH_1):PAGE476_I224@PURE_QUANTA.Q_CAPP(CHIPS)':
 C_PATH='@t6g_mb_lib.t6g(sch_1):page476_i224@pure_quanta.q_capp(chips)',
 P_PATH='@t6g_mb_lib.t6g(sch_1):page363_i224@pure_quanta.q_capp(chips)',
 PATH='I224',
 DRAWING='@T6G_MB_LIB.T6G(SCH_1):PAGE476',
 TOLERANCE='20%',
 MATERIAL='SPCAP',
 PHYS_PAGE='363',
 XY='(-375,-6600)',
 ROT='0',
 VER='1',
 PACK_TYPE='SMLF',
 LOCATION='PC6568',
 CDS_LIB='pure_quanta',
 CDS_PART_NAME='Q_CAPP_SMLF-470UF,2.5V,20%,SPCAP,CH747LM8818',
 VOLTAGE='2.5V',
 PART_NUMBER='CH747LM8818',
 VALUE='470UF',
 PRIM_FILE='./archive_libs/logical/q_capp/chips/chips.prt';

PART_NAME
 PC6569 'Q_CAPP_SMLF-470UF,2.5V,20%,SPCAP,CH747LM8818':;

SECTION_NUMBER 1
 '@T6G_MB_LIB.T6G(SCH_1):PAGE476_I225@PURE_QUANTA.Q_CAPP(CHIPS)':
 C_PATH='@t6g_mb_lib.t6g(sch_1):page476_i225@pure_quanta.q_capp(chips)',
 P_PATH='@t6g_mb_lib.t6g(sch_1):page363_i225@pure_quanta.q_capp(chips)',
 PATH='I225',
 DRAWING='@T6G_MB_LIB.T6G(SCH_1):PAGE476',
 TOLERANCE='20%',
 MATERIAL='SPCAP',
 PHYS_PAGE='363',
 XY='(-150,-6600)',
 ROT='0',
 VER='1',
 PACK_TYPE='SMLF',
 LOCATION='PC6569',
 CDS_LIB='pure_quanta',
 CDS_PART_NAME='Q_CAPP_SMLF-470UF,2.5V,20%,SPCAP,CH747LM8818',
 VOLTAGE='2.5V',
 PART_NUMBER='CH747LM8818',
 VALUE='470UF',
 PRIM_FILE='./archive_libs/logical/q_capp/chips/chips.prt';

PART_NAME
 PC6570 'Q_CAPP_SMLF-470UF,2.5V,20%,SPCAP,CH747LM8818':;

SECTION_NUMBER 1
 '@T6G_MB_LIB.T6G(SCH_1):PAGE476_I226@PURE_QUANTA.Q_CAPP(CHIPS)':
 C_PATH='@t6g_mb_lib.t6g(sch_1):page476_i226@pure_quanta.q_capp(chips)',
 P_PATH='@t6g_mb_lib.t6g(sch_1):page363_i226@pure_quanta.q_capp(chips)',
 PATH='I226',
 DRAWING='@T6G_MB_LIB.T6G(SCH_1):PAGE476',
 TOLERANCE='20%',
 MATERIAL='SPCAP',
 PHYS_PAGE='363',
 XY='(50,-6600)',
 ROT='0',
 VER='1',
 PACK_TYPE='SMLF',
 LOCATION='PC6570',
 CDS_LIB='pure_quanta',
 CDS_PART_NAME='Q_CAPP_SMLF-470UF,2.5V,20%,SPCAP,CH747LM8818',
 VOLTAGE='2.5V',
 PART_NUMBER='CH747LM8818',
 VALUE='470UF',
 PRIM_FILE='./archive_libs/logical/q_capp/chips/chips.prt';

PART_NAME
 PC6571 'Q_CAPP_SMLF-390UF,2.5V,20%,ALUM,CC7390JMZ13':;

SECTION_NUMBER 1
 '@T6G_MB_LIB.T6G(SCH_1):PAGE476_I227@PURE_QUANTA.Q_CAPP(CHIPS)':
 C_PATH='@t6g_mb_lib.t6g(sch_1):page476_i227@pure_quanta.q_capp(chips)',
 P_PATH='@t6g_mb_lib.t6g(sch_1):page363_i227@pure_quanta.q_capp(chips)',
 PATH='I227',
 DRAWING='@T6G_MB_LIB.T6G(SCH_1):PAGE476',
 TOLERANCE='20%',
 MATERIAL='ALUM',
 PHYS_PAGE='363',
 XY='(375,-6600)',
 ROT='0',
 VER='1',
 PACK_TYPE='SMLF',
 LOCATION='PC6571',
 CDS_LIB='pure_quanta',
 CDS_PART_NAME='Q_CAPP_SMLF-390UF,2.5V,20%,ALUM,CC7390JMZ13',
 VOLTAGE='2.5V',
 PART_NUMBER='CC7390JMZ13',
 VALUE='390UF',
 PRIM_FILE='./archive_libs/logical/q_capp/chips/chips.prt';

PART_NAME
 PC6572 'Q_CAPP_SMLF-390UF,2.5V,20%,ALUM,CC7390JMZ13':;

SECTION_NUMBER 1
 '@T6G_MB_LIB.T6G(SCH_1):PAGE476_I222@PURE_QUANTA.Q_CAPP(CHIPS)':
 C_PATH='@t6g_mb_lib.t6g(sch_1):page476_i222@pure_quanta.q_capp(chips)',
 P_PATH='@t6g_mb_lib.t6g(sch_1):page363_i222@pure_quanta.q_capp(chips)',
 PATH='I222',
 DRAWING='@T6G_MB_LIB.T6G(SCH_1):PAGE476',
 TOLERANCE='20%',
 MATERIAL='ALUM',
 PHYS_PAGE='363',
 XY='(625,-6600)',
 ROT='0',
 VER='1',
 PACK_TYPE='SMLF',
 LOCATION='PC6572',
 CDS_LIB='pure_quanta',
 CDS_PART_NAME='Q_CAPP_SMLF-390UF,2.5V,20%,ALUM,CC7390JMZ13',
 VOLTAGE='2.5V',
 PART_NUMBER='CC7390JMZ13',
 VALUE='390UF',
 PRIM_FILE='./archive_libs/logical/q_capp/chips/chips.prt';

PART_NAME
 PC6573 'Q_CAPP_SMLF-390UF,2.5V,20%,ALUM,CC7390JMZ13':;

SECTION_NUMBER 1
 '@T6G_MB_LIB.T6G(SCH_1):PAGE476_I238@PURE_QUANTA.Q_CAPP(CHIPS)':
 C_PATH='@t6g_mb_lib.t6g(sch_1):page476_i238@pure_quanta.q_capp(chips)',
 P_PATH='@t6g_mb_lib.t6g(sch_1):page363_i238@pure_quanta.q_capp(chips)',
 PATH='I238',
 DRAWING='@T6G_MB_LIB.T6G(SCH_1):PAGE476',
 TOLERANCE='20%',
 MATERIAL='ALUM',
 PHYS_PAGE='363',
 XY='(500,-9500)',
 ROT='0',
 VER='1',
 PACK_TYPE='SMLF',
 LOCATION='PC6573',
 CDS_LIB='pure_quanta',
 CDS_PART_NAME='Q_CAPP_SMLF-390UF,2.5V,20%,ALUM,CC7390JMZ13',
 VOLTAGE='2.5V',
 PART_NUMBER='CC7390JMZ13',
 VALUE='390UF',
 PRIM_FILE='./archive_libs/logical/q_capp/chips/chips.prt';

PART_NAME
 PC6574 'Q_CAPP_SMLF-390UF,2.5V,20%,ALUM,CC7390JMZ13':;

SECTION_NUMBER 1
 '@T6G_MB_LIB.T6G(SCH_1):PAGE476_I236@PURE_QUANTA.Q_CAPP(CHIPS)':
 C_PATH='@t6g_mb_lib.t6g(sch_1):page476_i236@pure_quanta.q_capp(chips)',
 P_PATH='@t6g_mb_lib.t6g(sch_1):page363_i236@pure_quanta.q_capp(chips)',
 PATH='I236',
 DRAWING='@T6G_MB_LIB.T6G(SCH_1):PAGE476',
 TOLERANCE='20%',
 MATERIAL='ALUM',
 PHYS_PAGE='363',
 XY='(750,-9500)',
 ROT='0',
 VER='1',
 PACK_TYPE='SMLF',
 LOCATION='PC6574',
 CDS_LIB='pure_quanta',
 CDS_PART_NAME='Q_CAPP_SMLF-390UF,2.5V,20%,ALUM,CC7390JMZ13',
 VOLTAGE='2.5V',
 PART_NUMBER='CC7390JMZ13',
 VALUE='390UF',
 PRIM_FILE='./archive_libs/logical/q_capp/chips/chips.prt';

PART_NAME
 PC6575 'Q_CAP_C0402-2.2UF,10V,10%,X6S,CH5222KEB01':;

SECTION_NUMBER 1
 '@T6G_MB_LIB.T6G(SCH_1):PAGE476_I271@PURE_QUANTA.Q_CAP(CHIPS)':
 C_PATH='@t6g_mb_lib.t6g(sch_1):page476_i271@pure_quanta.q_cap(chips)',
 P_PATH='@t6g_mb_lib.t6g(sch_1):page363_i271@pure_quanta.q_cap(chips)',
 PATH='I271',
 DRAWING='@T6G_MB_LIB.T6G(SCH_1):PAGE476',
 BOM_COST='VR_DIMM ',
 TOLERANCE='10%',
 MATERIAL='X6S',
 PHYS_PAGE='363',
 XY='(-5775,-8925)',
 ROT='0',
 VER='1',
 PACK_TYPE='C0402',
 LOCATION='PC6575',
 CDS_LIB='pure_quanta',
 CDS_PART_NAME='Q_CAP_C0402-2.2UF,10V,10%,X6S,CH5222KEB01',
 VOLTAGE='10V',
 PART_NUMBER='CH5222KEB01',
 VALUE='2.2UF',
 PRIM_FILE='./archive_libs/logical/q_cap/chips/chips.prt';

PART_NAME
 PC6576 'Q_CAP_C0402-100NF,50V,10%,X7R,CH4106K1B01':;

SECTION_NUMBER 1
 '@T6G_MB_LIB.T6G(SCH_1):PAGE476_I281@PURE_QUANTA.Q_CAP(CHIPS)':
 C_PATH='@t6g_mb_lib.t6g(sch_1):page476_i281@pure_quanta.q_cap(chips)',
 P_PATH='@t6g_mb_lib.t6g(sch_1):page363_i281@pure_quanta.q_cap(chips)',
 PATH='I281',
 DRAWING='@T6G_MB_LIB.T6G(SCH_1):PAGE476',
 BOM_COST='VR_CPU',
 TOLERANCE='10%',
 MATERIAL='X7R',
 PHYS_PAGE='363',
 XY='(-6525,-9775)',
 ROT='0',
 VER='1',
 PACK_TYPE='C0402',
 LOCATION='PC6576',
 CDS_LIB='pure_quanta',
 CDS_PART_NAME='Q_CAP_C0402-100NF,50V,10%,X7R,CH4106K1B01',
 VOLTAGE='50V',
 PART_NUMBER='CH4106K1B01',
 VALUE='100NF',
 PRIM_FILE='./archive_libs/logical/q_cap/chips/chips.prt';

PART_NAME
 PC6577_2 'Q_CAP_C0402-1UF,25V,10%,X6S,CH5104KEB02':;

SECTION_NUMBER 1
 '@T6G_MB_LIB.T6G(SCH_1):PAGE476_I258@PURE_QUANTA.Q_CAP(CHIPS)':
 C_PATH='@t6g_mb_lib.t6g(sch_1):page476_i258@pure_quanta.q_cap(chips)',
 P_PATH='@t6g_mb_lib.t6g(sch_1):page363_i258@pure_quanta.q_cap(chips)',
 PATH='I258',
 DRAWING='@T6G_MB_LIB.T6G(SCH_1):PAGE476',
 BOM_COST='VR_DIMM ',
 TOLERANCE='10%',
 MATERIAL='X6S',
 PHYS_PAGE='363',
 XY='(-2375,-8550)',
 ROT='0',
 VER='1',
 PACK_TYPE='C0402',
 LOCATION='PC6577_2',
 CDS_LIB='pure_quanta',
 CDS_PART_NAME='Q_CAP_C0402-1UF,25V,10%,X6S,CH5104KEB02',
 VOLTAGE='25V',
 PART_NUMBER='CH5104KEB02',
 VALUE='1UF',
 PRIM_FILE='./archive_libs/logical/q_cap/chips/chips.prt';

PART_NAME
 PC6578_2 'Q_CAP_0402-3300PF,50V,10%,X7R,TMP_QCH2336K1B12':;

SECTION_NUMBER 1
 '@T6G_MB_LIB.T6G(SCH_1):PAGE476_I259@PURE_QUANTA.Q_CAP(CHIPS)':
 C_PATH='@t6g_mb_lib.t6g(sch_1):page476_i259@pure_quanta.q_cap(chips)',
 P_PATH='@t6g_mb_lib.t6g(sch_1):page363_i259@pure_quanta.q_cap(chips)',
 PATH='I259',
 DRAWING='@T6G_MB_LIB.T6G(SCH_1):PAGE476',
 BOM_COST='VR_DIMM ',
 TOLERANCE='10%',
 MATERIAL='X7R',
 PHYS_PAGE='363',
 XY='(-2875,-8550)',
 ROT='0',
 VER='1',
 PACK_TYPE='0402',
 LOCATION='PC6578_2',
 CDS_LIB='pure_quanta',
 CDS_PART_NAME='Q_CAP_0402-3300PF,50V,10%,X7R,TMP_QCH2336K1B12',
 VOLTAGE='50V',
 PART_NUMBER='TMP_QCH2336K1B12',
 VALUE='3300PF',
 PRIM_FILE='./archive_libs/logical/q_cap/chips/chips.prt';

PART_NAME
 PC6579_2 'Q_CAP_C0805-22UF,16V,20%,X6S,CH6223MEA01':
 REUSE_ID='41';

SECTION_NUMBER 1
 '@T6G_MB_LIB.T6G(SCH_1):PAGE476_I245@PURE_QUANTA.Q_CAP(CHIPS)':
 C_PATH='@t6g_mb_lib.t6g(sch_1):page476_i245@pure_quanta.q_cap(chips)',
 P_PATH='@t6g_mb_lib.t6g(sch_1):page363_i245@pure_quanta.q_cap(chips)',
 PATH='I245',
 DRAWING='@T6G_MB_LIB.T6G(SCH_1):PAGE476',
 BOM_COST='VR_DIMM ',
 TOLERANCE='20%',
 MATERIAL='X6S',
 PHYS_PAGE='363',
 XY='(-1875,-8550)',
 ROT='0',
 VER='1',
 PACK_TYPE='C0805',
 LOCATION='PC6579_2',
 CDS_LIB='pure_quanta',
 CDS_PART_NAME='Q_CAP_C0805-22UF,16V,20%,X6S,CH6223MEA01',
 REUSE_ID='41',
 VOLTAGE='16V',
 PART_NUMBER='CH6223MEA01',
 VALUE='22UF',
 PRIM_FILE='./archive_libs/logical/q_cap/chips/chips.prt';

PART_NAME
 PC6580_2 'Q_CAP_C0805-22UF,16V,20%,X6S,CH6223MEA01':
 REUSE_ID='41';

SECTION_NUMBER 1
 '@T6G_MB_LIB.T6G(SCH_1):PAGE476_I244@PURE_QUANTA.Q_CAP(CHIPS)':
 C_PATH='@t6g_mb_lib.t6g(sch_1):page476_i244@pure_quanta.q_cap(chips)',
 P_PATH='@t6g_mb_lib.t6g(sch_1):page363_i244@pure_quanta.q_cap(chips)',
 PATH='I244',
 DRAWING='@T6G_MB_LIB.T6G(SCH_1):PAGE476',
 BOM_COST='VR_DIMM ',
 TOLERANCE='20%',
 MATERIAL='X6S',
 PHYS_PAGE='363',
 XY='(-1375,-8550)',
 ROT='0',
 VER='1',
 PACK_TYPE='C0805',
 LOCATION='PC6580_2',
 CDS_LIB='pure_quanta',
 CDS_PART_NAME='Q_CAP_C0805-22UF,16V,20%,X6S,CH6223MEA01',
 REUSE_ID='41',
 VOLTAGE='16V',
 PART_NUMBER='CH6223MEA01',
 VALUE='22UF',
 PRIM_FILE='./archive_libs/logical/q_cap/chips/chips.prt';

PART_NAME
 PC6581_2 'Q_CAP_C0805-22UF,16V,20%,X6S,CH6223MEA01':
 REUSE_ID='41';

SECTION_NUMBER 1
 '@T6G_MB_LIB.T6G(SCH_1):PAGE476_I243@PURE_QUANTA.Q_CAP(CHIPS)':
 C_PATH='@t6g_mb_lib.t6g(sch_1):page476_i243@pure_quanta.q_cap(chips)',
 P_PATH='@t6g_mb_lib.t6g(sch_1):page363_i243@pure_quanta.q_cap(chips)',
 PATH='I243',
 DRAWING='@T6G_MB_LIB.T6G(SCH_1):PAGE476',
 BOM_COST='VR_DIMM ',
 TOLERANCE='20%',
 MATERIAL='X6S',
 PHYS_PAGE='363',
 XY='(-900,-8550)',
 ROT='0',
 VER='1',
 PACK_TYPE='C0805',
 LOCATION='PC6581_2',
 CDS_LIB='pure_quanta',
 CDS_PART_NAME='Q_CAP_C0805-22UF,16V,20%,X6S,CH6223MEA01',
 REUSE_ID='41',
 VOLTAGE='16V',
 PART_NUMBER='CH6223MEA01',
 VALUE='22UF',
 PRIM_FILE='./archive_libs/logical/q_cap/chips/chips.prt';

PART_NAME
 PC6582_2 'Q_CAP_C0805-22UF,16V,20%,X6S,CH6223MEA01':
 REUSE_ID='41';

SECTION_NUMBER 1
 '@T6G_MB_LIB.T6G(SCH_1):PAGE476_I242@PURE_QUANTA.Q_CAP(CHIPS)':
 C_PATH='@t6g_mb_lib.t6g(sch_1):page476_i242@pure_quanta.q_cap(chips)',
 P_PATH='@t6g_mb_lib.t6g(sch_1):page363_i242@pure_quanta.q_cap(chips)',
 PATH='I242',
 DRAWING='@T6G_MB_LIB.T6G(SCH_1):PAGE476',
 BOM_COST='VR_DIMM ',
 TOLERANCE='20%',
 MATERIAL='X6S',
 PHYS_PAGE='363',
 XY='(-525,-8550)',
 ROT='0',
 VER='1',
 PACK_TYPE='C0805',
 LOCATION='PC6582_2',
 CDS_LIB='pure_quanta',
 CDS_PART_NAME='Q_CAP_C0805-22UF,16V,20%,X6S,CH6223MEA01',
 REUSE_ID='41',
 VOLTAGE='16V',
 PART_NUMBER='CH6223MEA01',
 VALUE='22UF',
 PRIM_FILE='./archive_libs/logical/q_cap/chips/chips.prt';

PART_NAME
 PC6583 'Q_CAP_C0805-22UF,16V,20%,X6S,CH6223MEA01':;

SECTION_NUMBER 1
 '@T6G_MB_LIB.T6G(SCH_1):PAGE476_I241@PURE_QUANTA.Q_CAP(CHIPS)':
 C_PATH='@t6g_mb_lib.t6g(sch_1):page476_i241@pure_quanta.q_cap(chips)',
 P_PATH='@t6g_mb_lib.t6g(sch_1):page363_i241@pure_quanta.q_cap(chips)',
 PATH='I241',
 DRAWING='@T6G_MB_LIB.T6G(SCH_1):PAGE476',
 TOLERANCE='20%',
 MATERIAL='X6S',
 PHYS_PAGE='363',
 XY='(-125,-8600)',
 ROT='0',
 VER='1',
 PACK_TYPE='C0805',
 LOCATION='PC6583',
 CDS_LIB='pure_quanta',
 CDS_PART_NAME='Q_CAP_C0805-22UF,16V,20%,X6S,CH6223MEA01',
 VOLTAGE='16V',
 PART_NUMBER='CH6223MEA01',
 VALUE='22UF',
 PRIM_FILE='./archive_libs/logical/q_cap/chips/chips.prt';

PART_NAME
 PC6584 'Q_CAP_C0402-100NF,50V,10%,X7R,CH4106K1B01':
 REUSE_ID='55';

SECTION_NUMBER 1
 '@T6G_MB_LIB.T6G(SCH_1):PAGE476_I253@PURE_QUANTA.Q_CAP(CHIPS)':
 C_PATH='@t6g_mb_lib.t6g(sch_1):page476_i253@pure_quanta.q_cap(chips)',
 P_PATH='@t6g_mb_lib.t6g(sch_1):page363_i253@pure_quanta.q_cap(chips)',
 PATH='I253',
 DRAWING='@T6G_MB_LIB.T6G(SCH_1):PAGE476',
 BOM_COST='VR_DIMM ',
 TOLERANCE='10%',
 MATERIAL='X7R',
 PHYS_PAGE='363',
 XY='(-1000,-9000)',
 ROT='0',
 VER='2',
 PACK_TYPE='C0402',
 LOCATION='PC6584',
 CDS_LIB='pure_quanta',
 CDS_PART_NAME='Q_CAP_C0402-100NF,50V,10%,X7R,CH4106K1B01',
 REUSE_ID='55',
 VOLTAGE='50V',
 PART_NUMBER='CH4106K1B01',
 VALUE='100NF',
 PRIM_FILE='./archive_libs/logical/q_cap/chips/chips.prt';

PART_NAME
 PC6585 'Q_CAP_C0402-560PF,50V,10%,EMPTY,CH1566K1B09':;

SECTION_NUMBER 1
 '@T6G_MB_LIB.T6G(SCH_1):PAGE476_I288@PURE_QUANTA.Q_CAP(CHIPS)':
 C_PATH='@t6g_mb_lib.t6g(sch_1):page476_i288@pure_quanta.q_cap(chips)',
 P_PATH='@t6g_mb_lib.t6g(sch_1):page363_i288@pure_quanta.q_cap(chips)',
 PATH='I288',
 DRAWING='@T6G_MB_LIB.T6G(SCH_1):PAGE476',
 TOLERANCE='10%',
 MATERIAL='EMPTY',
 PHYS_PAGE='363',
 XY='(-2400,-9550)',
 ROT='0',
 VER='1',
 PACK_TYPE='C0402',
 LOCATION='PC6585',
 CDS_LIB='pure_quanta',
 CDS_PART_NAME='Q_CAP_C0402-560PF,50V,10%,EMPTY,CH1566K1B09',
 VOLTAGE='50V',
 PART_NUMBER='CH1566K1B09',
 VALUE='560PF',
 PRIM_FILE='./archive_libs/logical/q_cap/chips/chips.prt';

PART_NAME
 PC6586_2 'Q_CAP_C0805-22UF,4V,20%,X6S,CH622KMEA03':;

SECTION_NUMBER 1
 '@T6G_MB_LIB.T6G(SCH_1):PAGE476_I251@PURE_QUANTA.Q_CAP(CHIPS)':
 C_PATH='@t6g_mb_lib.t6g(sch_1):page476_i251@pure_quanta.q_cap(chips)',
 P_PATH='@t6g_mb_lib.t6g(sch_1):page363_i251@pure_quanta.q_cap(chips)',
 PATH='I251',
 DRAWING='@T6G_MB_LIB.T6G(SCH_1):PAGE476',
 TOLERANCE='20%',
 MATERIAL='X6S',
 PHYS_PAGE='363',
 XY='(-700,-9500)',
 ROT='0',
 VER='1',
 PACK_TYPE='C0805',
 LOCATION='PC6586_2',
 CDS_LIB='pure_quanta',
 CDS_PART_NAME='Q_CAP_C0805-22UF,4V,20%,X6S,CH622KMEA03',
 VOLTAGE='4V',
 PART_NUMBER='CH622KMEA03',
 VALUE='22UF',
 PRIM_FILE='./archive_libs/logical/q_cap/chips/chips.prt';

PART_NAME
 PC6587_2 'Q_CAP_C0805-22UF,4V,20%,X6S,CH622KMEA03':;

SECTION_NUMBER 1
 '@T6G_MB_LIB.T6G(SCH_1):PAGE476_I250@PURE_QUANTA.Q_CAP(CHIPS)':
 C_PATH='@t6g_mb_lib.t6g(sch_1):page476_i250@pure_quanta.q_cap(chips)',
 P_PATH='@t6g_mb_lib.t6g(sch_1):page363_i250@pure_quanta.q_cap(chips)',
 PATH='I250',
 DRAWING='@T6G_MB_LIB.T6G(SCH_1):PAGE476',
 TOLERANCE='20%',
 MATERIAL='X6S',
 PHYS_PAGE='363',
 XY='(-475,-9500)',
 ROT='0',
 VER='1',
 PACK_TYPE='C0805',
 LOCATION='PC6587_2',
 CDS_LIB='pure_quanta',
 CDS_PART_NAME='Q_CAP_C0805-22UF,4V,20%,X6S,CH622KMEA03',
 VOLTAGE='4V',
 PART_NUMBER='CH622KMEA03',
 VALUE='22UF',
 PRIM_FILE='./archive_libs/logical/q_cap/chips/chips.prt';

PART_NAME
 PC6600 'Q_CAP_0402-3300PF,50V,10%,X7R,TMP_QCH2336K1B12':;

SECTION_NUMBER 1
 '@T6G_MB_LIB.T6G(SCH_1):PAGE477_I28@PURE_QUANTA.Q_CAP(CHIPS)':
 C_PATH='@t6g_mb_lib.t6g(sch_1):page477_i28@pure_quanta.q_cap(chips)',
 P_PATH='@t6g_mb_lib.t6g(sch_1):page364_i28@pure_quanta.q_cap(chips)',
 PATH='I28',
 DRAWING='@T6G_MB_LIB.T6G(SCH_1):PAGE477',
 TOLERANCE='10%',
 MATERIAL='X7R',
 PHYS_PAGE='364',
 XY='(-5650,4000)',
 ROT='0',
 VER='1',
 PACK_TYPE='0402',
 LOCATION='PC6600',
 CDS_LIB='pure_quanta',
 CDS_PART_NAME='Q_CAP_0402-3300PF,50V,10%,X7R,TMP_QCH2336K1B12',
 VOLTAGE='50V',
 PART_NUMBER='TMP_QCH2336K1B12',
 VALUE='3300PF',
 PRIM_FILE='./archive_libs/logical/q_cap/chips/chips.prt';

PART_NAME
 PC6601 'Q_CAP_0402-0.1UF,25V,10%,EMPTY,CH4104K1B00':;

SECTION_NUMBER 1
 '@T6G_MB_LIB.T6G(SCH_1):PAGE475_I151@PURE_QUANTA.Q_CAP(CHIPS)':
 C_PATH='@t6g_mb_lib.t6g(sch_1):page475_i151@pure_quanta.q_cap(chips)',
 P_PATH='@t6g_mb_lib.t6g(sch_1):page362_i151@pure_quanta.q_cap(chips)',
 PATH='I151',
 DRAWING='@T6G_MB_LIB.T6G(SCH_1):PAGE475',
 SEC_TYPE='0402',
 TOLERANCE='10%',
 MATERIAL='EMPTY',
 PHYS_PAGE='362',
 XY='(-8675,2100)',
 ROT='0',
 VER='1',
 PACK_TYPE='0402',
 LOCATION='PC6601',
 SEC='1',
 CDS_LIB='pure_quanta',
 CDS_PART_NAME='Q_CAP_0402-0.1UF,25V,10%,EMPTY,CH4104K1B00',
 VOLTAGE='25V',
 PART_NUMBER='CH4104K1B00',
 VALUE='0.1UF',
 PRIM_FILE='./archive_libs/logical/q_cap/chips/chips.prt';

PART_NAME
 PC6602 'Q_CAP_0402-0.1UF,25V,10%,X7R,CH4104K1B00':;

SECTION_NUMBER 1
 '@T6G_MB_LIB.T6G(SCH_1):PAGE475_I123@PURE_QUANTA.Q_CAP(CHIPS)':
 C_PATH='@t6g_mb_lib.t6g(sch_1):page475_i123@pure_quanta.q_cap(chips)',
 P_PATH='@t6g_mb_lib.t6g(sch_1):page362_i123@pure_quanta.q_cap(chips)',
 PATH='I123',
 DRAWING='@T6G_MB_LIB.T6G(SCH_1):PAGE475',
 SEC_TYPE='0402',
 TOLERANCE='10%',
 MATERIAL='X7R',
 PHYS_PAGE='362',
 XY='(-7925,2100)',
 ROT='0',
 VER='1',
 PACK_TYPE='0402',
 LOCATION='PC6602',
 SEC='1',
 CDS_LIB='pure_quanta',
 CDS_PART_NAME='Q_CAP_0402-0.1UF,25V,10%,X7R,CH4104K1B00',
 VOLTAGE='25V',
 PART_NUMBER='CH4104K1B00',
 VALUE='0.1UF',
 PRIM_FILE='./archive_libs/logical/q_cap/chips/chips.prt';

PART_NAME
 PC6603 'Q_CAP_C0402-100NF,50V,10%,X7R,CH4106K1B01':;

SECTION_NUMBER 1
 '@T6G_MB_LIB.T6G(SCH_1):PAGE475_I144@PURE_QUANTA.Q_CAP(CHIPS)':
 C_PATH='@t6g_mb_lib.t6g(sch_1):page475_i144@pure_quanta.q_cap(chips)',
 P_PATH='@t6g_mb_lib.t6g(sch_1):page362_i144@pure_quanta.q_cap(chips)',
 PATH='I144',
 DRAWING='@T6G_MB_LIB.T6G(SCH_1):PAGE475',
 SEC_TYPE='C0402',
 TOLERANCE='10%',
 MATERIAL='X7R',
 PHYS_PAGE='362',
 XY='(-5675,7675)',
 ROT='0',
 VER='1',
 PACK_TYPE='C0402',
 LOCATION='PC6603',
 SEC='1',
 CDS_LIB='pure_quanta',
 CDS_PART_NAME='Q_CAP_C0402-100NF,50V,10%,X7R,CH4106K1B01',
 VOLTAGE='50V',
 PART_NUMBER='CH4106K1B01',
 VALUE='100NF',
 PRIM_FILE='./archive_libs/logical/q_cap/chips/chips.prt';

PART_NAME
 PC6604 'Q_CAP_C0402-1UF,16V,10%,X6S,CH5103KEB01':;

SECTION_NUMBER 1
 '@T6G_MB_LIB.T6G(SCH_1):PAGE475_I132@PURE_QUANTA.Q_CAP(CHIPS)':
 C_PATH='@t6g_mb_lib.t6g(sch_1):page475_i132@pure_quanta.q_cap(chips)',
 P_PATH='@t6g_mb_lib.t6g(sch_1):page362_i132@pure_quanta.q_cap(chips)',
 PATH='I132',
 DRAWING='@T6G_MB_LIB.T6G(SCH_1):PAGE475',
 SEC_TYPE='C0402',
 TOLERANCE='10%',
 MATERIAL='X6S',
 PHYS_PAGE='362',
 XY='(-5275,7675)',
 ROT='0',
 VER='1',
 PACK_TYPE='C0402',
 LOCATION='PC6604',
 SEC='1',
 CDS_LIB='pure_quanta',
 CDS_PART_NAME='Q_CAP_C0402-1UF,16V,10%,X6S,CH5103KEB01',
 VOLTAGE='16V',
 PART_NUMBER='CH5103KEB01',
 VALUE='1UF',
 PRIM_FILE='./archive_libs/logical/q_cap/chips/chips.prt';

PART_NAME
 PC6605 'Q_CAP_C0402-1UF,16V,10%,X6S,CH5103KEB01':;

SECTION_NUMBER 1
 '@T6G_MB_LIB.T6G(SCH_1):PAGE475_I146@PURE_QUANTA.Q_CAP(CHIPS)':
 C_PATH='@t6g_mb_lib.t6g(sch_1):page475_i146@pure_quanta.q_cap(chips)',
 P_PATH='@t6g_mb_lib.t6g(sch_1):page362_i146@pure_quanta.q_cap(chips)',
 PATH='I146',
 DRAWING='@T6G_MB_LIB.T6G(SCH_1):PAGE475',
 SEC_TYPE='C0402',
 TOLERANCE='10%',
 MATERIAL='X6S',
 PHYS_PAGE='362',
 XY='(-5275,7200)',
 ROT='0',
 VER='1',
 PACK_TYPE='C0402',
 LOCATION='PC6605',
 SEC='1',
 CDS_LIB='pure_quanta',
 CDS_PART_NAME='Q_CAP_C0402-1UF,16V,10%,X6S,CH5103KEB01',
 VOLTAGE='16V',
 PART_NUMBER='CH5103KEB01',
 VALUE='1UF',
 PRIM_FILE='./archive_libs/logical/q_cap/chips/chips.prt';

PART_NAME
 PC6606 'Q_CAP_C0402-10UF,6.3V,20%,X6S,CH6101MEB03':;

SECTION_NUMBER 1
 '@T6G_MB_LIB.T6G(SCH_1):PAGE475_I145@PURE_QUANTA.Q_CAP(CHIPS)':
 C_PATH='@t6g_mb_lib.t6g(sch_1):page475_i145@pure_quanta.q_cap(chips)',
 P_PATH='@t6g_mb_lib.t6g(sch_1):page362_i145@pure_quanta.q_cap(chips)',
 PATH='I145',
 DRAWING='@T6G_MB_LIB.T6G(SCH_1):PAGE475',
 SEC_TYPE='C0402',
 TOLERANCE='20%',
 MATERIAL='X6S',
 PHYS_PAGE='362',
 XY='(-5675,7200)',
 ROT='0',
 VER='1',
 PACK_TYPE='C0402',
 LOCATION='PC6606',
 SEC='1',
 CDS_LIB='pure_quanta',
 CDS_PART_NAME='Q_CAP_C0402-10UF,6.3V,20%,X6S,CH6101MEB03',
 VOLTAGE='6.3V',
 PART_NUMBER='CH6101MEB03',
 VALUE='10UF',
 PRIM_FILE='./archive_libs/logical/q_cap/chips/chips.prt';

PART_NAME
 PC6607 'Q_CAP_0402-470PF,50V,10%,X7R,TMP_QCH14706KB18':;

SECTION_NUMBER 1
 '@T6G_MB_LIB.T6G(SCH_1):PAGE475_I148@PURE_QUANTA.Q_CAP(CHIPS)':
 C_PATH='@t6g_mb_lib.t6g(sch_1):page475_i148@pure_quanta.q_cap(chips)',
 P_PATH='@t6g_mb_lib.t6g(sch_1):page362_i148@pure_quanta.q_cap(chips)',
 PATH='I148',
 DRAWING='@T6G_MB_LIB.T6G(SCH_1):PAGE475',
 SEC_TYPE='0402',
 TOLERANCE='10%',
 MATERIAL='X7R',
 PHYS_PAGE='362',
 XY='(-5300,2475)',
 ROT='0',
 VER='1',
 PACK_TYPE='0402',
 LOCATION='PC6607',
 SEC='1',
 CDS_LIB='pure_quanta',
 CDS_PART_NAME='Q_CAP_0402-470PF,50V,10%,X7R,TMP_QCH14706KB18',
 VOLTAGE='50V',
 PART_NUMBER='TMP_QCH14706KB18',
 VALUE='470PF',
 PRIM_FILE='./archive_libs/logical/q_cap/chips/chips.prt';

PART_NAME
 PC6609_09P1_1 'Q_CAP_C0402-2.2UF,10V,10%,X6S,CH5222KEB01':;

SECTION_NUMBER 1
 '@T6G_MB_LIB.T6G(SCH_1):PAGE478_I55@PURE_QUANTA.Q_CAP(CHIPS)':
 C_PATH='@t6g_mb_lib.t6g(sch_1):page478_i55@pure_quanta.q_cap(chips)',
 P_PATH='@t6g_mb_lib.t6g(sch_1):page365_i55@pure_quanta.q_cap(chips)',
 PATH='I55',
 DRAWING='@T6G_MB_LIB.T6G(SCH_1):PAGE478',
 BOM_COST='VR_DIMM ',
 TOLERANCE='10%',
 MATERIAL='X6S',
 PHYS_PAGE='365',
 XY='(-8175,5300)',
 ROT='0',
 VER='1',
 PACK_TYPE='C0402',
 LOCATION='PC6609_09P1_1',
 CDS_LIB='pure_quanta',
 CDS_PART_NAME='Q_CAP_C0402-2.2UF,10V,10%,X6S,CH5222KEB01',
 VOLTAGE='10V',
 PART_NUMBER='CH5222KEB01',
 VALUE='2.2UF',
 PRIM_FILE='./archive_libs/logical/q_cap/chips/chips.prt';

PART_NAME
 PC6610 'Q_CAP_C0402-2.2UF,10V,10%,X6S,CH5222KEB01':;

SECTION_NUMBER 1
 '@T6G_MB_LIB.T6G(SCH_1):PAGE478_I52@PURE_QUANTA.Q_CAP(CHIPS)':
 C_PATH='@t6g_mb_lib.t6g(sch_1):page478_i52@pure_quanta.q_cap(chips)',
 P_PATH='@t6g_mb_lib.t6g(sch_1):page365_i52@pure_quanta.q_cap(chips)',
 PATH='I52',
 DRAWING='@T6G_MB_LIB.T6G(SCH_1):PAGE478',
 BOM_COST='VR_DIMM ',
 TOLERANCE='10%',
 MATERIAL='X6S',
 PHYS_PAGE='365',
 XY='(-8875,4775)',
 ROT='0',
 VER='1',
 PACK_TYPE='C0402',
 LOCATION='PC6610',
 CDS_LIB='pure_quanta',
 CDS_PART_NAME='Q_CAP_C0402-2.2UF,10V,10%,X6S,CH5222KEB01',
 VOLTAGE='10V',
 PART_NUMBER='CH5222KEB01',
 VALUE='2.2UF',
 PRIM_FILE='./archive_libs/logical/q_cap/chips/chips.prt';

PART_NAME
 PC6611_1 'Q_CAP_C0402-100NF,50V,10%,X7R,CH4106K1B01':;

SECTION_NUMBER 1
 '@T6G_MB_LIB.T6G(SCH_1):PAGE478_I39@PURE_QUANTA.Q_CAP(CHIPS)':
 C_PATH='@t6g_mb_lib.t6g(sch_1):page478_i39@pure_quanta.q_cap(chips)',
 P_PATH='@t6g_mb_lib.t6g(sch_1):page365_i39@pure_quanta.q_cap(chips)',
 PATH='I39',
 DRAWING='@T6G_MB_LIB.T6G(SCH_1):PAGE478',
 BOM_COST='VR_CPU',
 TOLERANCE='10%',
 MATERIAL='X7R',
 PHYS_PAGE='365',
 XY='(-9625,3925)',
 ROT='0',
 VER='1',
 PACK_TYPE='C0402',
 LOCATION='PC6611_1',
 CDS_LIB='pure_quanta',
 CDS_PART_NAME='Q_CAP_C0402-100NF,50V,10%,X7R,CH4106K1B01',
 VOLTAGE='50V',
 PART_NUMBER='CH4106K1B01',
 VALUE='100NF',
 PRIM_FILE='./archive_libs/logical/q_cap/chips/chips.prt';

PART_NAME
 PC6612_1 'Q_CAP_C0402-1UF,25V,10%,X6S,CH5104KEB02':;

SECTION_NUMBER 1
 '@T6G_MB_LIB.T6G(SCH_1):PAGE478_I64@PURE_QUANTA.Q_CAP(CHIPS)':
 C_PATH='@t6g_mb_lib.t6g(sch_1):page478_i64@pure_quanta.q_cap(chips)',
 P_PATH='@t6g_mb_lib.t6g(sch_1):page365_i64@pure_quanta.q_cap(chips)',
 PATH='I64',
 DRAWING='@T6G_MB_LIB.T6G(SCH_1):PAGE478',
 BOM_COST='VR_DIMM ',
 TOLERANCE='10%',
 MATERIAL='X6S',
 PHYS_PAGE='365',
 XY='(-5475,5150)',
 ROT='0',
 VER='1',
 PACK_TYPE='C0402',
 LOCATION='PC6612_1',
 CDS_LIB='pure_quanta',
 CDS_PART_NAME='Q_CAP_C0402-1UF,25V,10%,X6S,CH5104KEB02',
 VOLTAGE='25V',
 PART_NUMBER='CH5104KEB02',
 VALUE='1UF',
 PRIM_FILE='./archive_libs/logical/q_cap/chips/chips.prt';

PART_NAME
 PC6613_1 'Q_CAP_0402-3300PF,50V,10%,X7R,TMP_QCH2336K1B12':;

SECTION_NUMBER 1
 '@T6G_MB_LIB.T6G(SCH_1):PAGE478_I61@PURE_QUANTA.Q_CAP(CHIPS)':
 C_PATH='@t6g_mb_lib.t6g(sch_1):page478_i61@pure_quanta.q_cap(chips)',
 P_PATH='@t6g_mb_lib.t6g(sch_1):page365_i61@pure_quanta.q_cap(chips)',
 PATH='I61',
 DRAWING='@T6G_MB_LIB.T6G(SCH_1):PAGE478',
 BOM_COST='VR_DIMM ',
 TOLERANCE='10%',
 MATERIAL='X7R',
 PHYS_PAGE='365',
 XY='(-5975,5150)',
 ROT='0',
 VER='1',
 PACK_TYPE='0402',
 LOCATION='PC6613_1',
 CDS_LIB='pure_quanta',
 CDS_PART_NAME='Q_CAP_0402-3300PF,50V,10%,X7R,TMP_QCH2336K1B12',
 VOLTAGE='50V',
 PART_NUMBER='TMP_QCH2336K1B12',
 VALUE='3300PF',
 PRIM_FILE='./archive_libs/logical/q_cap/chips/chips.prt';

PART_NAME
 PC6614_1 'Q_CAP_C0805-22UF,16V,20%,X6S,CH6223MEA01':
 REUSE_ID='41';

SECTION_NUMBER 1
 '@T6G_MB_LIB.T6G(SCH_1):PAGE478_I72@PURE_QUANTA.Q_CAP(CHIPS)':
 C_PATH='@t6g_mb_lib.t6g(sch_1):page478_i72@pure_quanta.q_cap(chips)',
 P_PATH='@t6g_mb_lib.t6g(sch_1):page365_i72@pure_quanta.q_cap(chips)',
 PATH='I72',
 DRAWING='@T6G_MB_LIB.T6G(SCH_1):PAGE478',
 BOM_COST='VR_DIMM ',
 TOLERANCE='20%',
 MATERIAL='X6S',
 PHYS_PAGE='365',
 XY='(-4975,5150)',
 ROT='0',
 VER='1',
 PACK_TYPE='C0805',
 LOCATION='PC6614_1',
 CDS_LIB='pure_quanta',
 CDS_PART_NAME='Q_CAP_C0805-22UF,16V,20%,X6S,CH6223MEA01',
 REUSE_ID='41',
 VOLTAGE='16V',
 PART_NUMBER='CH6223MEA01',
 VALUE='22UF',
 PRIM_FILE='./archive_libs/logical/q_cap/chips/chips.prt';

PART_NAME
 PC6615_1 'Q_CAP_C0805-22UF,16V,20%,X6S,CH6223MEA01':
 REUSE_ID='41';

SECTION_NUMBER 1
 '@T6G_MB_LIB.T6G(SCH_1):PAGE478_I74@PURE_QUANTA.Q_CAP(CHIPS)':
 C_PATH='@t6g_mb_lib.t6g(sch_1):page478_i74@pure_quanta.q_cap(chips)',
 P_PATH='@t6g_mb_lib.t6g(sch_1):page365_i74@pure_quanta.q_cap(chips)',
 PATH='I74',
 DRAWING='@T6G_MB_LIB.T6G(SCH_1):PAGE478',
 BOM_COST='VR_DIMM ',
 TOLERANCE='20%',
 MATERIAL='X6S',
 PHYS_PAGE='365',
 XY='(-4475,5150)',
 ROT='0',
 VER='1',
 PACK_TYPE='C0805',
 LOCATION='PC6615_1',
 CDS_LIB='pure_quanta',
 CDS_PART_NAME='Q_CAP_C0805-22UF,16V,20%,X6S,CH6223MEA01',
 REUSE_ID='41',
 VOLTAGE='16V',
 PART_NUMBER='CH6223MEA01',
 VALUE='22UF',
 PRIM_FILE='./archive_libs/logical/q_cap/chips/chips.prt';

PART_NAME
 PC6616_1 'Q_CAP_C0805-22UF,16V,20%,X6S,CH6223MEA01':
 REUSE_ID='41';

SECTION_NUMBER 1
 '@T6G_MB_LIB.T6G(SCH_1):PAGE478_I77@PURE_QUANTA.Q_CAP(CHIPS)':
 C_PATH='@t6g_mb_lib.t6g(sch_1):page478_i77@pure_quanta.q_cap(chips)',
 P_PATH='@t6g_mb_lib.t6g(sch_1):page365_i77@pure_quanta.q_cap(chips)',
 PATH='I77',
 DRAWING='@T6G_MB_LIB.T6G(SCH_1):PAGE478',
 BOM_COST='VR_DIMM ',
 TOLERANCE='20%',
 MATERIAL='X6S',
 PHYS_PAGE='365',
 XY='(-4000,5150)',
 ROT='0',
 VER='1',
 PACK_TYPE='C0805',
 LOCATION='PC6616_1',
 CDS_LIB='pure_quanta',
 CDS_PART_NAME='Q_CAP_C0805-22UF,16V,20%,X6S,CH6223MEA01',
 REUSE_ID='41',
 VOLTAGE='16V',
 PART_NUMBER='CH6223MEA01',
 VALUE='22UF',
 PRIM_FILE='./archive_libs/logical/q_cap/chips/chips.prt';

PART_NAME
 PC6617_1 'Q_CAP_C0805-22UF,16V,20%,X6S,CH6223MEA01':
 REUSE_ID='41';

SECTION_NUMBER 1
 '@T6G_MB_LIB.T6G(SCH_1):PAGE478_I79@PURE_QUANTA.Q_CAP(CHIPS)':
 C_PATH='@t6g_mb_lib.t6g(sch_1):page478_i79@pure_quanta.q_cap(chips)',
 P_PATH='@t6g_mb_lib.t6g(sch_1):page365_i79@pure_quanta.q_cap(chips)',
 PATH='I79',
 DRAWING='@T6G_MB_LIB.T6G(SCH_1):PAGE478',
 BOM_COST='VR_DIMM ',
 TOLERANCE='20%',
 MATERIAL='X6S',
 PHYS_PAGE='365',
 XY='(-3625,5150)',
 ROT='0',
 VER='1',
 PACK_TYPE='C0805',
 LOCATION='PC6617_1',
 CDS_LIB='pure_quanta',
 CDS_PART_NAME='Q_CAP_C0805-22UF,16V,20%,X6S,CH6223MEA01',
 REUSE_ID='41',
 VOLTAGE='16V',
 PART_NUMBER='CH6223MEA01',
 VALUE='22UF',
 PRIM_FILE='./archive_libs/logical/q_cap/chips/chips.prt';

PART_NAME
 PC6618 'Q_CAP_C0805-22UF,16V,20%,X6S,CH6223MEA01':;

SECTION_NUMBER 1
 '@T6G_MB_LIB.T6G(SCH_1):PAGE478_I80@PURE_QUANTA.Q_CAP(CHIPS)':
 C_PATH='@t6g_mb_lib.t6g(sch_1):page478_i80@pure_quanta.q_cap(chips)',
 P_PATH='@t6g_mb_lib.t6g(sch_1):page365_i80@pure_quanta.q_cap(chips)',
 PATH='I80',
 DRAWING='@T6G_MB_LIB.T6G(SCH_1):PAGE478',
 TOLERANCE='20%',
 MATERIAL='X6S',
 PHYS_PAGE='365',
 XY='(-3225,5100)',
 ROT='0',
 VER='1',
 PACK_TYPE='C0805',
 LOCATION='PC6618',
 CDS_LIB='pure_quanta',
 CDS_PART_NAME='Q_CAP_C0805-22UF,16V,20%,X6S,CH6223MEA01',
 VOLTAGE='16V',
 PART_NUMBER='CH6223MEA01',
 VALUE='22UF',
 PRIM_FILE='./archive_libs/logical/q_cap/chips/chips.prt';

PART_NAME
 PC6619 'Q_CAPP_SMLF-100UF,16V,20%,OSCON,CC71003MZ30':;

SECTION_NUMBER 1
 '@T6G_MB_LIB.T6G(SCH_1):PAGE478_I102@PURE_QUANTA.Q_CAPP(CHIPS)':
 C_PATH='@t6g_mb_lib.t6g(sch_1):page478_i102@pure_quanta.q_capp(chips)',
 P_PATH='@t6g_mb_lib.t6g(sch_1):page365_i102@pure_quanta.q_capp(chips)',
 PATH='I102',
 DRAWING='@T6G_MB_LIB.T6G(SCH_1):PAGE478',
 TOLERANCE='20%',
 MATERIAL='OSCON',
 PHYS_PAGE='365',
 XY='(-2375,5125)',
 ROT='0',
 VER='1',
 PACK_TYPE='SMLF',
 LOCATION='PC6619',
 CDS_LIB='pure_quanta',
 CDS_PART_NAME='Q_CAPP_SMLF-100UF,16V,20%,OSCON,CC71003MZ30',
 VOLTAGE='16V',
 PART_NUMBER='CC71003MZ30',
 VALUE='100UF',
 PRIM_FILE='./archive_libs/logical/q_capp/chips/chips.prt';

PART_NAME
 PC6620 'Q_CAP_0402-0.1UF,25V,10%,X7R,CH4104K1B00':;

SECTION_NUMBER 1
 '@T6G_MB_LIB.T6G(SCH_1):PAGE478_I114@PURE_QUANTA.Q_CAP(CHIPS)':
 C_PATH='@t6g_mb_lib.t6g(sch_1):page478_i114@pure_quanta.q_cap(chips)',
 P_PATH='@t6g_mb_lib.t6g(sch_1):page365_i114@pure_quanta.q_cap(chips)',
 PATH='I114',
 DRAWING='@T6G_MB_LIB.T6G(SCH_1):PAGE478',
 TOLERANCE='10%',
 MATERIAL='X7R',
 PHYS_PAGE='365',
 XY='(-950,5125)',
 ROT='0',
 VER='1',
 PACK_TYPE='0402',
 LOCATION='PC6620',
 CDS_LIB='pure_quanta',
 CDS_PART_NAME='Q_CAP_0402-0.1UF,25V,10%,X7R,CH4104K1B00',
 VOLTAGE='25V',
 PART_NUMBER='CH4104K1B00',
 VALUE='0.1UF',
 PRIM_FILE='./archive_libs/logical/q_cap/chips/chips.prt';

PART_NAME
 PC6621 'Q_CAP_C0402-100NF,50V,10%,X7R,CH4106K1B01':
 REUSE_ID='55';

SECTION_NUMBER 1
 '@T6G_MB_LIB.T6G(SCH_1):PAGE478_I76@PURE_QUANTA.Q_CAP(CHIPS)':
 C_PATH='@t6g_mb_lib.t6g(sch_1):page478_i76@pure_quanta.q_cap(chips)',
 P_PATH='@t6g_mb_lib.t6g(sch_1):page365_i76@pure_quanta.q_cap(chips)',
 PATH='I76',
 DRAWING='@T6G_MB_LIB.T6G(SCH_1):PAGE478',
 BOM_COST='VR_DIMM ',
 TOLERANCE='10%',
 MATERIAL='X7R',
 PHYS_PAGE='365',
 XY='(-4100,4700)',
 ROT='0',
 VER='2',
 PACK_TYPE='C0402',
 LOCATION='PC6621',
 CDS_LIB='pure_quanta',
 CDS_PART_NAME='Q_CAP_C0402-100NF,50V,10%,X7R,CH4106K1B01',
 REUSE_ID='55',
 VOLTAGE='50V',
 PART_NUMBER='CH4106K1B01',
 VALUE='100NF',
 PRIM_FILE='./archive_libs/logical/q_cap/chips/chips.prt';

PART_NAME
 PC6622 'Q_CAP_C0402-560PF,50V,10%,EMPTY,CH1566K1B09':;

SECTION_NUMBER 1
 '@T6G_MB_LIB.T6G(SCH_1):PAGE478_I108@PURE_QUANTA.Q_CAP(CHIPS)':
 C_PATH='@t6g_mb_lib.t6g(sch_1):page478_i108@pure_quanta.q_cap(chips)',
 P_PATH='@t6g_mb_lib.t6g(sch_1):page365_i108@pure_quanta.q_cap(chips)',
 PATH='I108',
 DRAWING='@T6G_MB_LIB.T6G(SCH_1):PAGE478',
 TOLERANCE='10%',
 MATERIAL='EMPTY',
 PHYS_PAGE='365',
 XY='(-5425,4150)',
 ROT='0',
 VER='1',
 PACK_TYPE='C0402',
 LOCATION='PC6622',
 CDS_LIB='pure_quanta',
 CDS_PART_NAME='Q_CAP_C0402-560PF,50V,10%,EMPTY,CH1566K1B09',
 VOLTAGE='50V',
 PART_NUMBER='CH1566K1B09',
 VALUE='560PF',
 PRIM_FILE='./archive_libs/logical/q_cap/chips/chips.prt';

PART_NAME
 PC6623 'Q_CAP_C0402-100NF,50V,10%,X7R,CH4106K1B01':;

SECTION_NUMBER 1
 '@T6G_MB_LIB.T6G(SCH_1):PAGE478_I66@PURE_QUANTA.Q_CAP(CHIPS)':
 C_PATH='@t6g_mb_lib.t6g(sch_1):page478_i66@pure_quanta.q_cap(chips)',
 P_PATH='@t6g_mb_lib.t6g(sch_1):page365_i66@pure_quanta.q_cap(chips)',
 PATH='I66',
 DRAWING='@T6G_MB_LIB.T6G(SCH_1):PAGE478',
 BOM_COST='VR_DIMM ',
 TOLERANCE='10%',
 MATERIAL='X7R',
 PHYS_PAGE='365',
 XY='(-4125,4200)',
 ROT='0',
 VER='1',
 PACK_TYPE='C0402',
 LOCATION='PC6623',
 CDS_LIB='pure_quanta',
 CDS_PART_NAME='Q_CAP_C0402-100NF,50V,10%,X7R,CH4106K1B01',
 VOLTAGE='50V',
 PART_NUMBER='CH4106K1B01',
 VALUE='100NF',
 PRIM_FILE='./archive_libs/logical/q_cap/chips/chips.prt';

PART_NAME
 PC6624_1 'Q_CAP_C0805-22UF,4V,20%,X6S,CH622KMEA03':;

SECTION_NUMBER 1
 '@T6G_MB_LIB.T6G(SCH_1):PAGE478_I67@PURE_QUANTA.Q_CAP(CHIPS)':
 C_PATH='@t6g_mb_lib.t6g(sch_1):page478_i67@pure_quanta.q_cap(chips)',
 P_PATH='@t6g_mb_lib.t6g(sch_1):page365_i67@pure_quanta.q_cap(chips)',
 PATH='I67',
 DRAWING='@T6G_MB_LIB.T6G(SCH_1):PAGE478',
 TOLERANCE='20%',
 MATERIAL='X6S',
 PHYS_PAGE='365',
 XY='(-3800,4200)',
 ROT='0',
 VER='1',
 PACK_TYPE='C0805',
 LOCATION='PC6624_1',
 CDS_LIB='pure_quanta',
 CDS_PART_NAME='Q_CAP_C0805-22UF,4V,20%,X6S,CH622KMEA03',
 VOLTAGE='4V',
 PART_NUMBER='CH622KMEA03',
 VALUE='22UF',
 PRIM_FILE='./archive_libs/logical/q_cap/chips/chips.prt';

PART_NAME
 PC6625_1 'Q_CAP_C0805-22UF,4V,20%,X6S,CH622KMEA03':;

SECTION_NUMBER 1
 '@T6G_MB_LIB.T6G(SCH_1):PAGE478_I68@PURE_QUANTA.Q_CAP(CHIPS)':
 C_PATH='@t6g_mb_lib.t6g(sch_1):page478_i68@pure_quanta.q_cap(chips)',
 P_PATH='@t6g_mb_lib.t6g(sch_1):page365_i68@pure_quanta.q_cap(chips)',
 PATH='I68',
 DRAWING='@T6G_MB_LIB.T6G(SCH_1):PAGE478',
 TOLERANCE='20%',
 MATERIAL='X6S',
 PHYS_PAGE='365',
 XY='(-3575,4200)',
 ROT='0',
 VER='1',
 PACK_TYPE='C0805',
 LOCATION='PC6625_1',
 CDS_LIB='pure_quanta',
 CDS_PART_NAME='Q_CAP_C0805-22UF,4V,20%,X6S,CH622KMEA03',
 VOLTAGE='4V',
 PART_NUMBER='CH622KMEA03',
 VALUE='22UF',
 PRIM_FILE='./archive_libs/logical/q_cap/chips/chips.prt';

PART_NAME
 PC6626 'Q_CAPP_SMLF-470UF,2.5V,20%,SPCAP,CH747LM8818':;

SECTION_NUMBER 1
 '@T6G_MB_LIB.T6G(SCH_1):PAGE478_I69@PURE_QUANTA.Q_CAPP(CHIPS)':
 C_PATH='@t6g_mb_lib.t6g(sch_1):page478_i69@pure_quanta.q_capp(chips)',
 P_PATH='@t6g_mb_lib.t6g(sch_1):page365_i69@pure_quanta.q_capp(chips)',
 PATH='I69',
 DRAWING='@T6G_MB_LIB.T6G(SCH_1):PAGE478',
 TOLERANCE='20%',
 MATERIAL='SPCAP',
 PHYS_PAGE='365',
 XY='(-3350,4200)',
 ROT='0',
 VER='1',
 PACK_TYPE='SMLF',
 LOCATION='PC6626',
 CDS_LIB='pure_quanta',
 CDS_PART_NAME='Q_CAPP_SMLF-470UF,2.5V,20%,SPCAP,CH747LM8818',
 VOLTAGE='2.5V',
 PART_NUMBER='CH747LM8818',
 VALUE='470UF',
 PRIM_FILE='./archive_libs/logical/q_capp/chips/chips.prt';

PART_NAME
 PC6627 'Q_CAPP_SMLF-470UF,2.5V,20%,SPCAP,CH747LM8818':;

SECTION_NUMBER 1
 '@T6G_MB_LIB.T6G(SCH_1):PAGE478_I70@PURE_QUANTA.Q_CAPP(CHIPS)':
 C_PATH='@t6g_mb_lib.t6g(sch_1):page478_i70@pure_quanta.q_capp(chips)',
 P_PATH='@t6g_mb_lib.t6g(sch_1):page365_i70@pure_quanta.q_capp(chips)',
 PATH='I70',
 DRAWING='@T6G_MB_LIB.T6G(SCH_1):PAGE478',
 TOLERANCE='20%',
 MATERIAL='SPCAP',
 PHYS_PAGE='365',
 XY='(-3125,4200)',
 ROT='0',
 VER='1',
 PACK_TYPE='SMLF',
 LOCATION='PC6627',
 CDS_LIB='pure_quanta',
 CDS_PART_NAME='Q_CAPP_SMLF-470UF,2.5V,20%,SPCAP,CH747LM8818',
 VOLTAGE='2.5V',
 PART_NUMBER='CH747LM8818',
 VALUE='470UF',
 PRIM_FILE='./archive_libs/logical/q_capp/chips/chips.prt';

PART_NAME
 PC6628 'Q_CAPP_SMLF-470UF,2.5V,20%,SPCAP,CH747LM8818':;

SECTION_NUMBER 1
 '@T6G_MB_LIB.T6G(SCH_1):PAGE478_I93@PURE_QUANTA.Q_CAPP(CHIPS)':
 C_PATH='@t6g_mb_lib.t6g(sch_1):page478_i93@pure_quanta.q_capp(chips)',
 P_PATH='@t6g_mb_lib.t6g(sch_1):page365_i93@pure_quanta.q_capp(chips)',
 PATH='I93',
 DRAWING='@T6G_MB_LIB.T6G(SCH_1):PAGE478',
 TOLERANCE='20%',
 MATERIAL='SPCAP',
 PHYS_PAGE='365',
 XY='(-2925,4200)',
 ROT='0',
 VER='1',
 PACK_TYPE='SMLF',
 LOCATION='PC6628',
 CDS_LIB='pure_quanta',
 CDS_PART_NAME='Q_CAPP_SMLF-470UF,2.5V,20%,SPCAP,CH747LM8818',
 VOLTAGE='2.5V',
 PART_NUMBER='CH747LM8818',
 VALUE='470UF',
 PRIM_FILE='./archive_libs/logical/q_capp/chips/chips.prt';

PART_NAME
 PC6629 'Q_CAPP_SMLF-390UF,2.5V,20%,ALUM,CC7390JMZ13':;

SECTION_NUMBER 1
 '@T6G_MB_LIB.T6G(SCH_1):PAGE478_I94@PURE_QUANTA.Q_CAPP(CHIPS)':
 C_PATH='@t6g_mb_lib.t6g(sch_1):page478_i94@pure_quanta.q_capp(chips)',
 P_PATH='@t6g_mb_lib.t6g(sch_1):page365_i94@pure_quanta.q_capp(chips)',
 PATH='I94',
 DRAWING='@T6G_MB_LIB.T6G(SCH_1):PAGE478',
 TOLERANCE='20%',
 MATERIAL='ALUM',
 PHYS_PAGE='365',
 XY='(-2600,4200)',
 ROT='0',
 VER='1',
 PACK_TYPE='SMLF',
 LOCATION='PC6629',
 CDS_LIB='pure_quanta',
 CDS_PART_NAME='Q_CAPP_SMLF-390UF,2.5V,20%,ALUM,CC7390JMZ13',
 VOLTAGE='2.5V',
 PART_NUMBER='CC7390JMZ13',
 VALUE='390UF',
 PRIM_FILE='./archive_libs/logical/q_capp/chips/chips.prt';

PART_NAME
 PC6630 'Q_CAPP_SMLF-390UF,2.5V,20%,ALUM,CC7390JMZ13':;

SECTION_NUMBER 1
 '@T6G_MB_LIB.T6G(SCH_1):PAGE478_I95@PURE_QUANTA.Q_CAPP(CHIPS)':
 C_PATH='@t6g_mb_lib.t6g(sch_1):page478_i95@pure_quanta.q_capp(chips)',
 P_PATH='@t6g_mb_lib.t6g(sch_1):page365_i95@pure_quanta.q_capp(chips)',
 PATH='I95',
 DRAWING='@T6G_MB_LIB.T6G(SCH_1):PAGE478',
 TOLERANCE='20%',
 MATERIAL='ALUM',
 PHYS_PAGE='365',
 XY='(-2325,4200)',
 ROT='0',
 VER='1',
 PACK_TYPE='SMLF',
 LOCATION='PC6630',
 CDS_LIB='pure_quanta',
 CDS_PART_NAME='Q_CAPP_SMLF-390UF,2.5V,20%,ALUM,CC7390JMZ13',
 VOLTAGE='2.5V',
 PART_NUMBER='CC7390JMZ13',
 VALUE='390UF',
 PRIM_FILE='./archive_libs/logical/q_capp/chips/chips.prt';

PART_NAME
 PC6631 'Q_CAPP_SMLF-390UF,2.5V,20%,ALUM,CC7390JMZ13':;

SECTION_NUMBER 1
 '@T6G_MB_LIB.T6G(SCH_1):PAGE478_I83@PURE_QUANTA.Q_CAPP(CHIPS)':
 C_PATH='@t6g_mb_lib.t6g(sch_1):page478_i83@pure_quanta.q_capp(chips)',
 P_PATH='@t6g_mb_lib.t6g(sch_1):page365_i83@pure_quanta.q_capp(chips)',
 PATH='I83',
 DRAWING='@T6G_MB_LIB.T6G(SCH_1):PAGE478',
 TOLERANCE='20%',
 MATERIAL='ALUM',
 PHYS_PAGE='365',
 XY='(-2475,1300)',
 ROT='0',
 VER='1',
 PACK_TYPE='SMLF',
 LOCATION='PC6631',
 CDS_LIB='pure_quanta',
 CDS_PART_NAME='Q_CAPP_SMLF-390UF,2.5V,20%,ALUM,CC7390JMZ13',
 VOLTAGE='2.5V',
 PART_NUMBER='CC7390JMZ13',
 VALUE='390UF',
 PRIM_FILE='./archive_libs/logical/q_capp/chips/chips.prt';

PART_NAME
 PC6632 'Q_CAPP_SMLF-390UF,2.5V,20%,ALUM,CC7390JMZ13':;

SECTION_NUMBER 1
 '@T6G_MB_LIB.T6G(SCH_1):PAGE478_I84@PURE_QUANTA.Q_CAPP(CHIPS)':
 C_PATH='@t6g_mb_lib.t6g(sch_1):page478_i84@pure_quanta.q_capp(chips)',
 P_PATH='@t6g_mb_lib.t6g(sch_1):page365_i84@pure_quanta.q_capp(chips)',
 PATH='I84',
 DRAWING='@T6G_MB_LIB.T6G(SCH_1):PAGE478',
 TOLERANCE='20%',
 MATERIAL='ALUM',
 PHYS_PAGE='365',
 XY='(-2225,1300)',
 ROT='0',
 VER='1',
 PACK_TYPE='SMLF',
 LOCATION='PC6632',
 CDS_LIB='pure_quanta',
 CDS_PART_NAME='Q_CAPP_SMLF-390UF,2.5V,20%,ALUM,CC7390JMZ13',
 VOLTAGE='2.5V',
 PART_NUMBER='CC7390JMZ13',
 VALUE='390UF',
 PRIM_FILE='./archive_libs/logical/q_capp/chips/chips.prt';

PART_NAME
 PC6633_2 'Q_CAP_C0402-1UF,25V,10%,X6S,CH5104KEB02':;

SECTION_NUMBER 1
 '@T6G_MB_LIB.T6G(SCH_1):PAGE478_I21@PURE_QUANTA.Q_CAP(CHIPS)':
 C_PATH='@t6g_mb_lib.t6g(sch_1):page478_i21@pure_quanta.q_cap(chips)',
 P_PATH='@t6g_mb_lib.t6g(sch_1):page365_i21@pure_quanta.q_cap(chips)',
 PATH='I21',
 DRAWING='@T6G_MB_LIB.T6G(SCH_1):PAGE478',
 BOM_COST='VR_DIMM ',
 TOLERANCE='10%',
 MATERIAL='X6S',
 PHYS_PAGE='365',
 XY='(-5350,2250)',
 ROT='0',
 VER='1',
 PACK_TYPE='C0402',
 LOCATION='PC6633_2',
 CDS_LIB='pure_quanta',
 CDS_PART_NAME='Q_CAP_C0402-1UF,25V,10%,X6S,CH5104KEB02',
 VOLTAGE='25V',
 PART_NUMBER='CH5104KEB02',
 VALUE='1UF',
 PRIM_FILE='./archive_libs/logical/q_cap/chips/chips.prt';

PART_NAME
 PC6634_2 'Q_CAP_0402-3300PF,50V,10%,X7R,TMP_QCH2336K1B12':;

SECTION_NUMBER 1
 '@T6G_MB_LIB.T6G(SCH_1):PAGE478_I18@PURE_QUANTA.Q_CAP(CHIPS)':
 C_PATH='@t6g_mb_lib.t6g(sch_1):page478_i18@pure_quanta.q_cap(chips)',
 P_PATH='@t6g_mb_lib.t6g(sch_1):page365_i18@pure_quanta.q_cap(chips)',
 PATH='I18',
 DRAWING='@T6G_MB_LIB.T6G(SCH_1):PAGE478',
 BOM_COST='VR_DIMM ',
 TOLERANCE='10%',
 MATERIAL='X7R',
 PHYS_PAGE='365',
 XY='(-5850,2250)',
 ROT='0',
 VER='1',
 PACK_TYPE='0402',
 LOCATION='PC6634_2',
 CDS_LIB='pure_quanta',
 CDS_PART_NAME='Q_CAP_0402-3300PF,50V,10%,X7R,TMP_QCH2336K1B12',
 VOLTAGE='50V',
 PART_NUMBER='TMP_QCH2336K1B12',
 VALUE='3300PF',
 PRIM_FILE='./archive_libs/logical/q_cap/chips/chips.prt';

PART_NAME
 PC6635_2 'Q_CAP_C0805-22UF,16V,20%,X6S,CH6223MEA01':
 REUSE_ID='41';

SECTION_NUMBER 1
 '@T6G_MB_LIB.T6G(SCH_1):PAGE478_I25@PURE_QUANTA.Q_CAP(CHIPS)':
 C_PATH='@t6g_mb_lib.t6g(sch_1):page478_i25@pure_quanta.q_cap(chips)',
 P_PATH='@t6g_mb_lib.t6g(sch_1):page365_i25@pure_quanta.q_cap(chips)',
 PATH='I25',
 DRAWING='@T6G_MB_LIB.T6G(SCH_1):PAGE478',
 BOM_COST='VR_DIMM ',
 TOLERANCE='20%',
 MATERIAL='X6S',
 PHYS_PAGE='365',
 XY='(-4850,2250)',
 ROT='0',
 VER='1',
 PACK_TYPE='C0805',
 LOCATION='PC6635_2',
 CDS_LIB='pure_quanta',
 CDS_PART_NAME='Q_CAP_C0805-22UF,16V,20%,X6S,CH6223MEA01',
 REUSE_ID='41',
 VOLTAGE='16V',
 PART_NUMBER='CH6223MEA01',
 VALUE='22UF',
 PRIM_FILE='./archive_libs/logical/q_cap/chips/chips.prt';

PART_NAME
 PC6636_2 'Q_CAP_C0805-22UF,16V,20%,X6S,CH6223MEA01':
 REUSE_ID='41';

SECTION_NUMBER 1
 '@T6G_MB_LIB.T6G(SCH_1):PAGE478_I28@PURE_QUANTA.Q_CAP(CHIPS)':
 C_PATH='@t6g_mb_lib.t6g(sch_1):page478_i28@pure_quanta.q_cap(chips)',
 P_PATH='@t6g_mb_lib.t6g(sch_1):page365_i28@pure_quanta.q_cap(chips)',
 PATH='I28',
 DRAWING='@T6G_MB_LIB.T6G(SCH_1):PAGE478',
 BOM_COST='VR_DIMM ',
 TOLERANCE='20%',
 MATERIAL='X6S',
 PHYS_PAGE='365',
 XY='(-4350,2250)',
 ROT='0',
 VER='1',
 PACK_TYPE='C0805',
 LOCATION='PC6636_2',
 CDS_LIB='pure_quanta',
 CDS_PART_NAME='Q_CAP_C0805-22UF,16V,20%,X6S,CH6223MEA01',
 REUSE_ID='41',
 VOLTAGE='16V',
 PART_NUMBER='CH6223MEA01',
 VALUE='22UF',
 PRIM_FILE='./archive_libs/logical/q_cap/chips/chips.prt';

PART_NAME
 PC6637_2 'Q_CAP_C0805-22UF,16V,20%,X6S,CH6223MEA01':
 REUSE_ID='41';

SECTION_NUMBER 1
 '@T6G_MB_LIB.T6G(SCH_1):PAGE478_I35@PURE_QUANTA.Q_CAP(CHIPS)':
 C_PATH='@t6g_mb_lib.t6g(sch_1):page478_i35@pure_quanta.q_cap(chips)',
 P_PATH='@t6g_mb_lib.t6g(sch_1):page365_i35@pure_quanta.q_cap(chips)',
 PATH='I35',
 DRAWING='@T6G_MB_LIB.T6G(SCH_1):PAGE478',
 BOM_COST='VR_DIMM ',
 TOLERANCE='20%',
 MATERIAL='X6S',
 PHYS_PAGE='365',
 XY='(-3875,2250)',
 ROT='0',
 VER='1',
 PACK_TYPE='C0805',
 LOCATION='PC6637_2',
 CDS_LIB='pure_quanta',
 CDS_PART_NAME='Q_CAP_C0805-22UF,16V,20%,X6S,CH6223MEA01',
 REUSE_ID='41',
 VOLTAGE='16V',
 PART_NUMBER='CH6223MEA01',
 VALUE='22UF',
 PRIM_FILE='./archive_libs/logical/q_cap/chips/chips.prt';

PART_NAME
 PC6638_2 'Q_CAP_C0805-22UF,16V,20%,X6S,CH6223MEA01':
 REUSE_ID='41';

SECTION_NUMBER 1
 '@T6G_MB_LIB.T6G(SCH_1):PAGE478_I36@PURE_QUANTA.Q_CAP(CHIPS)':
 C_PATH='@t6g_mb_lib.t6g(sch_1):page478_i36@pure_quanta.q_cap(chips)',
 P_PATH='@t6g_mb_lib.t6g(sch_1):page365_i36@pure_quanta.q_cap(chips)',
 PATH='I36',
 DRAWING='@T6G_MB_LIB.T6G(SCH_1):PAGE478',
 BOM_COST='VR_DIMM ',
 TOLERANCE='20%',
 MATERIAL='X6S',
 PHYS_PAGE='365',
 XY='(-3500,2250)',
 ROT='0',
 VER='1',
 PACK_TYPE='C0805',
 LOCATION='PC6638_2',
 CDS_LIB='pure_quanta',
 CDS_PART_NAME='Q_CAP_C0805-22UF,16V,20%,X6S,CH6223MEA01',
 REUSE_ID='41',
 VOLTAGE='16V',
 PART_NUMBER='CH6223MEA01',
 VALUE='22UF',
 PRIM_FILE='./archive_libs/logical/q_cap/chips/chips.prt';

PART_NAME
 PC6639 'Q_CAP_C0805-22UF,16V,20%,X6S,CH6223MEA01':;

SECTION_NUMBER 1
 '@T6G_MB_LIB.T6G(SCH_1):PAGE478_I38@PURE_QUANTA.Q_CAP(CHIPS)':
 C_PATH='@t6g_mb_lib.t6g(sch_1):page478_i38@pure_quanta.q_cap(chips)',
 P_PATH='@t6g_mb_lib.t6g(sch_1):page365_i38@pure_quanta.q_cap(chips)',
 PATH='I38',
 DRAWING='@T6G_MB_LIB.T6G(SCH_1):PAGE478',
 TOLERANCE='20%',
 MATERIAL='X6S',
 PHYS_PAGE='365',
 XY='(-3100,2200)',
 ROT='0',
 VER='1',
 PACK_TYPE='C0805',
 LOCATION='PC6639',
 CDS_LIB='pure_quanta',
 CDS_PART_NAME='Q_CAP_C0805-22UF,16V,20%,X6S,CH6223MEA01',
 VOLTAGE='16V',
 PART_NUMBER='CH6223MEA01',
 VALUE='22UF',
 PRIM_FILE='./archive_libs/logical/q_cap/chips/chips.prt';

PART_NAME
 PC6640 'Q_CAP_C0402-100NF,50V,10%,X7R,CH4106K1B01':
 REUSE_ID='55';

SECTION_NUMBER 1
 '@T6G_MB_LIB.T6G(SCH_1):PAGE478_I26@PURE_QUANTA.Q_CAP(CHIPS)':
 C_PATH='@t6g_mb_lib.t6g(sch_1):page478_i26@pure_quanta.q_cap(chips)',
 P_PATH='@t6g_mb_lib.t6g(sch_1):page365_i26@pure_quanta.q_cap(chips)',
 PATH='I26',
 DRAWING='@T6G_MB_LIB.T6G(SCH_1):PAGE478',
 BOM_COST='VR_DIMM ',
 TOLERANCE='10%',
 MATERIAL='X7R',
 PHYS_PAGE='365',
 XY='(-3975,1800)',
 ROT='0',
 VER='2',
 PACK_TYPE='C0402',
 LOCATION='PC6640',
 CDS_LIB='pure_quanta',
 CDS_PART_NAME='Q_CAP_C0402-100NF,50V,10%,X7R,CH4106K1B01',
 REUSE_ID='55',
 VOLTAGE='50V',
 PART_NUMBER='CH4106K1B01',
 VALUE='100NF',
 PRIM_FILE='./archive_libs/logical/q_cap/chips/chips.prt';

PART_NAME
 PC6641 'Q_CAP_C0402-560PF,50V,10%,EMPTY,CH1566K1B09':;

SECTION_NUMBER 1
 '@T6G_MB_LIB.T6G(SCH_1):PAGE478_I109@PURE_QUANTA.Q_CAP(CHIPS)':
 C_PATH='@t6g_mb_lib.t6g(sch_1):page478_i109@pure_quanta.q_cap(chips)',
 P_PATH='@t6g_mb_lib.t6g(sch_1):page365_i109@pure_quanta.q_cap(chips)',
 PATH='I109',
 DRAWING='@T6G_MB_LIB.T6G(SCH_1):PAGE478',
 TOLERANCE='10%',
 MATERIAL='EMPTY',
 PHYS_PAGE='365',
 XY='(-5400,1250)',
 ROT='0',
 VER='1',
 PACK_TYPE='C0402',
 LOCATION='PC6641',
 CDS_LIB='pure_quanta',
 CDS_PART_NAME='Q_CAP_C0402-560PF,50V,10%,EMPTY,CH1566K1B09',
 VOLTAGE='50V',
 PART_NUMBER='CH1566K1B09',
 VALUE='560PF',
 PRIM_FILE='./archive_libs/logical/q_cap/chips/chips.prt';

PART_NAME
 PC6642_2 'Q_CAP_C0805-22UF,4V,20%,X6S,CH622KMEA03':;

SECTION_NUMBER 1
 '@T6G_MB_LIB.T6G(SCH_1):PAGE478_I29@PURE_QUANTA.Q_CAP(CHIPS)':
 C_PATH='@t6g_mb_lib.t6g(sch_1):page478_i29@pure_quanta.q_cap(chips)',
 P_PATH='@t6g_mb_lib.t6g(sch_1):page365_i29@pure_quanta.q_cap(chips)',
 PATH='I29',
 DRAWING='@T6G_MB_LIB.T6G(SCH_1):PAGE478',
 TOLERANCE='20%',
 MATERIAL='X6S',
 PHYS_PAGE='365',
 XY='(-3675,1300)',
 ROT='0',
 VER='1',
 PACK_TYPE='C0805',
 LOCATION='PC6642_2',
 CDS_LIB='pure_quanta',
 CDS_PART_NAME='Q_CAP_C0805-22UF,4V,20%,X6S,CH622KMEA03',
 VOLTAGE='4V',
 PART_NUMBER='CH622KMEA03',
 VALUE='22UF',
 PRIM_FILE='./archive_libs/logical/q_cap/chips/chips.prt';

PART_NAME
 PC6643_2 'Q_CAP_C0805-22UF,4V,20%,X6S,CH622KMEA03':;

SECTION_NUMBER 1
 '@T6G_MB_LIB.T6G(SCH_1):PAGE478_I30@PURE_QUANTA.Q_CAP(CHIPS)':
 C_PATH='@t6g_mb_lib.t6g(sch_1):page478_i30@pure_quanta.q_cap(chips)',
 P_PATH='@t6g_mb_lib.t6g(sch_1):page365_i30@pure_quanta.q_cap(chips)',
 PATH='I30',
 DRAWING='@T6G_MB_LIB.T6G(SCH_1):PAGE478',
 TOLERANCE='20%',
 MATERIAL='X6S',
 PHYS_PAGE='365',
 XY='(-3450,1300)',
 ROT='0',
 VER='1',
 PACK_TYPE='C0805',
 LOCATION='PC6643_2',
 CDS_LIB='pure_quanta',
 CDS_PART_NAME='Q_CAP_C0805-22UF,4V,20%,X6S,CH622KMEA03',
 VOLTAGE='4V',
 PART_NUMBER='CH622KMEA03',
 VALUE='22UF',
 PRIM_FILE='./archive_libs/logical/q_cap/chips/chips.prt';

PART_NAME
 PC6644_09P1_2 'Q_CAP_C0402-2.2UF,10V,10%,X6S,CH5222KEB01':;

SECTION_NUMBER 1
 '@T6G_MB_LIB.T6G(SCH_1):PAGE478_I14@PURE_QUANTA.Q_CAP(CHIPS)':
 C_PATH='@t6g_mb_lib.t6g(sch_1):page478_i14@pure_quanta.q_cap(chips)',
 P_PATH='@t6g_mb_lib.t6g(sch_1):page365_i14@pure_quanta.q_cap(chips)',
 PATH='I14',
 DRAWING='@T6G_MB_LIB.T6G(SCH_1):PAGE478',
 BOM_COST='VR_DIMM ',
 TOLERANCE='10%',
 MATERIAL='X6S',
 PHYS_PAGE='365',
 XY='(-8050,2400)',
 ROT='0',
 VER='1',
 PACK_TYPE='C0402',
 LOCATION='PC6644_09P1_2',
 CDS_LIB='pure_quanta',
 CDS_PART_NAME='Q_CAP_C0402-2.2UF,10V,10%,X6S,CH5222KEB01',
 VOLTAGE='10V',
 PART_NUMBER='CH5222KEB01',
 VALUE='2.2UF',
 PRIM_FILE='./archive_libs/logical/q_cap/chips/chips.prt';

PART_NAME
 PC6645 'Q_CAP_C0402-2.2UF,10V,10%,X6S,CH5222KEB01':;

SECTION_NUMBER 1
 '@T6G_MB_LIB.T6G(SCH_1):PAGE478_I10@PURE_QUANTA.Q_CAP(CHIPS)':
 C_PATH='@t6g_mb_lib.t6g(sch_1):page478_i10@pure_quanta.q_cap(chips)',
 P_PATH='@t6g_mb_lib.t6g(sch_1):page365_i10@pure_quanta.q_cap(chips)',
 PATH='I10',
 DRAWING='@T6G_MB_LIB.T6G(SCH_1):PAGE478',
 BOM_COST='VR_DIMM ',
 TOLERANCE='10%',
 MATERIAL='X6S',
 PHYS_PAGE='365',
 XY='(-8750,1875)',
 ROT='0',
 VER='1',
 PACK_TYPE='C0402',
 LOCATION='PC6645',
 CDS_LIB='pure_quanta',
 CDS_PART_NAME='Q_CAP_C0402-2.2UF,10V,10%,X6S,CH5222KEB01',
 VOLTAGE='10V',
 PART_NUMBER='CH5222KEB01',
 VALUE='2.2UF',
 PRIM_FILE='./archive_libs/logical/q_cap/chips/chips.prt';

PART_NAME
 PC6646 'Q_CAP_C0402-100NF,50V,10%,X7R,CH4106K1B01':;

SECTION_NUMBER 1
 '@T6G_MB_LIB.T6G(SCH_1):PAGE478_I2@PURE_QUANTA.Q_CAP(CHIPS)':
 C_PATH='@t6g_mb_lib.t6g(sch_1):page478_i2@pure_quanta.q_cap(chips)',
 P_PATH='@t6g_mb_lib.t6g(sch_1):page365_i2@pure_quanta.q_cap(chips)',
 PATH='I2',
 DRAWING='@T6G_MB_LIB.T6G(SCH_1):PAGE478',
 BOM_COST='VR_CPU',
 TOLERANCE='10%',
 MATERIAL='X7R',
 PHYS_PAGE='365',
 XY='(-9500,1025)',
 ROT='0',
 VER='1',
 PACK_TYPE='C0402',
 LOCATION='PC6646',
 CDS_LIB='pure_quanta',
 CDS_PART_NAME='Q_CAP_C0402-100NF,50V,10%,X7R,CH4106K1B01',
 VOLTAGE='50V',
 PART_NUMBER='CH4106K1B01',
 VALUE='100NF',
 PRIM_FILE='./archive_libs/logical/q_cap/chips/chips.prt';

PART_NAME
 PC6800 'Q_CAPP_SMLF-270UF,16V,20%,OSCON,CC72703MZ11':;

SECTION_NUMBER 1
 '@T6G_MB_LIB.T6G(SCH_1):PAGE469_I6@PURE_QUANTA.Q_CAPP(CHIPS)':
 C_PATH='@t6g_mb_lib.t6g(sch_1):page469_i6@pure_quanta.q_capp(chips)',
 P_PATH='@t6g_mb_lib.t6g(sch_1):page360_i6@pure_quanta.q_capp(chips)',
 PATH='I6',
 DRAWING='@T6G_MB_LIB.T6G(SCH_1):PAGE469',
 TOLERANCE='20%',
 MATERIAL='OSCON',
 PHYS_PAGE='360',
 XY='(-8450,3975)',
 ROT='2',
 VER='1',
 PACK_TYPE='SMLF',
 LOCATION='PC6800',
 CDS_LIB='pure_quanta',
 CDS_PART_NAME='Q_CAPP_SMLF-270UF,16V,20%,OSCON,CC72703MZ11',
 VOLTAGE='16V',
 PART_NUMBER='CC72703MZ11',
 VALUE='270UF',
 PRIM_FILE='./archive_libs/logical/q_capp/chips/chips.prt';

PART_NAME
 PC6801 'Q_CAPP_SMLF-270UF,16V,20%,OSCON,CC72703MZ11':;

SECTION_NUMBER 1
 '@T6G_MB_LIB.T6G(SCH_1):PAGE470_I6@PURE_QUANTA.Q_CAPP(CHIPS)':
 C_PATH='@t6g_mb_lib.t6g(sch_1):page470_i6@pure_quanta.q_capp(chips)',
 P_PATH='@t6g_mb_lib.t6g(sch_1):page361_i6@pure_quanta.q_capp(chips)',
 PATH='I6',
 DRAWING='@T6G_MB_LIB.T6G(SCH_1):PAGE470',
 TOLERANCE='20%',
 MATERIAL='OSCON',
 PHYS_PAGE='361',
 XY='(-8525,4000)',
 ROT='2',
 VER='1',
 PACK_TYPE='SMLF',
 LOCATION='PC6801',
 CDS_LIB='pure_quanta',
 CDS_PART_NAME='Q_CAPP_SMLF-270UF,16V,20%,OSCON,CC72703MZ11',
 VOLTAGE='16V',
 PART_NUMBER='CC72703MZ11',
 VALUE='270UF',
 PRIM_FILE='./archive_libs/logical/q_capp/chips/chips.prt';

PART_NAME
 PC6802 'Q_CAP_C0805-22UF,16V,20%,X6S,CH6223MEA01':;

SECTION_NUMBER 1
 '@T6G_MB_LIB.T6G(SCH_1):PAGE469_I7@PURE_QUANTA.Q_CAP(CHIPS)':
 C_PATH='@t6g_mb_lib.t6g(sch_1):page469_i7@pure_quanta.q_cap(chips)',
 P_PATH='@t6g_mb_lib.t6g(sch_1):page360_i7@pure_quanta.q_cap(chips)',
 PATH='I7',
 DRAWING='@T6G_MB_LIB.T6G(SCH_1):PAGE469',
 TOLERANCE='20%',
 MATERIAL='X6S',
 PHYS_PAGE='360',
 XY='(-8300,3975)',
 ROT='0',
 VER='1',
 PACK_TYPE='C0805',
 LOCATION='PC6802',
 CDS_LIB='pure_quanta',
 CDS_PART_NAME='Q_CAP_C0805-22UF,16V,20%,X6S,CH6223MEA01',
 VOLTAGE='16V',
 PART_NUMBER='CH6223MEA01',
 VALUE='22UF',
 PRIM_FILE='./archive_libs/logical/q_cap/chips/chips.prt';

PART_NAME
 PC6803 'Q_CAP_C0805-22UF,16V,20%,X6S,CH6223MEA01':;

SECTION_NUMBER 1
 '@T6G_MB_LIB.T6G(SCH_1):PAGE470_I7@PURE_QUANTA.Q_CAP(CHIPS)':
 C_PATH='@t6g_mb_lib.t6g(sch_1):page470_i7@pure_quanta.q_cap(chips)',
 P_PATH='@t6g_mb_lib.t6g(sch_1):page361_i7@pure_quanta.q_cap(chips)',
 PATH='I7',
 DRAWING='@T6G_MB_LIB.T6G(SCH_1):PAGE470',
 TOLERANCE='20%',
 MATERIAL='X6S',
 PHYS_PAGE='361',
 XY='(-8400,4000)',
 ROT='0',
 VER='1',
 PACK_TYPE='C0805',
 LOCATION='PC6803',
 CDS_LIB='pure_quanta',
 CDS_PART_NAME='Q_CAP_C0805-22UF,16V,20%,X6S,CH6223MEA01',
 VOLTAGE='16V',
 PART_NUMBER='CH6223MEA01',
 VALUE='22UF',
 PRIM_FILE='./archive_libs/logical/q_cap/chips/chips.prt';

PART_NAME
 PC6804 'Q_CAPP_SMLF-390UF,2.5V,20%,ALUM,CC7390JMZ13':;

SECTION_NUMBER 1
 '@T6G_MB_LIB.T6G(SCH_1):PAGE470_I47@PURE_QUANTA.Q_CAPP(CHIPS)':
 C_PATH='@t6g_mb_lib.t6g(sch_1):page470_i47@pure_quanta.q_capp(chips)',
 P_PATH='@t6g_mb_lib.t6g(sch_1):page361_i47@pure_quanta.q_capp(chips)',
 PATH='I47',
 DRAWING='@T6G_MB_LIB.T6G(SCH_1):PAGE470',
 TOLERANCE='20%',
 MATERIAL='ALUM',
 PHYS_PAGE='361',
 XY='(-1050,3200)',
 ROT='0',
 VER='1',
 PACK_TYPE='SMLF',
 LOCATION='PC6804',
 CDS_LIB='pure_quanta',
 CDS_PART_NAME='Q_CAPP_SMLF-390UF,2.5V,20%,ALUM,CC7390JMZ13',
 VOLTAGE='2.5V',
 PART_NUMBER='CC7390JMZ13',
 VALUE='390UF',
 PRIM_FILE='./archive_libs/logical/q_capp/chips/chips.prt';

PART_NAME
 PC6805 'Q_CAPP_SMLF-390UF,2.5V,20%,ALUM,CC7390JMZ13':;

SECTION_NUMBER 1
 '@T6G_MB_LIB.T6G(SCH_1):PAGE469_I48@PURE_QUANTA.Q_CAPP(CHIPS)':
 C_PATH='@t6g_mb_lib.t6g(sch_1):page469_i48@pure_quanta.q_capp(chips)',
 P_PATH='@t6g_mb_lib.t6g(sch_1):page360_i48@pure_quanta.q_capp(chips)',
 PATH='I48',
 DRAWING='@T6G_MB_LIB.T6G(SCH_1):PAGE469',
 TOLERANCE='20%',
 MATERIAL='ALUM',
 PHYS_PAGE='360',
 XY='(-1000,3150)',
 ROT='0',
 VER='1',
 PACK_TYPE='SMLF',
 LOCATION='PC6805',
 CDS_LIB='pure_quanta',
 CDS_PART_NAME='Q_CAPP_SMLF-390UF,2.5V,20%,ALUM,CC7390JMZ13',
 VOLTAGE='2.5V',
 PART_NUMBER='CC7390JMZ13',
 VALUE='390UF',
 PRIM_FILE='./archive_libs/logical/q_capp/chips/chips.prt';

PART_NAME
 PC6806 'Q_CAP_C0402-100NF,50V,10%,X7R,CH4106K1B01':;

SECTION_NUMBER 1
 '@T6G_MB_LIB.T6G(SCH_1):PAGE476_I255@PURE_QUANTA.Q_CAP(CHIPS)':
 C_PATH='@t6g_mb_lib.t6g(sch_1):page476_i255@pure_quanta.q_cap(chips)',
 P_PATH='@t6g_mb_lib.t6g(sch_1):page363_i255@pure_quanta.q_cap(chips)',
 PATH='I255',
 DRAWING='@T6G_MB_LIB.T6G(SCH_1):PAGE476',
 BOM_COST='VR_DIMM ',
 TOLERANCE='10%',
 MATERIAL='X7R',
 PHYS_PAGE='363',
 XY='(-1025,-9500)',
 ROT='0',
 VER='1',
 PACK_TYPE='C0402',
 LOCATION='PC6806',
 CDS_LIB='pure_quanta',
 CDS_PART_NAME='Q_CAP_C0402-100NF,50V,10%,X7R,CH4106K1B01',
 VOLTAGE='50V',
 PART_NUMBER='CH4106K1B01',
 VALUE='100NF',
 PRIM_FILE='./archive_libs/logical/q_cap/chips/chips.prt';

PART_NAME
 PC6807 'Q_CAP_C0402-100NF,50V,10%,X7R,CH4106K1B01':;

SECTION_NUMBER 1
 '@T6G_MB_LIB.T6G(SCH_1):PAGE478_I23@PURE_QUANTA.Q_CAP(CHIPS)':
 C_PATH='@t6g_mb_lib.t6g(sch_1):page478_i23@pure_quanta.q_cap(chips)',
 P_PATH='@t6g_mb_lib.t6g(sch_1):page365_i23@pure_quanta.q_cap(chips)',
 PATH='I23',
 DRAWING='@T6G_MB_LIB.T6G(SCH_1):PAGE478',
 BOM_COST='VR_DIMM ',
 TOLERANCE='10%',
 MATERIAL='X7R',
 PHYS_PAGE='365',
 XY='(-4000,1300)',
 ROT='0',
 VER='1',
 PACK_TYPE='C0402',
 LOCATION='PC6807',
 CDS_LIB='pure_quanta',
 CDS_PART_NAME='Q_CAP_C0402-100NF,50V,10%,X7R,CH4106K1B01',
 VOLTAGE='50V',
 PART_NUMBER='CH4106K1B01',
 VALUE='100NF',
 PRIM_FILE='./archive_libs/logical/q_cap/chips/chips.prt';

PART_NAME
 PC6810 'Q_CAPP_SMLF-100UF,16V,20%,OSCON,CC71003MZ30':;

SECTION_NUMBER 1
 '@T6G_MB_LIB.T6G(SCH_1):PAGE476_I231@PURE_QUANTA.Q_CAPP(CHIPS)':
 C_PATH='@t6g_mb_lib.t6g(sch_1):page476_i231@pure_quanta.q_capp(chips)',
 P_PATH='@t6g_mb_lib.t6g(sch_1):page363_i231@pure_quanta.q_capp(chips)',
 PATH='I231',
 DRAWING='@T6G_MB_LIB.T6G(SCH_1):PAGE476',
 TOLERANCE='20%',
 MATERIAL='OSCON',
 PHYS_PAGE='363',
 XY='(725,-8575)',
 ROT='0',
 VER='1',
 PACK_TYPE='SMLF',
 LOCATION='PC6810',
 CDS_LIB='pure_quanta',
 CDS_PART_NAME='Q_CAPP_SMLF-100UF,16V,20%,OSCON,CC71003MZ30',
 VOLTAGE='16V',
 PART_NUMBER='CC71003MZ30',
 VALUE='100UF',
 PRIM_FILE='./archive_libs/logical/q_capp/chips/chips.prt';

PART_NAME
 PC6811 'Q_CAPP_SMLF-470UF,2.5V,20%,SPCAP,CH747LM8818':;

SECTION_NUMBER 1
 '@T6G_MB_LIB.T6G(SCH_1):PAGE476_I247@PURE_QUANTA.Q_CAPP(CHIPS)':
 C_PATH='@t6g_mb_lib.t6g(sch_1):page476_i247@pure_quanta.q_capp(chips)',
 P_PATH='@t6g_mb_lib.t6g(sch_1):page363_i247@pure_quanta.q_capp(chips)',
 PATH='I247',
 DRAWING='@T6G_MB_LIB.T6G(SCH_1):PAGE476',
 TOLERANCE='20%',
 MATERIAL='SPCAP',
 PHYS_PAGE='363',
 XY='(-25,-9500)',
 ROT='0',
 VER='1',
 PACK_TYPE='SMLF',
 LOCATION='PC6811',
 CDS_LIB='pure_quanta',
 CDS_PART_NAME='Q_CAPP_SMLF-470UF,2.5V,20%,SPCAP,CH747LM8818',
 VOLTAGE='2.5V',
 PART_NUMBER='CH747LM8818',
 VALUE='470UF',
 PRIM_FILE='./archive_libs/logical/q_capp/chips/chips.prt';

PART_NAME
 PC6812 'Q_CAPP_SMLF-470UF,2.5V,20%,SPCAP,CH747LM8818':;

SECTION_NUMBER 1
 '@T6G_MB_LIB.T6G(SCH_1):PAGE476_I248@PURE_QUANTA.Q_CAPP(CHIPS)':
 C_PATH='@t6g_mb_lib.t6g(sch_1):page476_i248@pure_quanta.q_capp(chips)',
 P_PATH='@t6g_mb_lib.t6g(sch_1):page363_i248@pure_quanta.q_capp(chips)',
 PATH='I248',
 DRAWING='@T6G_MB_LIB.T6G(SCH_1):PAGE476',
 TOLERANCE='20%',
 MATERIAL='SPCAP',
 PHYS_PAGE='363',
 XY='(-250,-9500)',
 ROT='0',
 VER='1',
 PACK_TYPE='SMLF',
 LOCATION='PC6812',
 CDS_LIB='pure_quanta',
 CDS_PART_NAME='Q_CAPP_SMLF-470UF,2.5V,20%,SPCAP,CH747LM8818',
 VOLTAGE='2.5V',
 PART_NUMBER='CH747LM8818',
 VALUE='470UF',
 PRIM_FILE='./archive_libs/logical/q_capp/chips/chips.prt';

PART_NAME
 PC6813 'Q_CAPP_SMLF-470UF,2.5V,20%,SPCAP,CH747LM8818':;

SECTION_NUMBER 1
 '@T6G_MB_LIB.T6G(SCH_1):PAGE478_I31@PURE_QUANTA.Q_CAPP(CHIPS)':
 C_PATH='@t6g_mb_lib.t6g(sch_1):page478_i31@pure_quanta.q_capp(chips)',
 P_PATH='@t6g_mb_lib.t6g(sch_1):page365_i31@pure_quanta.q_capp(chips)',
 PATH='I31',
 DRAWING='@T6G_MB_LIB.T6G(SCH_1):PAGE478',
 TOLERANCE='20%',
 MATERIAL='SPCAP',
 PHYS_PAGE='365',
 XY='(-3225,1300)',
 ROT='0',
 VER='1',
 PACK_TYPE='SMLF',
 LOCATION='PC6813',
 CDS_LIB='pure_quanta',
 CDS_PART_NAME='Q_CAPP_SMLF-470UF,2.5V,20%,SPCAP,CH747LM8818',
 VOLTAGE='2.5V',
 PART_NUMBER='CH747LM8818',
 VALUE='470UF',
 PRIM_FILE='./archive_libs/logical/q_capp/chips/chips.prt';

PART_NAME
 PC6814 'Q_CAPP_SMLF-470UF,2.5V,20%,SPCAP,CH747LM8818':;

SECTION_NUMBER 1
 '@T6G_MB_LIB.T6G(SCH_1):PAGE478_I32@PURE_QUANTA.Q_CAPP(CHIPS)':
 C_PATH='@t6g_mb_lib.t6g(sch_1):page478_i32@pure_quanta.q_capp(chips)',
 P_PATH='@t6g_mb_lib.t6g(sch_1):page365_i32@pure_quanta.q_capp(chips)',
 PATH='I32',
 DRAWING='@T6G_MB_LIB.T6G(SCH_1):PAGE478',
 TOLERANCE='20%',
 MATERIAL='SPCAP',
 PHYS_PAGE='365',
 XY='(-3000,1300)',
 ROT='0',
 VER='1',
 PACK_TYPE='SMLF',
 LOCATION='PC6814',
 CDS_LIB='pure_quanta',
 CDS_PART_NAME='Q_CAPP_SMLF-470UF,2.5V,20%,SPCAP,CH747LM8818',
 VOLTAGE='2.5V',
 PART_NUMBER='CH747LM8818',
 VALUE='470UF',
 PRIM_FILE='./archive_libs/logical/q_capp/chips/chips.prt';

PART_NAME
 PC6815 'Q_CAPP_SMLF-470UF,2.5V,20%,SPCAP,CH747LM8818':;

SECTION_NUMBER 1
 '@T6G_MB_LIB.T6G(SCH_1):PAGE478_I82@PURE_QUANTA.Q_CAPP(CHIPS)':
 C_PATH='@t6g_mb_lib.t6g(sch_1):page478_i82@pure_quanta.q_capp(chips)',
 P_PATH='@t6g_mb_lib.t6g(sch_1):page365_i82@pure_quanta.q_capp(chips)',
 PATH='I82',
 DRAWING='@T6G_MB_LIB.T6G(SCH_1):PAGE478',
 TOLERANCE='20%',
 MATERIAL='SPCAP',
 PHYS_PAGE='365',
 XY='(-2800,1300)',
 ROT='0',
 VER='1',
 PACK_TYPE='SMLF',
 LOCATION='PC6815',
 CDS_LIB='pure_quanta',
 CDS_PART_NAME='Q_CAPP_SMLF-470UF,2.5V,20%,SPCAP,CH747LM8818',
 VOLTAGE='2.5V',
 PART_NUMBER='CH747LM8818',
 VALUE='470UF',
 PRIM_FILE='./archive_libs/logical/q_capp/chips/chips.prt';

PART_NAME
 PC6816 'Q_CAP_C0805-22UF,16V,20%,X6S,CH6223MEA01':;

SECTION_NUMBER 1
 '@T6G_MB_LIB.T6G(SCH_1):PAGE476_I216@PURE_QUANTA.Q_CAP(CHIPS)':
 C_PATH='@t6g_mb_lib.t6g(sch_1):page476_i216@pure_quanta.q_cap(chips)',
 P_PATH='@t6g_mb_lib.t6g(sch_1):page363_i216@pure_quanta.q_cap(chips)',
 PATH='I216',
 DRAWING='@T6G_MB_LIB.T6G(SCH_1):PAGE476',
 SEC_TYPE='C0805',
 TOLERANCE='20%',
 MATERIAL='X6S',
 PHYS_PAGE='363',
 XY='(200,-5700)',
 ROT='0',
 VER='1',
 PACK_TYPE='C0805',
 LOCATION='PC6816',
 SEC='1',
 CDS_LIB='pure_quanta',
 CDS_PART_NAME='Q_CAP_C0805-22UF,16V,20%,X6S,CH6223MEA01',
 VOLTAGE='16V',
 PART_NUMBER='CH6223MEA01',
 VALUE='22UF',
 PRIM_FILE='./archive_libs/logical/q_cap/chips/chips.prt';

PART_NAME
 PC6817 'Q_CAP_C0805-22UF,16V,20%,X6S,CH6223MEA01':;

SECTION_NUMBER 1
 '@T6G_MB_LIB.T6G(SCH_1):PAGE476_I232@PURE_QUANTA.Q_CAP(CHIPS)':
 C_PATH='@t6g_mb_lib.t6g(sch_1):page476_i232@pure_quanta.q_cap(chips)',
 P_PATH='@t6g_mb_lib.t6g(sch_1):page363_i232@pure_quanta.q_cap(chips)',
 PATH='I232',
 DRAWING='@T6G_MB_LIB.T6G(SCH_1):PAGE476',
 TOLERANCE='20%',
 MATERIAL='X6S',
 PHYS_PAGE='363',
 XY='(325,-8600)',
 ROT='0',
 VER='1',
 PACK_TYPE='C0805',
 LOCATION='PC6817',
 CDS_LIB='pure_quanta',
 CDS_PART_NAME='Q_CAP_C0805-22UF,16V,20%,X6S,CH6223MEA01',
 VOLTAGE='16V',
 PART_NUMBER='CH6223MEA01',
 VALUE='22UF',
 PRIM_FILE='./archive_libs/logical/q_cap/chips/chips.prt';

PART_NAME
 PC6818 'Q_CAP_C0805-22UF,16V,20%,X6S,CH6223MEA01':;

SECTION_NUMBER 1
 '@T6G_MB_LIB.T6G(SCH_1):PAGE478_I86@PURE_QUANTA.Q_CAP(CHIPS)':
 C_PATH='@t6g_mb_lib.t6g(sch_1):page478_i86@pure_quanta.q_cap(chips)',
 P_PATH='@t6g_mb_lib.t6g(sch_1):page365_i86@pure_quanta.q_cap(chips)',
 PATH='I86',
 DRAWING='@T6G_MB_LIB.T6G(SCH_1):PAGE478',
 TOLERANCE='20%',
 MATERIAL='X6S',
 PHYS_PAGE='365',
 XY='(-2650,2200)',
 ROT='0',
 VER='1',
 PACK_TYPE='C0805',
 LOCATION='PC6818',
 CDS_LIB='pure_quanta',
 CDS_PART_NAME='Q_CAP_C0805-22UF,16V,20%,X6S,CH6223MEA01',
 VOLTAGE='16V',
 PART_NUMBER='CH6223MEA01',
 VALUE='22UF',
 PRIM_FILE='./archive_libs/logical/q_cap/chips/chips.prt';

PART_NAME
 PC6819 'Q_CAP_C0805-22UF,16V,20%,X6S,CH6223MEA01':;

SECTION_NUMBER 1
 '@T6G_MB_LIB.T6G(SCH_1):PAGE478_I100@PURE_QUANTA.Q_CAP(CHIPS)':
 C_PATH='@t6g_mb_lib.t6g(sch_1):page478_i100@pure_quanta.q_cap(chips)',
 P_PATH='@t6g_mb_lib.t6g(sch_1):page365_i100@pure_quanta.q_cap(chips)',
 PATH='I100',
 DRAWING='@T6G_MB_LIB.T6G(SCH_1):PAGE478',
 TOLERANCE='20%',
 MATERIAL='X6S',
 PHYS_PAGE='365',
 XY='(-2775,5100)',
 ROT='0',
 VER='1',
 PACK_TYPE='C0805',
 LOCATION='PC6819',
 CDS_LIB='pure_quanta',
 CDS_PART_NAME='Q_CAP_C0805-22UF,16V,20%,X6S,CH6223MEA01',
 VOLTAGE='16V',
 PART_NUMBER='CH6223MEA01',
 VALUE='22UF',
 PRIM_FILE='./archive_libs/logical/q_cap/chips/chips.prt';

PART_NAME
 PC6900 'Q_CAP_C0805-22UF,16V,20%,X6S,CH6223MEA01':;

SECTION_NUMBER 1
 '@T6G_MB_LIB.T6G(SCH_1):PAGE469_I58@PURE_QUANTA.Q_CAP(CHIPS)':
 C_PATH='@t6g_mb_lib.t6g(sch_1):page469_i58@pure_quanta.q_cap(chips)',
 P_PATH='@t6g_mb_lib.t6g(sch_1):page360_i58@pure_quanta.q_cap(chips)',
 PATH='I58',
 DRAWING='@T6G_MB_LIB.T6G(SCH_1):PAGE469',
 TOLERANCE='20%',
 MATERIAL='X6S',
 PHYS_PAGE='360',
 XY='(-6850,3975)',
 ROT='0',
 VER='1',
 PACK_TYPE='C0805',
 LOCATION='PC6900',
 CDS_LIB='pure_quanta',
 CDS_PART_NAME='Q_CAP_C0805-22UF,16V,20%,X6S,CH6223MEA01',
 VOLTAGE='16V',
 PART_NUMBER='CH6223MEA01',
 VALUE='22UF',
 PRIM_FILE='./archive_libs/logical/q_cap/chips/chips.prt';

PART_NAME
 PC6901 'Q_CAP_C0805-22UF,16V,20%,X6S,CH6223MEA01':;

SECTION_NUMBER 1
 '@T6G_MB_LIB.T6G(SCH_1):PAGE469_I57@PURE_QUANTA.Q_CAP(CHIPS)':
 C_PATH='@t6g_mb_lib.t6g(sch_1):page469_i57@pure_quanta.q_cap(chips)',
 P_PATH='@t6g_mb_lib.t6g(sch_1):page360_i57@pure_quanta.q_cap(chips)',
 PATH='I57',
 DRAWING='@T6G_MB_LIB.T6G(SCH_1):PAGE469',
 TOLERANCE='20%',
 MATERIAL='X6S',
 PHYS_PAGE='360',
 XY='(-6650,3975)',
 ROT='0',
 VER='1',
 PACK_TYPE='C0805',
 LOCATION='PC6901',
 CDS_LIB='pure_quanta',
 CDS_PART_NAME='Q_CAP_C0805-22UF,16V,20%,X6S,CH6223MEA01',
 VOLTAGE='16V',
 PART_NUMBER='CH6223MEA01',
 VALUE='22UF',
 PRIM_FILE='./archive_libs/logical/q_cap/chips/chips.prt';

PART_NAME
 PC6902 'Q_CAP_C0805-22UF,16V,20%,X6S,CH6223MEA01':;

SECTION_NUMBER 1
 '@T6G_MB_LIB.T6G(SCH_1):PAGE469_I56@PURE_QUANTA.Q_CAP(CHIPS)':
 C_PATH='@t6g_mb_lib.t6g(sch_1):page469_i56@pure_quanta.q_cap(chips)',
 P_PATH='@t6g_mb_lib.t6g(sch_1):page360_i56@pure_quanta.q_cap(chips)',
 PATH='I56',
 DRAWING='@T6G_MB_LIB.T6G(SCH_1):PAGE469',
 TOLERANCE='20%',
 MATERIAL='X6S',
 PHYS_PAGE='360',
 XY='(-6450,3975)',
 ROT='0',
 VER='1',
 PACK_TYPE='C0805',
 LOCATION='PC6902',
 CDS_LIB='pure_quanta',
 CDS_PART_NAME='Q_CAP_C0805-22UF,16V,20%,X6S,CH6223MEA01',
 VOLTAGE='16V',
 PART_NUMBER='CH6223MEA01',
 VALUE='22UF',
 PRIM_FILE='./archive_libs/logical/q_cap/chips/chips.prt';

PART_NAME
 PC6903 'Q_CAP_C0805-22UF,16V,20%,X6S,CH6223MEA01':;

SECTION_NUMBER 1
 '@T6G_MB_LIB.T6G(SCH_1):PAGE470_I57@PURE_QUANTA.Q_CAP(CHIPS)':
 C_PATH='@t6g_mb_lib.t6g(sch_1):page470_i57@pure_quanta.q_cap(chips)',
 P_PATH='@t6g_mb_lib.t6g(sch_1):page361_i57@pure_quanta.q_cap(chips)',
 PATH='I57',
 DRAWING='@T6G_MB_LIB.T6G(SCH_1):PAGE470',
 TOLERANCE='20%',
 MATERIAL='X6S',
 PHYS_PAGE='361',
 XY='(-6900,4000)',
 ROT='0',
 VER='1',
 PACK_TYPE='C0805',
 LOCATION='PC6903',
 CDS_LIB='pure_quanta',
 CDS_PART_NAME='Q_CAP_C0805-22UF,16V,20%,X6S,CH6223MEA01',
 VOLTAGE='16V',
 PART_NUMBER='CH6223MEA01',
 VALUE='22UF',
 PRIM_FILE='./archive_libs/logical/q_cap/chips/chips.prt';

PART_NAME
 PC6904 'Q_CAP_C0805-22UF,16V,20%,X6S,CH6223MEA01':;

SECTION_NUMBER 1
 '@T6G_MB_LIB.T6G(SCH_1):PAGE470_I56@PURE_QUANTA.Q_CAP(CHIPS)':
 C_PATH='@t6g_mb_lib.t6g(sch_1):page470_i56@pure_quanta.q_cap(chips)',
 P_PATH='@t6g_mb_lib.t6g(sch_1):page361_i56@pure_quanta.q_cap(chips)',
 PATH='I56',
 DRAWING='@T6G_MB_LIB.T6G(SCH_1):PAGE470',
 TOLERANCE='20%',
 MATERIAL='X6S',
 PHYS_PAGE='361',
 XY='(-6700,4000)',
 ROT='0',
 VER='1',
 PACK_TYPE='C0805',
 LOCATION='PC6904',
 CDS_LIB='pure_quanta',
 CDS_PART_NAME='Q_CAP_C0805-22UF,16V,20%,X6S,CH6223MEA01',
 VOLTAGE='16V',
 PART_NUMBER='CH6223MEA01',
 VALUE='22UF',
 PRIM_FILE='./archive_libs/logical/q_cap/chips/chips.prt';

PART_NAME
 PC6905 'Q_CAP_C0805-22UF,16V,20%,X6S,CH6223MEA01':;

SECTION_NUMBER 1
 '@T6G_MB_LIB.T6G(SCH_1):PAGE470_I55@PURE_QUANTA.Q_CAP(CHIPS)':
 C_PATH='@t6g_mb_lib.t6g(sch_1):page470_i55@pure_quanta.q_cap(chips)',
 P_PATH='@t6g_mb_lib.t6g(sch_1):page361_i55@pure_quanta.q_cap(chips)',
 PATH='I55',
 DRAWING='@T6G_MB_LIB.T6G(SCH_1):PAGE470',
 TOLERANCE='20%',
 MATERIAL='X6S',
 PHYS_PAGE='361',
 XY='(-6525,4000)',
 ROT='0',
 VER='1',
 PACK_TYPE='C0805',
 LOCATION='PC6905',
 CDS_LIB='pure_quanta',
 CDS_PART_NAME='Q_CAP_C0805-22UF,16V,20%,X6S,CH6223MEA01',
 VOLTAGE='16V',
 PART_NUMBER='CH6223MEA01',
 VALUE='22UF',
 PRIM_FILE='./archive_libs/logical/q_cap/chips/chips.prt';

PART_NAME
 PC7000 'Q_CAP_C0805-22UF,16V,20%,X6S,CH6223MEA01':;

SECTION_NUMBER 1
 '@T6G_MB_LIB.T6G(SCH_1):PAGE180_I85@PURE_QUANTA.Q_CAP(CHIPS)':
 C_PATH='@t6g_mb_lib.t6g(sch_1):page180_i85@pure_quanta.q_cap(chips)',
 P_PATH='@t6g_mb_lib.t6g(sch_1):page205_i85@pure_quanta.q_cap(chips)',
 PATH='I85',
 DRAWING='@T6G_MB_LIB.T6G(SCH_1):PAGE180',
 TOLERANCE='20%',
 MATERIAL='X6S',
 PHYS_PAGE='205',
 XY='(5425,5900)',
 ROT='0',
 VER='1',
 PACK_TYPE='C0805',
 LOCATION='PC7000',
 CDS_LIB='pure_quanta',
 CDS_PART_NAME='Q_CAP_C0805-22UF,16V,20%,X6S,CH6223MEA01',
 VOLTAGE='16V',
 PART_NUMBER='CH6223MEA01',
 VALUE='22UF',
 PRIM_FILE='./archive_libs/logical/q_cap/chips/chips.prt';

PART_NAME
 PC7001 'Q_CAP_C0805-22UF,16V,20%,X6S,CH6223MEA01':;

SECTION_NUMBER 1
 '@T6G_MB_LIB.T6G(SCH_1):PAGE197_I86@PURE_QUANTA.Q_CAP(CHIPS)':
 C_PATH='@t6g_mb_lib.t6g(sch_1):page197_i86@pure_quanta.q_cap(chips)',
 P_PATH='@t6g_mb_lib.t6g(sch_1):page222_i86@pure_quanta.q_cap(chips)',
 PATH='I86',
 DRAWING='@T6G_MB_LIB.T6G(SCH_1):PAGE197',
 TOLERANCE='20%',
 MATERIAL='X6S',
 PHYS_PAGE='222',
 XY='(4500,5925)',
 ROT='0',
 VER='1',
 PACK_TYPE='C0805',
 LOCATION='PC7001',
 CDS_LIB='pure_quanta',
 CDS_PART_NAME='Q_CAP_C0805-22UF,16V,20%,X6S,CH6223MEA01',
 VOLTAGE='16V',
 PART_NUMBER='CH6223MEA01',
 VALUE='22UF',
 PRIM_FILE='./archive_libs/logical/q_cap/chips/chips.prt';

PART_NAME
 PC7002 'Q_CAP_C0805-22UF,16V,20%,X6S,CH6223MEA01':;

SECTION_NUMBER 1
 '@T6G_MB_LIB.T6G(SCH_1):PAGE183_I95@PURE_QUANTA.Q_CAP(CHIPS)':
 C_PATH='@t6g_mb_lib.t6g(sch_1):page183_i95@pure_quanta.q_cap(chips)',
 P_PATH='@t6g_mb_lib.t6g(sch_1):page208_i95@pure_quanta.q_cap(chips)',
 PATH='I95',
 DRAWING='@T6G_MB_LIB.T6G(SCH_1):PAGE183',
 TOLERANCE='20%',
 MATERIAL='X6S',
 PHYS_PAGE='208',
 XY='(-3550,5325)',
 ROT='0',
 VER='1',
 PACK_TYPE='C0805',
 LOCATION='PC7002',
 CDS_LIB='pure_quanta',
 CDS_PART_NAME='Q_CAP_C0805-22UF,16V,20%,X6S,CH6223MEA01',
 VOLTAGE='16V',
 PART_NUMBER='CH6223MEA01',
 VALUE='22UF',
 PRIM_FILE='./archive_libs/logical/q_cap/chips/chips.prt';

PART_NAME
 PC7003 'Q_CAP_C0805-22UF,16V,20%,X6S,CH6223MEA01':;

SECTION_NUMBER 1
 '@T6G_MB_LIB.T6G(SCH_1):PAGE200_I95@PURE_QUANTA.Q_CAP(CHIPS)':
 C_PATH='@t6g_mb_lib.t6g(sch_1):page200_i95@pure_quanta.q_cap(chips)',
 P_PATH='@t6g_mb_lib.t6g(sch_1):page225_i95@pure_quanta.q_cap(chips)',
 PATH='I95',
 DRAWING='@T6G_MB_LIB.T6G(SCH_1):PAGE200',
 TOLERANCE='20%',
 MATERIAL='X6S',
 PHYS_PAGE='225',
 XY='(-3600,5525)',
 ROT='0',
 VER='1',
 PACK_TYPE='C0805',
 LOCATION='PC7003',
 CDS_LIB='pure_quanta',
 CDS_PART_NAME='Q_CAP_C0805-22UF,16V,20%,X6S,CH6223MEA01',
 VOLTAGE='16V',
 PART_NUMBER='CH6223MEA01',
 VALUE='22UF',
 PRIM_FILE='./archive_libs/logical/q_cap/chips/chips.prt';

PART_NAME
 PC8000 'Q_CAP_C0805-22UF,16V,20%,X6S,CH6223MEA01':;

SECTION_NUMBER 1
 '@T6G_MB_LIB.T6G(SCH_1):PAGE167_I44@PURE_QUANTA.Q_CAP(CHIPS)':
 C_PATH='@t6g_mb_lib.t6g(sch_1):page167_i44@pure_quanta.q_cap(chips)',
 P_PATH='@t6g_mb_lib.t6g(sch_1):page192_i44@pure_quanta.q_cap(chips)',
 PATH='I44',
 DRAWING='@T6G_MB_LIB.T6G(SCH_1):PAGE167',
 TOLERANCE='20%',
 MATERIAL='X6S',
 PHYS_PAGE='192',
 XY='(-9275,4500)',
 ROT='0',
 VER='1',
 PACK_TYPE='C0805',
 LOCATION='PC8000',
 CDS_LIB='pure_quanta',
 CDS_PART_NAME='Q_CAP_C0805-22UF,16V,20%,X6S,CH6223MEA01',
 VOLTAGE='16V',
 PART_NUMBER='CH6223MEA01',
 VALUE='22UF',
 PRIM_FILE='./archive_libs/logical/q_cap/chips/chips.prt';

PART_NAME
 PC8001 'Q_CAP_C0805-22UF,16V,20%,X6S,CH6223MEA01':;

SECTION_NUMBER 1
 '@T6G_MB_LIB.T6G(SCH_1):PAGE167_I45@PURE_QUANTA.Q_CAP(CHIPS)':
 C_PATH='@t6g_mb_lib.t6g(sch_1):page167_i45@pure_quanta.q_cap(chips)',
 P_PATH='@t6g_mb_lib.t6g(sch_1):page192_i45@pure_quanta.q_cap(chips)',
 PATH='I45',
 DRAWING='@T6G_MB_LIB.T6G(SCH_1):PAGE167',
 TOLERANCE='20%',
 MATERIAL='X6S',
 PHYS_PAGE='192',
 XY='(-9600,4500)',
 ROT='0',
 VER='1',
 PACK_TYPE='C0805',
 LOCATION='PC8001',
 CDS_LIB='pure_quanta',
 CDS_PART_NAME='Q_CAP_C0805-22UF,16V,20%,X6S,CH6223MEA01',
 VOLTAGE='16V',
 PART_NUMBER='CH6223MEA01',
 VALUE='22UF',
 PRIM_FILE='./archive_libs/logical/q_cap/chips/chips.prt';

PART_NAME
 PC8002 'Q_CAP_C0805-22UF,16V,20%,X6S,CH6223MEA01':;

SECTION_NUMBER 1
 '@T6G_MB_LIB.T6G(SCH_1):PAGE184_I57@PURE_QUANTA.Q_CAP(CHIPS)':
 C_PATH='@t6g_mb_lib.t6g(sch_1):page184_i57@pure_quanta.q_cap(chips)',
 P_PATH='@t6g_mb_lib.t6g(sch_1):page209_i57@pure_quanta.q_cap(chips)',
 PATH='I57',
 DRAWING='@T6G_MB_LIB.T6G(SCH_1):PAGE184',
 TOLERANCE='20%',
 MATERIAL='X6S',
 PHYS_PAGE='209',
 XY='(-8200,4125)',
 ROT='0',
 VER='1',
 PACK_TYPE='C0805',
 LOCATION='PC8002',
 CDS_LIB='pure_quanta',
 CDS_PART_NAME='Q_CAP_C0805-22UF,16V,20%,X6S,CH6223MEA01',
 VOLTAGE='16V',
 PART_NUMBER='CH6223MEA01',
 VALUE='22UF',
 PRIM_FILE='./archive_libs/logical/q_cap/chips/chips.prt';

PART_NAME
 PC8003 'Q_CAP_C0805-22UF,16V,20%,X6S,CH6223MEA01':;

SECTION_NUMBER 1
 '@T6G_MB_LIB.T6G(SCH_1):PAGE201_I57@PURE_QUANTA.Q_CAP(CHIPS)':
 C_PATH='@t6g_mb_lib.t6g(sch_1):page201_i57@pure_quanta.q_cap(chips)',
 P_PATH='@t6g_mb_lib.t6g(sch_1):page226_i57@pure_quanta.q_cap(chips)',
 PATH='I57',
 DRAWING='@T6G_MB_LIB.T6G(SCH_1):PAGE201',
 TOLERANCE='20%',
 MATERIAL='X6S',
 PHYS_PAGE='226',
 XY='(-7850,4575)',
 ROT='0',
 VER='1',
 PACK_TYPE='C0805',
 LOCATION='PC8003',
 CDS_LIB='pure_quanta',
 CDS_PART_NAME='Q_CAP_C0805-22UF,16V,20%,X6S,CH6223MEA01',
 VOLTAGE='16V',
 PART_NUMBER='CH6223MEA01',
 VALUE='22UF',
 PRIM_FILE='./archive_libs/logical/q_cap/chips/chips.prt';

PART_NAME
 PC8004 'Q_CAP_C0805-22UF,16V,20%,X6S,CH6223MEA01':;

SECTION_NUMBER 1
 '@T6G_MB_LIB.T6G(SCH_1):PAGE183_I93@PURE_QUANTA.Q_CAP(CHIPS)':
 C_PATH='@t6g_mb_lib.t6g(sch_1):page183_i93@pure_quanta.q_cap(chips)',
 P_PATH='@t6g_mb_lib.t6g(sch_1):page208_i93@pure_quanta.q_cap(chips)',
 PATH='I93',
 DRAWING='@T6G_MB_LIB.T6G(SCH_1):PAGE183',
 TOLERANCE='20%',
 MATERIAL='X6S',
 PHYS_PAGE='208',
 XY='(-3800,5325)',
 ROT='0',
 VER='1',
 PACK_TYPE='C0805',
 LOCATION='PC8004',
 CDS_LIB='pure_quanta',
 CDS_PART_NAME='Q_CAP_C0805-22UF,16V,20%,X6S,CH6223MEA01',
 VOLTAGE='16V',
 PART_NUMBER='CH6223MEA01',
 VALUE='22UF',
 PRIM_FILE='./archive_libs/logical/q_cap/chips/chips.prt';

PART_NAME
 PC8005 'Q_CAP_C0805-22UF,16V,20%,X6S,CH6223MEA01':;

SECTION_NUMBER 1
 '@T6G_MB_LIB.T6G(SCH_1):PAGE183_I94@PURE_QUANTA.Q_CAP(CHIPS)':
 C_PATH='@t6g_mb_lib.t6g(sch_1):page183_i94@pure_quanta.q_cap(chips)',
 P_PATH='@t6g_mb_lib.t6g(sch_1):page208_i94@pure_quanta.q_cap(chips)',
 PATH='I94',
 DRAWING='@T6G_MB_LIB.T6G(SCH_1):PAGE183',
 TOLERANCE='20%',
 MATERIAL='X6S',
 PHYS_PAGE='208',
 XY='(-3375,2400)',
 ROT='0',
 VER='1',
 PACK_TYPE='C0805',
 LOCATION='PC8005',
 CDS_LIB='pure_quanta',
 CDS_PART_NAME='Q_CAP_C0805-22UF,16V,20%,X6S,CH6223MEA01',
 VOLTAGE='16V',
 PART_NUMBER='CH6223MEA01',
 VALUE='22UF',
 PRIM_FILE='./archive_libs/logical/q_cap/chips/chips.prt';

PART_NAME
 PC8006 'Q_CAP_C0805-22UF,16V,20%,X6S,CH6223MEA01':;

SECTION_NUMBER 1
 '@T6G_MB_LIB.T6G(SCH_1):PAGE200_I93@PURE_QUANTA.Q_CAP(CHIPS)':
 C_PATH='@t6g_mb_lib.t6g(sch_1):page200_i93@pure_quanta.q_cap(chips)',
 P_PATH='@t6g_mb_lib.t6g(sch_1):page225_i93@pure_quanta.q_cap(chips)',
 PATH='I93',
 DRAWING='@T6G_MB_LIB.T6G(SCH_1):PAGE200',
 TOLERANCE='20%',
 MATERIAL='X6S',
 PHYS_PAGE='225',
 XY='(-3850,5525)',
 ROT='0',
 VER='1',
 PACK_TYPE='C0805',
 LOCATION='PC8006',
 CDS_LIB='pure_quanta',
 CDS_PART_NAME='Q_CAP_C0805-22UF,16V,20%,X6S,CH6223MEA01',
 VOLTAGE='16V',
 PART_NUMBER='CH6223MEA01',
 VALUE='22UF',
 PRIM_FILE='./archive_libs/logical/q_cap/chips/chips.prt';

PART_NAME
 PC8007 'Q_CAP_C0805-22UF,16V,20%,X6S,CH6223MEA01':;

SECTION_NUMBER 1
 '@T6G_MB_LIB.T6G(SCH_1):PAGE200_I94@PURE_QUANTA.Q_CAP(CHIPS)':
 C_PATH='@t6g_mb_lib.t6g(sch_1):page200_i94@pure_quanta.q_cap(chips)',
 P_PATH='@t6g_mb_lib.t6g(sch_1):page225_i94@pure_quanta.q_cap(chips)',
 PATH='I94',
 DRAWING='@T6G_MB_LIB.T6G(SCH_1):PAGE200',
 TOLERANCE='20%',
 MATERIAL='X6S',
 PHYS_PAGE='225',
 XY='(-3500,2600)',
 ROT='0',
 VER='1',
 PACK_TYPE='C0805',
 LOCATION='PC8007',
 CDS_LIB='pure_quanta',
 CDS_PART_NAME='Q_CAP_C0805-22UF,16V,20%,X6S,CH6223MEA01',
 VOLTAGE='16V',
 PART_NUMBER='CH6223MEA01',
 VALUE='22UF',
 PRIM_FILE='./archive_libs/logical/q_cap/chips/chips.prt';

PART_NAME
 PC8008 'Q_CAP_0603-1UF,16V,10%,X7R,TMP_QCH5103K1900':;

SECTION_NUMBER 1
 '@T6G_MB_LIB.T6G(SCH_1):PAGE245_I44@PURE_QUANTA.Q_CAP(CHIPS)':
 C_PATH='@t6g_mb_lib.t6g(sch_1):page245_i44@pure_quanta.q_cap(chips)',
 P_PATH='@t6g_mb_lib.t6g(sch_1):page190_i44@pure_quanta.q_cap(chips)',
 PATH='I44',
 DRAWING='@T6G_MB_LIB.T6G(SCH_1):PAGE245',
 TOLERANCE='10%',
 MATERIAL='X7R',
 PHYS_PAGE='190',
 XY='(-900,725)',
 ROT='0',
 VER='1',
 PACK_TYPE='0603',
 LOCATION='PC8008',
 CDS_LIB='pure_quanta',
 CDS_PART_NAME='Q_CAP_0603-1UF,16V,10%,X7R,TMP_QCH5103K1900',
 VOLTAGE='16V',
 PART_NUMBER='TMP_QCH5103K1900',
 VALUE='1UF',
 PRIM_FILE='./archive_libs/logical/q_cap/chips/chips.prt';

PART_NAME
 PC8009 'Q_CAP_C0805-22UF,16V,20%,X6S,CH6223MEA01':;

SECTION_NUMBER 1
 '@T6G_MB_LIB.T6G(SCH_1):PAGE173_I87@PURE_QUANTA.Q_CAP(CHIPS)':
 C_PATH='@t6g_mb_lib.t6g(sch_1):page173_i87@pure_quanta.q_cap(chips)',
 P_PATH='@t6g_mb_lib.t6g(sch_1):page198_i87@pure_quanta.q_cap(chips)',
 PATH='I87',
 DRAWING='@T6G_MB_LIB.T6G(SCH_1):PAGE173',
 TOLERANCE='20%',
 MATERIAL='X6S',
 PHYS_PAGE='198',
 XY='(-3550,5925)',
 ROT='0',
 VER='1',
 PACK_TYPE='C0805',
 LOCATION='PC8009',
 CDS_LIB='pure_quanta',
 CDS_PART_NAME='Q_CAP_C0805-22UF,16V,20%,X6S,CH6223MEA01',
 VOLTAGE='16V',
 PART_NUMBER='CH6223MEA01',
 VALUE='22UF',
 PRIM_FILE='./archive_libs/logical/q_cap/chips/chips.prt';

PART_NAME
 PC8010 'Q_CAP_C0805-22UF,16V,20%,X6S,CH6223MEA01':;

SECTION_NUMBER 1
 '@T6G_MB_LIB.T6G(SCH_1):PAGE173_I88@PURE_QUANTA.Q_CAP(CHIPS)':
 C_PATH='@t6g_mb_lib.t6g(sch_1):page173_i88@pure_quanta.q_cap(chips)',
 P_PATH='@t6g_mb_lib.t6g(sch_1):page198_i88@pure_quanta.q_cap(chips)',
 PATH='I88',
 DRAWING='@T6G_MB_LIB.T6G(SCH_1):PAGE173',
 TOLERANCE='20%',
 MATERIAL='X6S',
 PHYS_PAGE='198',
 XY='(-3075,2850)',
 ROT='0',
 VER='1',
 PACK_TYPE='C0805',
 LOCATION='PC8010',
 CDS_LIB='pure_quanta',
 CDS_PART_NAME='Q_CAP_C0805-22UF,16V,20%,X6S,CH6223MEA01',
 VOLTAGE='16V',
 PART_NUMBER='CH6223MEA01',
 VALUE='22UF',
 PRIM_FILE='./archive_libs/logical/q_cap/chips/chips.prt';

PART_NAME
 PC8011 'Q_CAP_C0805-22UF,16V,20%,X6S,CH6223MEA01':;

SECTION_NUMBER 1
 '@T6G_MB_LIB.T6G(SCH_1):PAGE190_I87@PURE_QUANTA.Q_CAP(CHIPS)':
 C_PATH='@t6g_mb_lib.t6g(sch_1):page190_i87@pure_quanta.q_cap(chips)',
 P_PATH='@t6g_mb_lib.t6g(sch_1):page215_i87@pure_quanta.q_cap(chips)',
 PATH='I87',
 DRAWING='@T6G_MB_LIB.T6G(SCH_1):PAGE190',
 TOLERANCE='20%',
 MATERIAL='X6S',
 PHYS_PAGE='215',
 XY='(-3750,5600)',
 ROT='0',
 VER='1',
 PACK_TYPE='C0805',
 LOCATION='PC8011',
 CDS_LIB='pure_quanta',
 CDS_PART_NAME='Q_CAP_C0805-22UF,16V,20%,X6S,CH6223MEA01',
 VOLTAGE='16V',
 PART_NUMBER='CH6223MEA01',
 VALUE='22UF',
 PRIM_FILE='./archive_libs/logical/q_cap/chips/chips.prt';

PART_NAME
 PC8012 'Q_CAP_C0805-22UF,16V,20%,X6S,CH6223MEA01':;

SECTION_NUMBER 1
 '@T6G_MB_LIB.T6G(SCH_1):PAGE190_I88@PURE_QUANTA.Q_CAP(CHIPS)':
 C_PATH='@t6g_mb_lib.t6g(sch_1):page190_i88@pure_quanta.q_cap(chips)',
 P_PATH='@t6g_mb_lib.t6g(sch_1):page215_i88@pure_quanta.q_cap(chips)',
 PATH='I88',
 DRAWING='@T6G_MB_LIB.T6G(SCH_1):PAGE190',
 TOLERANCE='20%',
 MATERIAL='X6S',
 PHYS_PAGE='215',
 XY='(-3375,2850)',
 ROT='0',
 VER='1',
 PACK_TYPE='C0805',
 LOCATION='PC8012',
 CDS_LIB='pure_quanta',
 CDS_PART_NAME='Q_CAP_C0805-22UF,16V,20%,X6S,CH6223MEA01',
 VOLTAGE='16V',
 PART_NUMBER='CH6223MEA01',
 VALUE='22UF',
 PRIM_FILE='./archive_libs/logical/q_cap/chips/chips.prt';

PART_NAME
 PC8013 'Q_CAP_C0805-22UF,16V,20%,X6S,CH6223MEA01':;

SECTION_NUMBER 1
 '@T6G_MB_LIB.T6G(SCH_1):PAGE245_I70@PURE_QUANTA.Q_CAP(CHIPS)':
 C_PATH='@t6g_mb_lib.t6g(sch_1):page245_i70@pure_quanta.q_cap(chips)',
 P_PATH='@t6g_mb_lib.t6g(sch_1):page190_i70@pure_quanta.q_cap(chips)',
 PATH='I70',
 DRAWING='@T6G_MB_LIB.T6G(SCH_1):PAGE245',
 TOLERANCE='20%',
 MATERIAL='X6S',
 PHYS_PAGE='190',
 XY='(-1825,425)',
 ROT='0',
 VER='1',
 PACK_TYPE='C0805',
 LOCATION='PC8013',
 CDS_LIB='pure_quanta',
 CDS_PART_NAME='Q_CAP_C0805-22UF,16V,20%,X6S,CH6223MEA01',
 VOLTAGE='16V',
 PART_NUMBER='CH6223MEA01',
 VALUE='22UF',
 PRIM_FILE='./archive_libs/logical/q_cap/chips/chips.prt';

PART_NAME
 PC8014 'Q_CAP_C0805-22UF,16V,20%,X6S,CH6223MEA01':;

SECTION_NUMBER 1
 '@T6G_MB_LIB.T6G(SCH_1):PAGE245_I71@PURE_QUANTA.Q_CAP(CHIPS)':
 C_PATH='@t6g_mb_lib.t6g(sch_1):page245_i71@pure_quanta.q_cap(chips)',
 P_PATH='@t6g_mb_lib.t6g(sch_1):page190_i71@pure_quanta.q_cap(chips)',
 PATH='I71',
 DRAWING='@T6G_MB_LIB.T6G(SCH_1):PAGE245',
 TOLERANCE='20%',
 MATERIAL='X6S',
 PHYS_PAGE='190',
 XY='(-1625,450)',
 ROT='0',
 VER='1',
 PACK_TYPE='C0805',
 LOCATION='PC8014',
 CDS_LIB='pure_quanta',
 CDS_PART_NAME='Q_CAP_C0805-22UF,16V,20%,X6S,CH6223MEA01',
 VOLTAGE='16V',
 PART_NUMBER='CH6223MEA01',
 VALUE='22UF',
 PRIM_FILE='./archive_libs/logical/q_cap/chips/chips.prt';

PART_NAME
 PC8071 'Q_CAP_C0805-22UF,16V,20%,X6S,CH6223MEA01':;

SECTION_NUMBER 1
 '@T6G_MB_LIB.T6G(SCH_1):PAGE245_I40@PURE_QUANTA.Q_CAP(CHIPS)':
 C_PATH='@t6g_mb_lib.t6g(sch_1):page245_i40@pure_quanta.q_cap(chips)',
 P_PATH='@t6g_mb_lib.t6g(sch_1):page190_i40@pure_quanta.q_cap(chips)',
 PATH='I40',
 DRAWING='@T6G_MB_LIB.T6G(SCH_1):PAGE245',
 TOLERANCE='20%',
 MATERIAL='X6S',
 PHYS_PAGE='190',
 XY='(-2050,1100)',
 ROT='0',
 VER='1',
 PACK_TYPE='C0805',
 LOCATION='PC8071',
 CDS_LIB='pure_quanta',
 CDS_PART_NAME='Q_CAP_C0805-22UF,16V,20%,X6S,CH6223MEA01',
 VOLTAGE='16V',
 PART_NUMBER='CH6223MEA01',
 VALUE='22UF',
 PRIM_FILE='./archive_libs/logical/q_cap/chips/chips.prt';

PART_NAME
 PC8567 'Q_CAP_C0805-22UF,16V,20%,X6S,CH6223MEA01':;

SECTION_NUMBER 1
 '@T6G_MB_LIB.T6G(SCH_1):PAGE245_I32@PURE_QUANTA.Q_CAP(CHIPS)':
 C_PATH='@t6g_mb_lib.t6g(sch_1):page245_i32@pure_quanta.q_cap(chips)',
 P_PATH='@t6g_mb_lib.t6g(sch_1):page190_i32@pure_quanta.q_cap(chips)',
 PATH='I32',
 DRAWING='@T6G_MB_LIB.T6G(SCH_1):PAGE245',
 TOLERANCE='20%',
 MATERIAL='X6S',
 PHYS_PAGE='190',
 XY='(-3350,1100)',
 ROT='0',
 VER='1',
 PACK_TYPE='C0805',
 LOCATION='PC8567',
 CDS_LIB='pure_quanta',
 CDS_PART_NAME='Q_CAP_C0805-22UF,16V,20%,X6S,CH6223MEA01',
 VOLTAGE='16V',
 PART_NUMBER='CH6223MEA01',
 VALUE='22UF',
 PRIM_FILE='./archive_libs/logical/q_cap/chips/chips.prt';

PART_NAME
 PD13 'ZENER_AC-5.0SMDJ14A,SMLF,IC,BC0MDJ14000':;

SECTION_NUMBER 1
 '@T6G_MB_LIB.T6G(SCH_1):PAGE372_I3@PURE_QUANTA.ZENER_AC(CHIPS)':
 C_PATH='@t6g_mb_lib.t6g(sch_1):page372_i3@pure_quanta.zener_ac(chips)',
 P_PATH='@t6g_mb_lib.t6g(sch_1):page268_i3@pure_quanta.zener_ac(chips)',
 PATH='I3',
 DRAWING='@T6G_MB_LIB.T6G(SCH_1):PAGE372',
 PART_TYPE='SMLF',
 MATERIAL='IC',
 PHYS_PAGE='268',
 XY='(-8075,5525)',
 ROT='1',
 VER='1',
 LOCATION='PD13',
 CDS_LIB='pure_quanta',
 CDS_PART_NAME='ZENER_AC-5.0SMDJ14A,SMLF,IC,BC0MDJ14000',
 PART_NUMBER='BC0MDJ14000',
 VALUE='5.0SMDJ14A',
 PRIM_FILE='./archive_libs/logical/zener_ac/chips/chips.prt';

PART_NAME
 PD15 'ZENER_AC-5.0SMDJ14A,SMLF,IC,BC0MDJ14000':;

SECTION_NUMBER 1
 '@T6G_MB_LIB.T6G(SCH_1):PAGE372_I1@PURE_QUANTA.ZENER_AC(CHIPS)':
 C_PATH='@t6g_mb_lib.t6g(sch_1):page372_i1@pure_quanta.zener_ac(chips)',
 P_PATH='@t6g_mb_lib.t6g(sch_1):page268_i1@pure_quanta.zener_ac(chips)',
 PATH='I1',
 DRAWING='@T6G_MB_LIB.T6G(SCH_1):PAGE372',
 PART_TYPE='SMLF',
 MATERIAL='IC',
 PHYS_PAGE='268',
 XY='(-8575,5525)',
 ROT='1',
 VER='1',
 LOCATION='PD15',
 CDS_LIB='pure_quanta',
 CDS_PART_NAME='ZENER_AC-5.0SMDJ14A,SMLF,IC,BC0MDJ14000',
 PART_NUMBER='BC0MDJ14000',
 VALUE='5.0SMDJ14A',
 PRIM_FILE='./archive_libs/logical/zener_ac/chips/chips.prt';

PART_NAME
 PD17 'SS15P3SM386A-SS15P3S-M3/86A,SMLF,IC,BC015P3SZ00':
 ROOM='HSC BOM2';

SECTION_NUMBER 1
 '@T6G_MB_LIB.T6G(SCH_1):PAGE302_I72@PURE_QUANTA.SS15P3SM386A(CHIPS)':
 C_PATH='@t6g_mb_lib.t6g(sch_1):page302_i72@pure_quanta.ss15p3sm386a(chips)',
 P_PATH='@t6g_mb_lib.t6g(sch_1):page266_i72@pure_quanta.ss15p3sm386a(chips)',
 PATH='I72',
 DRAWING='@T6G_MB_LIB.T6G(SCH_1):PAGE302',
 PART_TYPE='SMLF',
 MATERIAL='IC',
 PHYS_PAGE='266',
 XY='(-475,1375)',
 ROT='1',
 VER='1',
 LOCATION='PD17',
 CDS_LIB='pure_quanta',
 CDS_PART_NAME='SS15P3SM386A-SS15P3S-M3/86A,SMLF,IC,BC015P3SZ00',
 ROOM='HSC BOM2',
 PART_NUMBER='BC015P3SZ00',
 VALUE='SS15P3S-M3/86A',
 PRIM_FILE='./archive_libs/logical/ss15p3sm386a/chips/chips.prt';

PART_NAME
 PD101 'DIODE_TVS-SMF14A,SMLF,IC,BCSMF14AZ01':;

SECTION_NUMBER 1
 '@T6G_MB_LIB.T6G(SCH_1):PAGE338_I115@PURE_QUANTA.DIODE_TVS(CHIPS)':
 C_PATH='@t6g_mb_lib.t6g(sch_1):page338_i115@pure_quanta.diode_tvs(chips)',
 P_PATH='@t6g_mb_lib.t6g(sch_1):page134_i115@pure_quanta.diode_tvs(chips)',
 PATH='I115',
 DRAWING='@T6G_MB_LIB.T6G(SCH_1):PAGE338',
 PIN_NAMES_ROTATE='True',
 PART_TYPE='SMLF',
 MATERIAL='IC',
 PHYS_PAGE='134',
 XY='(5300,11450)',
 ROT='1',
 VER='1',
 LOCATION='PD101',
 CDS_LIB='pure_quanta',
 CDS_PART_NAME='DIODE_TVS-SMF14A,SMLF,IC,BCSMF14AZ01',
 PART_NUMBER='BCSMF14AZ01',
 VALUE='SMF14A',
 PRIM_FILE='./archive_libs/logical/diode_tvs/chips/chips.prt';

PART_NAME
 PD102 'SCHOTTKY_AC-B340A-13-F,SMLF,IC,BC000340Z30':;

SECTION_NUMBER 1
 '@T6G_MB_LIB.T6G(SCH_1):PAGE338_I79@PURE_QUANTA.SCHOTTKY_AC(CHIPS)':
 C_PATH='@t6g_mb_lib.t6g(sch_1):page338_i79@pure_quanta.schottky_ac(chips)',
 P_PATH='@t6g_mb_lib.t6g(sch_1):page134_i79@pure_quanta.schottky_ac(chips)',
 PATH='I79',
 DRAWING='@T6G_MB_LIB.T6G(SCH_1):PAGE338',
 PART_TYPE='SMLF',
 MATERIAL='IC',
 PHYS_PAGE='134',
 XY='(8825,11700)',
 ROT='1',
 VER='1',
 LOCATION='PD102',
 CDS_LIB='pure_quanta',
 CDS_PART_NAME='SCHOTTKY_AC-B340A-13-F,SMLF,IC,BC000340Z30',
 PART_NUMBER='BC000340Z30',
 VALUE='B340A-13-F',
 PRIM_FILE='./archive_libs/logical/schottky_ac/chips/chips.prt';

PART_NAME
 PD103 'SCHOTTKY_AC-B340A-13-F,SMLF,IC,BC000340Z30':;

SECTION_NUMBER 1
 '@T6G_MB_LIB.T6G(SCH_1):PAGE338_I97@PURE_QUANTA.SCHOTTKY_AC(CHIPS)':
 C_PATH='@t6g_mb_lib.t6g(sch_1):page338_i97@pure_quanta.schottky_ac(chips)',
 P_PATH='@t6g_mb_lib.t6g(sch_1):page134_i97@pure_quanta.schottky_ac(chips)',
 PATH='I97',
 DRAWING='@T6G_MB_LIB.T6G(SCH_1):PAGE338',
 PART_TYPE='SMLF',
 MATERIAL='IC',
 PHYS_PAGE='134',
 XY='(9050,13675)',
 ROT='1',
 VER='1',
 LOCATION='PD103',
 CDS_LIB='pure_quanta',
 CDS_PART_NAME='SCHOTTKY_AC-B340A-13-F,SMLF,IC,BC000340Z30',
 PART_NUMBER='BC000340Z30',
 VALUE='B340A-13-F',
 PRIM_FILE='./archive_libs/logical/schottky_ac/chips/chips.prt';

PART_NAME
 PD107 'DIODE_TVS-SMF14A,SMLF,IC,BCSMF14AZ01':;

SECTION_NUMBER 1
 '@T6G_MB_LIB.T6G(SCH_1):PAGE343_I47@PURE_QUANTA.DIODE_TVS(CHIPS)':
 C_PATH='@t6g_mb_lib.t6g(sch_1):page343_i47@pure_quanta.diode_tvs(chips)',
 P_PATH='@t6g_mb_lib.t6g(sch_1):page140_i47@pure_quanta.diode_tvs(chips)',
 PATH='I47',
 DRAWING='@T6G_MB_LIB.T6G(SCH_1):PAGE343',
 PIN_NAMES_ROTATE='True',
 PART_TYPE='SMLF',
 MATERIAL='IC',
 PHYS_PAGE='140',
 XY='(-875,7025)',
 ROT='1',
 VER='1',
 LOCATION='PD107',
 CDS_LIB='pure_quanta',
 CDS_PART_NAME='DIODE_TVS-SMF14A,SMLF,IC,BCSMF14AZ01',
 PART_NUMBER='BCSMF14AZ01',
 VALUE='SMF14A',
 PRIM_FILE='./archive_libs/logical/diode_tvs/chips/chips.prt';

PART_NAME
 PD108 'SCHOTTKY_AC-B340A-13-F,SMLF,IC,BC000340Z30':;

SECTION_NUMBER 1
 '@T6G_MB_LIB.T6G(SCH_1):PAGE343_I92@PURE_QUANTA.SCHOTTKY_AC(CHIPS)':
 C_PATH='@t6g_mb_lib.t6g(sch_1):page343_i92@pure_quanta.schottky_ac(chips)',
 P_PATH='@t6g_mb_lib.t6g(sch_1):page140_i92@pure_quanta.schottky_ac(chips)',
 PATH='I92',
 DRAWING='@T6G_MB_LIB.T6G(SCH_1):PAGE343',
 PART_TYPE='SMLF',
 MATERIAL='IC',
 PHYS_PAGE='140',
 XY='(2675,7250)',
 ROT='1',
 VER='1',
 LOCATION='PD108',
 CDS_LIB='pure_quanta',
 CDS_PART_NAME='SCHOTTKY_AC-B340A-13-F,SMLF,IC,BC000340Z30',
 PART_NUMBER='BC000340Z30',
 VALUE='B340A-13-F',
 PRIM_FILE='./archive_libs/logical/schottky_ac/chips/chips.prt';

PART_NAME
 PD109 'SCHOTTKY_AC-B340A-13-F,SMLF,IC,BC000340Z30':;

SECTION_NUMBER 1
 '@T6G_MB_LIB.T6G(SCH_1):PAGE343_I106@PURE_QUANTA.SCHOTTKY_AC(CHIPS)':
 C_PATH='@t6g_mb_lib.t6g(sch_1):page343_i106@pure_quanta.schottky_ac(chips)',
 P_PATH='@t6g_mb_lib.t6g(sch_1):page140_i106@pure_quanta.schottky_ac(chips)',
 PATH='I106',
 DRAWING='@T6G_MB_LIB.T6G(SCH_1):PAGE343',
 PART_TYPE='SMLF',
 MATERIAL='IC',
 PHYS_PAGE='140',
 XY='(2800,9575)',
 ROT='1',
 VER='1',
 LOCATION='PD109',
 CDS_LIB='pure_quanta',
 CDS_PART_NAME='SCHOTTKY_AC-B340A-13-F,SMLF,IC,BC000340Z30',
 PART_NUMBER='BC000340Z30',
 VALUE='B340A-13-F',
 PRIM_FILE='./archive_libs/logical/schottky_ac/chips/chips.prt';

PART_NAME
 PD111 'SS15P3SM386A-SS15P3S-M3/86A,SMLF,IC,BC015P3SZ00':
 ROOM='HSC BOM1';

SECTION_NUMBER 1
 '@T6G_MB_LIB.T6G(SCH_1):PAGE267_I89@PURE_QUANTA.SS15P3SM386A(CHIPS)':
 C_PATH='@t6g_mb_lib.t6g(sch_1):page267_i89@pure_quanta.ss15p3sm386a(chips)',
 P_PATH='@t6g_mb_lib.t6g(sch_1):page262_i89@pure_quanta.ss15p3sm386a(chips)',
 PATH='I89',
 DRAWING='@T6G_MB_LIB.T6G(SCH_1):PAGE267',
 PART_TYPE='SMLF',
 MATERIAL='IC',
 PHYS_PAGE='262',
 XY='(-9175,4225)',
 ROT='1',
 VER='1',
 LOCATION='PD111',
 CDS_LIB='pure_quanta',
 CDS_PART_NAME='SS15P3SM386A-SS15P3S-M3/86A,SMLF,IC,BC015P3SZ00',
 ROOM='HSC BOM1',
 PART_NUMBER='BC015P3SZ00',
 VALUE='SS15P3S-M3/86A',
 PRIM_FILE='./archive_libs/logical/ss15p3sm386a/chips/chips.prt';

PART_NAME
 PD112 'SCHOTTKY_AC-B340A-13-F,SMLF,IC,BC000340Z30':;

SECTION_NUMBER 1
 '@T6G_MB_LIB.T6G(SCH_1):PAGE324_I74@PURE_QUANTA.SCHOTTKY_AC(CHIPS)':
 C_PATH='@t6g_mb_lib.t6g(sch_1):page324_i74@pure_quanta.schottky_ac(chips)',
 P_PATH='@t6g_mb_lib.t6g(sch_1):page146_i74@pure_quanta.schottky_ac(chips)',
 PATH='I74',
 DRAWING='@T6G_MB_LIB.T6G(SCH_1):PAGE324',
 PART_TYPE='SMLF',
 MATERIAL='IC',
 PHYS_PAGE='146',
 XY='(2700,1600)',
 ROT='1',
 VER='1',
 LOCATION='PD112',
 CDS_LIB='pure_quanta',
 CDS_PART_NAME='SCHOTTKY_AC-B340A-13-F,SMLF,IC,BC000340Z30',
 PART_NUMBER='BC000340Z30',
 VALUE='B340A-13-F',
 PRIM_FILE='./archive_libs/logical/schottky_ac/chips/chips.prt';

PART_NAME
 PD113 'SCHOTTKY_AC-B340A-13-F,SMLF,IC,BC000340Z30':;

SECTION_NUMBER 1
 '@T6G_MB_LIB.T6G(SCH_1):PAGE324_I50@PURE_QUANTA.SCHOTTKY_AC(CHIPS)':
 C_PATH='@t6g_mb_lib.t6g(sch_1):page324_i50@pure_quanta.schottky_ac(chips)',
 P_PATH='@t6g_mb_lib.t6g(sch_1):page146_i50@pure_quanta.schottky_ac(chips)',
 PATH='I50',
 DRAWING='@T6G_MB_LIB.T6G(SCH_1):PAGE324',
 PART_TYPE='SMLF',
 MATERIAL='IC',
 PHYS_PAGE='146',
 XY='(2700,-1100)',
 ROT='1',
 VER='1',
 LOCATION='PD113',
 CDS_LIB='pure_quanta',
 CDS_PART_NAME='SCHOTTKY_AC-B340A-13-F,SMLF,IC,BC000340Z30',
 PART_NUMBER='BC000340Z30',
 VALUE='B340A-13-F',
 PRIM_FILE='./archive_libs/logical/schottky_ac/chips/chips.prt';

PART_NAME
 PD114 'DIODE_TVS-SMF14A,SMLF,IC,BCSMF14AZ01':;

SECTION_NUMBER 1
 '@T6G_MB_LIB.T6G(SCH_1):PAGE324_I33@PURE_QUANTA.DIODE_TVS(CHIPS)':
 C_PATH='@t6g_mb_lib.t6g(sch_1):page324_i33@pure_quanta.diode_tvs(chips)',
 P_PATH='@t6g_mb_lib.t6g(sch_1):page146_i33@pure_quanta.diode_tvs(chips)',
 PATH='I33',
 DRAWING='@T6G_MB_LIB.T6G(SCH_1):PAGE324',
 PIN_NAMES_ROTATE='TRUE',
 PART_TYPE='SMLF',
 MATERIAL='IC',
 PHYS_PAGE='146',
 XY='(-900,1375)',
 ROT='1',
 VER='1',
 LOCATION='PD114',
 CDS_LIB='pure_quanta',
 CDS_PART_NAME='DIODE_TVS-SMF14A,SMLF,IC,BCSMF14AZ01',
 PART_NUMBER='BCSMF14AZ01',
 VALUE='SMF14A',
 PRIM_FILE='./archive_libs/logical/diode_tvs/chips/chips.prt';

PART_NAME
 PD115 'DIODE_TVS-SMF14A,SMLF,IC,BCSMF14AZ01':;

SECTION_NUMBER 1
 '@T6G_MB_LIB.T6G(SCH_1):PAGE350_I28@PURE_QUANTA.DIODE_TVS(CHIPS)':
 C_PATH='@t6g_mb_lib.t6g(sch_1):page350_i28@pure_quanta.diode_tvs(chips)',
 P_PATH='@t6g_mb_lib.t6g(sch_1):page152_i28@pure_quanta.diode_tvs(chips)',
 PATH='I28',
 DRAWING='@T6G_MB_LIB.T6G(SCH_1):PAGE350',
 PIN_NAMES_ROTATE='TRUE',
 PART_TYPE='SMLF',
 MATERIAL='IC',
 PHYS_PAGE='152',
 XY='(-50,15650)',
 ROT='1',
 VER='1',
 LOCATION='PD115',
 CDS_LIB='pure_quanta',
 CDS_PART_NAME='DIODE_TVS-SMF14A,SMLF,IC,BCSMF14AZ01',
 PART_NUMBER='BCSMF14AZ01',
 VALUE='SMF14A',
 PRIM_FILE='./archive_libs/logical/diode_tvs/chips/chips.prt';

PART_NAME
 PD116 'SCHOTTKY_AC-B340A-13-F,SMLF,IC,BC000340Z30':;

SECTION_NUMBER 1
 '@T6G_MB_LIB.T6G(SCH_1):PAGE350_I79@PURE_QUANTA.SCHOTTKY_AC(CHIPS)':
 C_PATH='@t6g_mb_lib.t6g(sch_1):page350_i79@pure_quanta.schottky_ac(chips)',
 P_PATH='@t6g_mb_lib.t6g(sch_1):page152_i79@pure_quanta.schottky_ac(chips)',
 PATH='I79',
 DRAWING='@T6G_MB_LIB.T6G(SCH_1):PAGE350',
 PART_TYPE='SMLF',
 MATERIAL='IC',
 PHYS_PAGE='152',
 XY='(3500,15850)',
 ROT='1',
 VER='1',
 LOCATION='PD116',
 CDS_LIB='pure_quanta',
 CDS_PART_NAME='SCHOTTKY_AC-B340A-13-F,SMLF,IC,BC000340Z30',
 PART_NUMBER='BC000340Z30',
 VALUE='B340A-13-F',
 PRIM_FILE='./archive_libs/logical/schottky_ac/chips/chips.prt';

PART_NAME
 PJ1 'CONN3_210HP1030BR1-CONN3_210-HP1-030BR1,THLF,IO,DFA':;

SECTION_NUMBER 1
 '@T6G_MB_LIB.T6G(SCH_1):PAGE168_I143@PURE_QUANTA.CONN3_210HP1030BR1(CHIPS)':
 C_PATH='@t6g_mb_lib.t6g(sch_1):page168_i143@pure_quanta.conn3_210hp1030br1(chip~
s)',
 P_PATH='@t6g_mb_lib.t6g(sch_1):page193_i143@pure_quanta.conn3_210hp1030br1(chip~
s)',
 PATH='I143',
 DRAWING='@T6G_MB_LIB.T6G(SCH_1):PAGE168',
 PART_TYPE='THLF',
 MATERIAL='IO',
 PHYS_PAGE='193',
 XY='(-6150,4675)',
 ROT='2',
 VER='1',
 LOCATION='PJ1',
 CDS_LIB='pure_quanta',
 CDS_PART_NAME='CONN3_210HP1030BR1-CONN3_210-HP1-030BR1,THLF,IO,DFA',
 PART_NUMBER='DFHD03MS213',
 VALUE='CONN3_210-HP1-030BR1',
 PRIM_FILE='./archive_libs/logical/conn3_210hp1030br1/chips/chips.prt';

PART_NAME
 PJ09_P0_N 'Q_SHORT_SM-EMPTY,SHORT16':;

SECTION_NUMBER 1
 '@T6G_MB_LIB.T6G(SCH_1):PAGE475_I215@PURE_QUANTA.Q_SHORT(CHIPS)':
 C_PATH='@t6g_mb_lib.t6g(sch_1):page475_i215@pure_quanta.q_short(chips)',
 P_PATH='@t6g_mb_lib.t6g(sch_1):page362_i215@pure_quanta.q_short(chips)',
 PATH='I215',
 DRAWING='@T6G_MB_LIB.T6G(SCH_1):PAGE475',
 SEC_TYPE='SM',
 MATERIAL='EMPTY',
 PHYS_PAGE='362',
 XY='(-10550,5500)',
 ROT='0',
 VER='1',
 PACK_TYPE='SM',
 LOCATION='PJ09_P0_N',
 SEC='1',
 CDS_LIB='pure_quanta',
 CDS_PART_NAME='Q_SHORT_SM-EMPTY,SHORT16',
 PART_NUMBER='SHORT16',
 PRIM_FILE='./archive_libs/logical/q_short/chips/chips.prt';

PART_NAME
 PJ09_P0_P 'Q_SHORT_SM-EMPTY,SHORT16':;

SECTION_NUMBER 1
 '@T6G_MB_LIB.T6G(SCH_1):PAGE475_I214@PURE_QUANTA.Q_SHORT(CHIPS)':
 C_PATH='@t6g_mb_lib.t6g(sch_1):page475_i214@pure_quanta.q_short(chips)',
 P_PATH='@t6g_mb_lib.t6g(sch_1):page362_i214@pure_quanta.q_short(chips)',
 PATH='I214',
 DRAWING='@T6G_MB_LIB.T6G(SCH_1):PAGE475',
 SEC_TYPE='SM',
 MATERIAL='EMPTY',
 PHYS_PAGE='362',
 XY='(-10550,5875)',
 ROT='0',
 VER='1',
 PACK_TYPE='SM',
 LOCATION='PJ09_P0_P',
 SEC='1',
 CDS_LIB='pure_quanta',
 CDS_PART_NAME='Q_SHORT_SM-EMPTY,SHORT16',
 PART_NUMBER='SHORT16',
 PRIM_FILE='./archive_libs/logical/q_short/chips/chips.prt';

PART_NAME
 PJ09_P1_N 'Q_SHORT_SM-EMPTY,SHORT16':;

SECTION_NUMBER 1
 '@T6G_MB_LIB.T6G(SCH_1):PAGE477_I96@PURE_QUANTA.Q_SHORT(CHIPS)':
 C_PATH='@t6g_mb_lib.t6g(sch_1):page477_i96@pure_quanta.q_short(chips)',
 P_PATH='@t6g_mb_lib.t6g(sch_1):page364_i96@pure_quanta.q_short(chips)',
 PATH='I96',
 DRAWING='@T6G_MB_LIB.T6G(SCH_1):PAGE477',
 MATERIAL='EMPTY',
 PHYS_PAGE='364',
 XY='(-7750,3800)',
 ROT='0',
 VER='1',
 PACK_TYPE='SM',
 LOCATION='PJ09_P1_N',
 CDS_LIB='pure_quanta',
 CDS_PART_NAME='Q_SHORT_SM-EMPTY,SHORT16',
 PART_NUMBER='SHORT16',
 PRIM_FILE='./archive_libs/logical/q_short/chips/chips.prt';

PART_NAME
 PJ09_P1_P 'Q_SHORT_SM-EMPTY,SHORT16':;

SECTION_NUMBER 1
 '@T6G_MB_LIB.T6G(SCH_1):PAGE477_I95@PURE_QUANTA.Q_SHORT(CHIPS)':
 C_PATH='@t6g_mb_lib.t6g(sch_1):page477_i95@pure_quanta.q_short(chips)',
 P_PATH='@t6g_mb_lib.t6g(sch_1):page364_i95@pure_quanta.q_short(chips)',
 PATH='I95',
 DRAWING='@T6G_MB_LIB.T6G(SCH_1):PAGE477',
 MATERIAL='EMPTY',
 PHYS_PAGE='364',
 XY='(-7750,4175)',
 ROT='0',
 VER='1',
 PACK_TYPE='SM',
 LOCATION='PJ09_P1_P',
 CDS_LIB='pure_quanta',
 CDS_PART_NAME='Q_SHORT_SM-EMPTY,SHORT16',
 PART_NUMBER='SHORT16',
 PRIM_FILE='./archive_libs/logical/q_short/chips/chips.prt';

PART_NAME
 PJ38 'SCONN21_9193031121LF-SCONN21_91930-31121LF,SMLF,IOA':
 ROOM='HSC BOM2';

SECTION_NUMBER 1
 '@T6G_MB_LIB.T6G(SCH_1):PAGE371_I42@PURE_QUANTA.SCONN21_9193031121LF(CHIPS)':
 C_PATH='@t6g_mb_lib.t6g(sch_1):page371_i42@pure_quanta.sconn21_9193031121lf(chi~
ps)',
 P_PATH='@t6g_mb_lib.t6g(sch_1):page267_i42@pure_quanta.sconn21_9193031121lf(chi~
ps)',
 PATH='I42',
 DRAWING='@T6G_MB_LIB.T6G(SCH_1):PAGE371',
 SEC_TYPE='',
 PART_TYPE='SMLF',
 MATERIAL='IO',
 PHYS_PAGE='267',
 XY='(-1700,4025)',
 ROT='2',
 VER='1',
 LOCATION='PJ38',
 SEC='1',
 CDS_LIB='pure_quanta',
 CDS_PART_NAME='SCONN21_9193031121LF-SCONN21_91930-31121LF,SMLF,IOA',
 ROOM='HSC BOM2',
 PART_NUMBER='DFHS21FS003',
 VALUE='SCONN21_91930-31121LF',
 PRIM_FILE='./archive_libs/logical/sconn21_9193031121lf/chips/chips.prt';

PART_NAME
 PL7 'Q_INDUCTOR4P_14-150NH,SMLF,IND,CV+15^0TZ04':;

SECTION_NUMBER 1
 '@T6G_MB_LIB.T6G(SCH_1):PAGE178_I38@PURE_QUANTA.Q_INDUCTOR4P_14(CHIPS)':
 C_PATH='@t6g_mb_lib.t6g(sch_1):page178_i38@pure_quanta.q_inductor4p_14(chips)',
 P_PATH='@t6g_mb_lib.t6g(sch_1):page203_i38@pure_quanta.q_inductor4p_14(chips)',
 PATH='I38',
 DRAWING='@T6G_MB_LIB.T6G(SCH_1):PAGE178',
 PART_TYPE='SMLF',
 MATERIAL='IND',
 PHYS_PAGE='203',
 XY='(6300,2100)',
 ROT='0',
 VER='1',
 LOCATION='PL7',
 CDS_LIB='pure_quanta',
 CDS_PART_NAME='Q_INDUCTOR4P_14-150NH,SMLF,IND,CV+15^0TZ04',
 PART_NUMBER='CV+15^0TZ04',
 VALUE='150NH',
 PRIM_FILE='./archive_libs/logical/q_inductor4p_14/chips/chips.prt';

PART_NAME
 PL8 'Q_INDUCTOR4P_14-150NH,SMLF,IND,CV+15^0TZ04':;

SECTION_NUMBER 1
 '@T6G_MB_LIB.T6G(SCH_1):PAGE188_I53@PURE_QUANTA.Q_INDUCTOR4P_14(CHIPS)':
 C_PATH='@t6g_mb_lib.t6g(sch_1):page188_i53@pure_quanta.q_inductor4p_14(chips)',
 P_PATH='@t6g_mb_lib.t6g(sch_1):page213_i53@pure_quanta.q_inductor4p_14(chips)',
 PATH='I53',
 DRAWING='@T6G_MB_LIB.T6G(SCH_1):PAGE188',
 PART_TYPE='SMLF',
 MATERIAL='IND',
 PHYS_PAGE='213',
 XY='(-2425,1825)',
 ROT='0',
 VER='1',
 LOCATION='PL8',
 CDS_LIB='pure_quanta',
 CDS_PART_NAME='Q_INDUCTOR4P_14-150NH,SMLF,IND,CV+15^0TZ04',
 PART_NUMBER='CV+15^0TZ04',
 VALUE='150NH',
 PRIM_FILE='./archive_libs/logical/q_inductor4p_14/chips/chips.prt';

PART_NAME
 PL9 'Q_INDUCTOR_SMLF-120NH/69A,IND,CV+12^0EZ03':;

SECTION_NUMBER 1
 '@T6G_MB_LIB.T6G(SCH_1):PAGE178_I36@PURE_QUANTA.Q_INDUCTOR(CHIPS)':
 C_PATH='@t6g_mb_lib.t6g(sch_1):page178_i36@pure_quanta.q_inductor(chips)',
 P_PATH='@t6g_mb_lib.t6g(sch_1):page203_i36@pure_quanta.q_inductor(chips)',
 PATH='I36',
 DRAWING='@T6G_MB_LIB.T6G(SCH_1):PAGE178',
 MATERIAL='IND',
 PHYS_PAGE='203',
 XY='(5325,2000)',
 ROT='2',
 VER='1',
 PACK_TYPE='SMLF',
 LOCATION='PL9',
 CDS_LIB='pure_quanta',
 CDS_PART_NAME='Q_INDUCTOR_SMLF-120NH/69A,IND,CV+12^0EZ03',
 PART_NUMBER='CV+12^0EZ03',
 VALUE='120NH/69A',
 PRIM_FILE='./archive_libs/logical/q_inductor/chips/chips.prt';

PART_NAME
 PL10 'Q_INDUCTOR4P_14-150NH,SMLF,IND,CV+15^0TZ04':;

SECTION_NUMBER 1
 '@T6G_MB_LIB.T6G(SCH_1):PAGE176_I62@PURE_QUANTA.Q_INDUCTOR4P_14(CHIPS)':
 C_PATH='@t6g_mb_lib.t6g(sch_1):page176_i62@pure_quanta.q_inductor4p_14(chips)',
 P_PATH='@t6g_mb_lib.t6g(sch_1):page201_i62@pure_quanta.q_inductor4p_14(chips)',
 PATH='I62',
 DRAWING='@T6G_MB_LIB.T6G(SCH_1):PAGE176',
 PART_TYPE='SMLF',
 MATERIAL='IND',
 PHYS_PAGE='201',
 XY='(-4450,4000)',
 ROT='0',
 VER='1',
 LOCATION='PL10',
 CDS_LIB='pure_quanta',
 CDS_PART_NAME='Q_INDUCTOR4P_14-150NH,SMLF,IND,CV+15^0TZ04',
 PART_NUMBER='CV+15^0TZ04',
 VALUE='150NH',
 PRIM_FILE='./archive_libs/logical/q_inductor4p_14/chips/chips.prt';

PART_NAME
 PL11 'Q_INDUCTOR4P_14-150NH,SMLF,IND,CV+15^0TZ04':;

SECTION_NUMBER 1
 '@T6G_MB_LIB.T6G(SCH_1):PAGE176_I46@PURE_QUANTA.Q_INDUCTOR4P_14(CHIPS)':
 C_PATH='@t6g_mb_lib.t6g(sch_1):page176_i46@pure_quanta.q_inductor4p_14(chips)',
 P_PATH='@t6g_mb_lib.t6g(sch_1):page201_i46@pure_quanta.q_inductor4p_14(chips)',
 PATH='I46',
 DRAWING='@T6G_MB_LIB.T6G(SCH_1):PAGE176',
 PART_TYPE='SMLF',
 MATERIAL='IND',
 PHYS_PAGE='201',
 XY='(-4150,1050)',
 ROT='0',
 VER='1',
 LOCATION='PL11',
 CDS_LIB='pure_quanta',
 CDS_PART_NAME='Q_INDUCTOR4P_14-150NH,SMLF,IND,CV+15^0TZ04',
 PART_NUMBER='CV+15^0TZ04',
 VALUE='150NH',
 PRIM_FILE='./archive_libs/logical/q_inductor4p_14/chips/chips.prt';

PART_NAME
 PL12 'Q_INDUCTOR_SMLF-50NH/86A,IND,CVA50^0MZ09':;

SECTION_NUMBER 1
 '@T6G_MB_LIB.T6G(SCH_1):PAGE176_I83@PURE_QUANTA.Q_INDUCTOR(CHIPS)':
 C_PATH='@t6g_mb_lib.t6g(sch_1):page176_i83@pure_quanta.q_inductor(chips)',
 P_PATH='@t6g_mb_lib.t6g(sch_1):page201_i83@pure_quanta.q_inductor(chips)',
 PATH='I83',
 DRAWING='@T6G_MB_LIB.T6G(SCH_1):PAGE176',
 MATERIAL='IND',
 PHYS_PAGE='201',
 XY='(-3625,5300)',
 ROT='0',
 VER='1',
 PACK_TYPE='SMLF',
 LOCATION='PL12',
 CDS_LIB='pure_quanta',
 CDS_PART_NAME='Q_INDUCTOR_SMLF-50NH/86A,IND,CVA50^0MZ09',
 PART_NUMBER='CVA50^0MZ09',
 VALUE='50NH/86A',
 PRIM_FILE='./archive_libs/logical/q_inductor/chips/chips.prt';

PART_NAME
 PL13 'Q_INDUCTOR4P_14-150NH,SMLF,IND,CV+15^0TZ04':;

SECTION_NUMBER 1
 '@T6G_MB_LIB.T6G(SCH_1):PAGE177_I42@PURE_QUANTA.Q_INDUCTOR4P_14(CHIPS)':
 C_PATH='@t6g_mb_lib.t6g(sch_1):page177_i42@pure_quanta.q_inductor4p_14(chips)',
 P_PATH='@t6g_mb_lib.t6g(sch_1):page202_i42@pure_quanta.q_inductor4p_14(chips)',
 PATH='I42',
 DRAWING='@T6G_MB_LIB.T6G(SCH_1):PAGE177',
 PART_TYPE='SMLF',
 MATERIAL='IND',
 PHYS_PAGE='202',
 XY='(6150,1400)',
 ROT='0',
 VER='1',
 LOCATION='PL13',
 CDS_LIB='pure_quanta',
 CDS_PART_NAME='Q_INDUCTOR4P_14-150NH,SMLF,IND,CV+15^0TZ04',
 PART_NUMBER='CV+15^0TZ04',
 VALUE='150NH',
 PRIM_FILE='./archive_libs/logical/q_inductor4p_14/chips/chips.prt';

PART_NAME
 PL14 'Q_INDUCTOR4P_14-150NH,SMLF,IND,CV+15^0TZ04':;

SECTION_NUMBER 1
 '@T6G_MB_LIB.T6G(SCH_1):PAGE177_I64@PURE_QUANTA.Q_INDUCTOR4P_14(CHIPS)':
 C_PATH='@t6g_mb_lib.t6g(sch_1):page177_i64@pure_quanta.q_inductor4p_14(chips)',
 P_PATH='@t6g_mb_lib.t6g(sch_1):page202_i64@pure_quanta.q_inductor4p_14(chips)',
 PATH='I64',
 DRAWING='@T6G_MB_LIB.T6G(SCH_1):PAGE177',
 PART_TYPE='SMLF',
 MATERIAL='IND',
 PHYS_PAGE='202',
 XY='(6475,4225)',
 ROT='0',
 VER='1',
 LOCATION='PL14',
 CDS_LIB='pure_quanta',
 CDS_PART_NAME='Q_INDUCTOR4P_14-150NH,SMLF,IND,CV+15^0TZ04',
 PART_NUMBER='CV+15^0TZ04',
 VALUE='150NH',
 PRIM_FILE='./archive_libs/logical/q_inductor4p_14/chips/chips.prt';

PART_NAME
 PL15 'Q_INDUCTOR4P_14-150NH,SMLF,IND,CV+15^0TZ04':;

SECTION_NUMBER 1
 '@T6G_MB_LIB.T6G(SCH_1):PAGE178_I63@PURE_QUANTA.Q_INDUCTOR4P_14(CHIPS)':
 C_PATH='@t6g_mb_lib.t6g(sch_1):page178_i63@pure_quanta.q_inductor4p_14(chips)',
 P_PATH='@t6g_mb_lib.t6g(sch_1):page203_i63@pure_quanta.q_inductor4p_14(chips)',
 PATH='I63',
 DRAWING='@T6G_MB_LIB.T6G(SCH_1):PAGE178',
 PART_TYPE='SMLF',
 MATERIAL='IND',
 PHYS_PAGE='203',
 XY='(6300,4750)',
 ROT='0',
 VER='1',
 LOCATION='PL15',
 CDS_LIB='pure_quanta',
 CDS_PART_NAME='Q_INDUCTOR4P_14-150NH,SMLF,IND,CV+15^0TZ04',
 PART_NUMBER='CV+15^0TZ04',
 VALUE='150NH',
 PRIM_FILE='./archive_libs/logical/q_inductor4p_14/chips/chips.prt';

PART_NAME
 PL16 'Q_INDUCTOR_SMLF-0.22UH/33A,IND,CV+22Y0EZ00':;

SECTION_NUMBER 1
 '@T6G_MB_LIB.T6G(SCH_1):PAGE181_I43@PURE_QUANTA.Q_INDUCTOR(CHIPS)':
 C_PATH='@t6g_mb_lib.t6g(sch_1):page181_i43@pure_quanta.q_inductor(chips)',
 P_PATH='@t6g_mb_lib.t6g(sch_1):page206_i43@pure_quanta.q_inductor(chips)',
 PATH='I43',
 DRAWING='@T6G_MB_LIB.T6G(SCH_1):PAGE181',
 MATERIAL='IND',
 PHYS_PAGE='206',
 XY='(-7300,2400)',
 ROT='2',
 VER='1',
 PACK_TYPE='SMLF',
 LOCATION='PL16',
 CDS_LIB='pure_quanta',
 CDS_PART_NAME='Q_INDUCTOR_SMLF-0.22UH/33A,IND,CV+22Y0EZ00',
 PART_NUMBER='CV+22Y0EZ00',
 VALUE='0.22UH/33A',
 PRIM_FILE='./archive_libs/logical/q_inductor/chips/chips.prt';

PART_NAME
 PL17 'Q_INDUCTOR4P_14-150NH,SMLF,IND,CV+15^0TZ04':;

SECTION_NUMBER 1
 '@T6G_MB_LIB.T6G(SCH_1):PAGE180_I64@PURE_QUANTA.Q_INDUCTOR4P_14(CHIPS)':
 C_PATH='@t6g_mb_lib.t6g(sch_1):page180_i64@pure_quanta.q_inductor4p_14(chips)',
 P_PATH='@t6g_mb_lib.t6g(sch_1):page205_i64@pure_quanta.q_inductor4p_14(chips)',
 PATH='I64',
 DRAWING='@T6G_MB_LIB.T6G(SCH_1):PAGE180',
 PART_TYPE='SMLF',
 MATERIAL='IND',
 PHYS_PAGE='205',
 XY='(6050,4850)',
 ROT='0',
 VER='1',
 LOCATION='PL17',
 CDS_LIB='pure_quanta',
 CDS_PART_NAME='Q_INDUCTOR4P_14-150NH,SMLF,IND,CV+15^0TZ04',
 PART_NUMBER='CV+15^0TZ04',
 VALUE='150NH',
 PRIM_FILE='./archive_libs/logical/q_inductor4p_14/chips/chips.prt';

PART_NAME
 PL18 'Q_INDUCTOR4P_14-150NH,SMLF,IND,CV+15^0TZ04':;

SECTION_NUMBER 1
 '@T6G_MB_LIB.T6G(SCH_1):PAGE180_I40@PURE_QUANTA.Q_INDUCTOR4P_14(CHIPS)':
 C_PATH='@t6g_mb_lib.t6g(sch_1):page180_i40@pure_quanta.q_inductor4p_14(chips)',
 P_PATH='@t6g_mb_lib.t6g(sch_1):page205_i40@pure_quanta.q_inductor4p_14(chips)',
 PATH='I40',
 DRAWING='@T6G_MB_LIB.T6G(SCH_1):PAGE180',
 PART_TYPE='SMLF',
 MATERIAL='IND',
 PHYS_PAGE='205',
 XY='(6225,2050)',
 ROT='0',
 VER='1',
 LOCATION='PL18',
 CDS_LIB='pure_quanta',
 CDS_PART_NAME='Q_INDUCTOR4P_14-150NH,SMLF,IND,CV+15^0TZ04',
 PART_NUMBER='CV+15^0TZ04',
 VALUE='150NH',
 PRIM_FILE='./archive_libs/logical/q_inductor4p_14/chips/chips.prt';

PART_NAME
 PL19 'Q_INDUCTOR_SMLF-50NH/86A,IND,CVA50^0MZ09':;

SECTION_NUMBER 1
 '@T6G_MB_LIB.T6G(SCH_1):PAGE180_I69@PURE_QUANTA.Q_INDUCTOR(CHIPS)':
 C_PATH='@t6g_mb_lib.t6g(sch_1):page180_i69@pure_quanta.q_inductor(chips)',
 P_PATH='@t6g_mb_lib.t6g(sch_1):page205_i69@pure_quanta.q_inductor(chips)',
 PATH='I69',
 DRAWING='@T6G_MB_LIB.T6G(SCH_1):PAGE180',
 MATERIAL='IND',
 PHYS_PAGE='205',
 XY='(6075,6150)',
 ROT='0',
 VER='1',
 PACK_TYPE='SMLF',
 LOCATION='PL19',
 CDS_LIB='pure_quanta',
 CDS_PART_NAME='Q_INDUCTOR_SMLF-50NH/86A,IND,CVA50^0MZ09',
 PART_NUMBER='CVA50^0MZ09',
 VALUE='50NH/86A',
 PRIM_FILE='./archive_libs/logical/q_inductor/chips/chips.prt';

PART_NAME
 PL20 'Q_INDUCTOR4P_14-150NH,SMLF,IND,CV+15^0TZ04':;

SECTION_NUMBER 1
 '@T6G_MB_LIB.T6G(SCH_1):PAGE181_I42@PURE_QUANTA.Q_INDUCTOR4P_14(CHIPS)':
 C_PATH='@t6g_mb_lib.t6g(sch_1):page181_i42@pure_quanta.q_inductor4p_14(chips)',
 P_PATH='@t6g_mb_lib.t6g(sch_1):page206_i42@pure_quanta.q_inductor4p_14(chips)',
 PATH='I42',
 DRAWING='@T6G_MB_LIB.T6G(SCH_1):PAGE181',
 PART_TYPE='SMLF',
 MATERIAL='IND',
 PHYS_PAGE='206',
 XY='(-6275,2500)',
 ROT='0',
 VER='1',
 LOCATION='PL20',
 CDS_LIB='pure_quanta',
 CDS_PART_NAME='Q_INDUCTOR4P_14-150NH,SMLF,IND,CV+15^0TZ04',
 PART_NUMBER='CV+15^0TZ04',
 VALUE='150NH',
 PRIM_FILE='./archive_libs/logical/q_inductor4p_14/chips/chips.prt';

PART_NAME
 PL21 'Q_INDUCTOR4P_14-150NH,SMLF,IND,CV+15^0TZ04':;

SECTION_NUMBER 1
 '@T6G_MB_LIB.T6G(SCH_1):PAGE181_I61@PURE_QUANTA.Q_INDUCTOR4P_14(CHIPS)':
 C_PATH='@t6g_mb_lib.t6g(sch_1):page181_i61@pure_quanta.q_inductor4p_14(chips)',
 P_PATH='@t6g_mb_lib.t6g(sch_1):page206_i61@pure_quanta.q_inductor4p_14(chips)',
 PATH='I61',
 DRAWING='@T6G_MB_LIB.T6G(SCH_1):PAGE181',
 PART_TYPE='SMLF',
 MATERIAL='IND',
 PHYS_PAGE='206',
 XY='(-6025,5300)',
 ROT='0',
 VER='1',
 LOCATION='PL21',
 CDS_LIB='pure_quanta',
 CDS_PART_NAME='Q_INDUCTOR4P_14-150NH,SMLF,IND,CV+15^0TZ04',
 PART_NUMBER='CV+15^0TZ04',
 VALUE='150NH',
 PRIM_FILE='./archive_libs/logical/q_inductor4p_14/chips/chips.prt';

PART_NAME
 PL22 'Q_INDUCTOR_SMLF-90NH/155A,IND,CVA90^0KZ13':;

SECTION_NUMBER 1
 '@T6G_MB_LIB.T6G(SCH_1):PAGE183_I52@PURE_QUANTA.Q_INDUCTOR(CHIPS)':
 C_PATH='@t6g_mb_lib.t6g(sch_1):page183_i52@pure_quanta.q_inductor(chips)',
 P_PATH='@t6g_mb_lib.t6g(sch_1):page208_i52@pure_quanta.q_inductor(chips)',
 PATH='I52',
 DRAWING='@T6G_MB_LIB.T6G(SCH_1):PAGE183',
 MATERIAL='IND',
 PHYS_PAGE='208',
 XY='(-3375,1525)',
 ROT='0',
 VER='1',
 PACK_TYPE='SMLF',
 LOCATION='PL22',
 CDS_LIB='pure_quanta',
 CDS_PART_NAME='Q_INDUCTOR_SMLF-90NH/155A,IND,CVA90^0KZ13',
 PART_NUMBER='CVA90^0KZ13',
 VALUE='90NH/155A',
 PRIM_FILE='./archive_libs/logical/q_inductor/chips/chips.prt';

PART_NAME
 PL23 'Q_INDUCTOR_SMLF-90NH/155A,IND,CVA90^0KZ13':;

SECTION_NUMBER 1
 '@T6G_MB_LIB.T6G(SCH_1):PAGE183_I73@PURE_QUANTA.Q_INDUCTOR(CHIPS)':
 C_PATH='@t6g_mb_lib.t6g(sch_1):page183_i73@pure_quanta.q_inductor(chips)',
 P_PATH='@t6g_mb_lib.t6g(sch_1):page208_i73@pure_quanta.q_inductor(chips)',
 PATH='I73',
 DRAWING='@T6G_MB_LIB.T6G(SCH_1):PAGE183',
 MATERIAL='IND',
 PHYS_PAGE='208',
 XY='(-3275,4450)',
 ROT='0',
 VER='1',
 PACK_TYPE='SMLF',
 LOCATION='PL23',
 CDS_LIB='pure_quanta',
 CDS_PART_NAME='Q_INDUCTOR_SMLF-90NH/155A,IND,CVA90^0KZ13',
 PART_NUMBER='CVA90^0KZ13',
 VALUE='90NH/155A',
 PRIM_FILE='./archive_libs/logical/q_inductor/chips/chips.prt';

PART_NAME
 PL24 'Q_INDUCTOR_SMLF-100NH/16A,IND,CV+10G0MZ04':;

SECTION_NUMBER 1
 '@T6G_MB_LIB.T6G(SCH_1):PAGE183_I78@PURE_QUANTA.Q_INDUCTOR(CHIPS)':
 C_PATH='@t6g_mb_lib.t6g(sch_1):page183_i78@pure_quanta.q_inductor(chips)',
 P_PATH='@t6g_mb_lib.t6g(sch_1):page208_i78@pure_quanta.q_inductor(chips)',
 PATH='I78',
 DRAWING='@T6G_MB_LIB.T6G(SCH_1):PAGE183',
 MATERIAL='IND',
 PHYS_PAGE='208',
 XY='(-2900,5525)',
 ROT='0',
 VER='1',
 PACK_TYPE='SMLF',
 LOCATION='PL24',
 CDS_LIB='pure_quanta',
 CDS_PART_NAME='Q_INDUCTOR_SMLF-100NH/16A,IND,CV+10G0MZ04',
 PART_NUMBER='CV+10G0MZ04',
 VALUE='100NH/16A',
 PRIM_FILE='./archive_libs/logical/q_inductor/chips/chips.prt';

PART_NAME
 PL26 'Q_INDUCTOR_SMLF-BLM18SN220TN1D/8000MA,IND,CX220TN1A':;

SECTION_NUMBER 1
 '@T6G_MB_LIB.T6G(SCH_1):PAGE201_I4@PURE_QUANTA.Q_INDUCTOR(CHIPS)':
 C_PATH='@t6g_mb_lib.t6g(sch_1):page201_i4@pure_quanta.q_inductor(chips)',
 P_PATH='@t6g_mb_lib.t6g(sch_1):page226_i4@pure_quanta.q_inductor(chips)',
 PATH='I4',
 DRAWING='@T6G_MB_LIB.T6G(SCH_1):PAGE201',
 MATERIAL='IND',
 PHYS_PAGE='226',
 XY='(-8450,4800)',
 ROT='0',
 VER='1',
 PACK_TYPE='SMLF',
 LOCATION='PL26',
 CDS_LIB='pure_quanta',
 CDS_PART_NAME='Q_INDUCTOR_SMLF-BLM18SN220TN1D/8000MA,IND,CX220TN1A',
 PART_NUMBER='CX220TN1001',
 VALUE='BLM18SN220TN1D/8000MA',
 PRIM_FILE='./archive_libs/logical/q_inductor/chips/chips.prt';

PART_NAME
 PL27 'Q_INDUCTOR_SMLF-120NH/69A,IND,CV+12^0EZ03':;

SECTION_NUMBER 1
 '@T6G_MB_LIB.T6G(SCH_1):PAGE188_I51@PURE_QUANTA.Q_INDUCTOR(CHIPS)':
 C_PATH='@t6g_mb_lib.t6g(sch_1):page188_i51@pure_quanta.q_inductor(chips)',
 P_PATH='@t6g_mb_lib.t6g(sch_1):page213_i51@pure_quanta.q_inductor(chips)',
 PATH='I51',
 DRAWING='@T6G_MB_LIB.T6G(SCH_1):PAGE188',
 MATERIAL='IND',
 PHYS_PAGE='213',
 XY='(-3400,1725)',
 ROT='0',
 VER='1',
 PACK_TYPE='SMLF',
 LOCATION='PL27',
 CDS_LIB='pure_quanta',
 CDS_PART_NAME='Q_INDUCTOR_SMLF-120NH/69A,IND,CV+12^0EZ03',
 PART_NUMBER='CV+12^0EZ03',
 VALUE='120NH/69A',
 PRIM_FILE='./archive_libs/logical/q_inductor/chips/chips.prt';

PART_NAME
 PL28 'Q_INDUCTOR4P_14-150NH,SMLF,IND,CV+15^0TZ04':;

SECTION_NUMBER 1
 '@T6G_MB_LIB.T6G(SCH_1):PAGE186_I90@PURE_QUANTA.Q_INDUCTOR4P_14(CHIPS)':
 C_PATH='@t6g_mb_lib.t6g(sch_1):page186_i90@pure_quanta.q_inductor4p_14(chips)',
 P_PATH='@t6g_mb_lib.t6g(sch_1):page211_i90@pure_quanta.q_inductor4p_14(chips)',
 PATH='I90',
 DRAWING='@T6G_MB_LIB.T6G(SCH_1):PAGE186',
 PART_TYPE='SMLF',
 MATERIAL='IND',
 PHYS_PAGE='211',
 XY='(-3325,4325)',
 ROT='0',
 VER='1',
 LOCATION='PL28',
 CDS_LIB='pure_quanta',
 CDS_PART_NAME='Q_INDUCTOR4P_14-150NH,SMLF,IND,CV+15^0TZ04',
 PART_NUMBER='CV+15^0TZ04',
 VALUE='150NH',
 PRIM_FILE='./archive_libs/logical/q_inductor4p_14/chips/chips.prt';

PART_NAME
 PL29 'Q_INDUCTOR4P_14-150NH,SMLF,IND,CV+15^0TZ04':;

SECTION_NUMBER 1
 '@T6G_MB_LIB.T6G(SCH_1):PAGE186_I56@PURE_QUANTA.Q_INDUCTOR4P_14(CHIPS)':
 C_PATH='@t6g_mb_lib.t6g(sch_1):page186_i56@pure_quanta.q_inductor4p_14(chips)',
 P_PATH='@t6g_mb_lib.t6g(sch_1):page211_i56@pure_quanta.q_inductor4p_14(chips)',
 PATH='I56',
 DRAWING='@T6G_MB_LIB.T6G(SCH_1):PAGE186',
 PART_TYPE='SMLF',
 MATERIAL='IND',
 PHYS_PAGE='211',
 XY='(-2875,1575)',
 ROT='0',
 VER='1',
 LOCATION='PL29',
 CDS_LIB='pure_quanta',
 CDS_PART_NAME='Q_INDUCTOR4P_14-150NH,SMLF,IND,CV+15^0TZ04',
 PART_NUMBER='CV+15^0TZ04',
 VALUE='150NH',
 PRIM_FILE='./archive_libs/logical/q_inductor4p_14/chips/chips.prt';

PART_NAME
 PL30 'Q_INDUCTOR_SMLF-50NH/86A,IND,CVA50^0MZ09':;

SECTION_NUMBER 1
 '@T6G_MB_LIB.T6G(SCH_1):PAGE186_I73@PURE_QUANTA.Q_INDUCTOR(CHIPS)':
 C_PATH='@t6g_mb_lib.t6g(sch_1):page186_i73@pure_quanta.q_inductor(chips)',
 P_PATH='@t6g_mb_lib.t6g(sch_1):page211_i73@pure_quanta.q_inductor(chips)',
 PATH='I73',
 DRAWING='@T6G_MB_LIB.T6G(SCH_1):PAGE186',
 MATERIAL='IND',
 PHYS_PAGE='211',
 XY='(-2900,5525)',
 ROT='0',
 VER='1',
 PACK_TYPE='SMLF',
 LOCATION='PL30',
 CDS_LIB='pure_quanta',
 CDS_PART_NAME='Q_INDUCTOR_SMLF-50NH/86A,IND,CVA50^0MZ09',
 PART_NUMBER='CVA50^0MZ09',
 VALUE='50NH/86A',
 PRIM_FILE='./archive_libs/logical/q_inductor/chips/chips.prt';

PART_NAME
 PL31 'Q_INDUCTOR4P_14-150NH,SMLF,IND,CV+15^0TZ04':;

SECTION_NUMBER 1
 '@T6G_MB_LIB.T6G(SCH_1):PAGE187_I67@PURE_QUANTA.Q_INDUCTOR4P_14(CHIPS)':
 C_PATH='@t6g_mb_lib.t6g(sch_1):page187_i67@pure_quanta.q_inductor4p_14(chips)',
 P_PATH='@t6g_mb_lib.t6g(sch_1):page212_i67@pure_quanta.q_inductor4p_14(chips)',
 PATH='I67',
 DRAWING='@T6G_MB_LIB.T6G(SCH_1):PAGE187',
 PART_TYPE='SMLF',
 MATERIAL='IND',
 PHYS_PAGE='212',
 XY='(-2450,4750)',
 ROT='0',
 VER='1',
 LOCATION='PL31',
 CDS_LIB='pure_quanta',
 CDS_PART_NAME='Q_INDUCTOR4P_14-150NH,SMLF,IND,CV+15^0TZ04',
 PART_NUMBER='CV+15^0TZ04',
 VALUE='150NH',
 PRIM_FILE='./archive_libs/logical/q_inductor4p_14/chips/chips.prt';

PART_NAME
 PL32 'Q_INDUCTOR4P_14-150NH,SMLF,IND,CV+15^0TZ04':;

SECTION_NUMBER 1
 '@T6G_MB_LIB.T6G(SCH_1):PAGE187_I53@PURE_QUANTA.Q_INDUCTOR4P_14(CHIPS)':
 C_PATH='@t6g_mb_lib.t6g(sch_1):page187_i53@pure_quanta.q_inductor4p_14(chips)',
 P_PATH='@t6g_mb_lib.t6g(sch_1):page212_i53@pure_quanta.q_inductor4p_14(chips)',
 PATH='I53',
 DRAWING='@T6G_MB_LIB.T6G(SCH_1):PAGE187',
 PART_TYPE='SMLF',
 MATERIAL='IND',
 PHYS_PAGE='212',
 XY='(-2350,1450)',
 ROT='0',
 VER='1',
 LOCATION='PL32',
 CDS_LIB='pure_quanta',
 CDS_PART_NAME='Q_INDUCTOR4P_14-150NH,SMLF,IND,CV+15^0TZ04',
 PART_NUMBER='CV+15^0TZ04',
 VALUE='150NH',
 PRIM_FILE='./archive_libs/logical/q_inductor4p_14/chips/chips.prt';

PART_NAME
 PL33 'Q_INDUCTOR4P_14-150NH,SMLF,IND,CV+15^0TZ04':;

SECTION_NUMBER 1
 '@T6G_MB_LIB.T6G(SCH_1):PAGE188_I64@PURE_QUANTA.Q_INDUCTOR4P_14(CHIPS)':
 C_PATH='@t6g_mb_lib.t6g(sch_1):page188_i64@pure_quanta.q_inductor4p_14(chips)',
 P_PATH='@t6g_mb_lib.t6g(sch_1):page213_i64@pure_quanta.q_inductor4p_14(chips)',
 PATH='I64',
 DRAWING='@T6G_MB_LIB.T6G(SCH_1):PAGE188',
 PART_TYPE='SMLF',
 MATERIAL='IND',
 PHYS_PAGE='213',
 XY='(-2475,4725)',
 ROT='0',
 VER='1',
 LOCATION='PL33',
 CDS_LIB='pure_quanta',
 CDS_PART_NAME='Q_INDUCTOR4P_14-150NH,SMLF,IND,CV+15^0TZ04',
 PART_NUMBER='CV+15^0TZ04',
 VALUE='150NH',
 PRIM_FILE='./archive_libs/logical/q_inductor4p_14/chips/chips.prt';

PART_NAME
 PL34 'Q_INDUCTOR_SMLF-0.22UH/33A,IND,CV+22Y0EZ00':;

SECTION_NUMBER 1
 '@T6G_MB_LIB.T6G(SCH_1):PAGE191_I25@PURE_QUANTA.Q_INDUCTOR(CHIPS)':
 C_PATH='@t6g_mb_lib.t6g(sch_1):page191_i25@pure_quanta.q_inductor(chips)',
 P_PATH='@t6g_mb_lib.t6g(sch_1):page216_i25@pure_quanta.q_inductor(chips)',
 PATH='I25',
 DRAWING='@T6G_MB_LIB.T6G(SCH_1):PAGE191',
 MATERIAL='IND',
 PHYS_PAGE='216',
 XY='(-3650,4275)',
 ROT='0',
 VER='1',
 PACK_TYPE='SMLF',
 LOCATION='PL34',
 CDS_LIB='pure_quanta',
 CDS_PART_NAME='Q_INDUCTOR_SMLF-0.22UH/33A,IND,CV+22Y0EZ00',
 PART_NUMBER='CV+22Y0EZ00',
 VALUE='0.22UH/33A',
 PRIM_FILE='./archive_libs/logical/q_inductor/chips/chips.prt';

PART_NAME
 PL35 'Q_INDUCTOR4P_14-150NH,SMLF,IND,CV+15^0TZ04':;

SECTION_NUMBER 1
 '@T6G_MB_LIB.T6G(SCH_1):PAGE190_I69@PURE_QUANTA.Q_INDUCTOR4P_14(CHIPS)':
 C_PATH='@t6g_mb_lib.t6g(sch_1):page190_i69@pure_quanta.q_inductor4p_14(chips)',
 P_PATH='@t6g_mb_lib.t6g(sch_1):page215_i69@pure_quanta.q_inductor4p_14(chips)',
 PATH='I69',
 DRAWING='@T6G_MB_LIB.T6G(SCH_1):PAGE190',
 PART_TYPE='SMLF',
 MATERIAL='IND',
 PHYS_PAGE='215',
 XY='(-3200,4625)',
 ROT='0',
 VER='1',
 LOCATION='PL35',
 CDS_LIB='pure_quanta',
 CDS_PART_NAME='Q_INDUCTOR4P_14-150NH,SMLF,IND,CV+15^0TZ04',
 PART_NUMBER='CV+15^0TZ04',
 VALUE='150NH',
 PRIM_FILE='./archive_libs/logical/q_inductor4p_14/chips/chips.prt';

PART_NAME
 PL36 'Q_INDUCTOR4P_14-150NH,SMLF,IND,CV+15^0TZ04':;

SECTION_NUMBER 1
 '@T6G_MB_LIB.T6G(SCH_1):PAGE190_I52@PURE_QUANTA.Q_INDUCTOR4P_14(CHIPS)':
 C_PATH='@t6g_mb_lib.t6g(sch_1):page190_i52@pure_quanta.q_inductor4p_14(chips)',
 P_PATH='@t6g_mb_lib.t6g(sch_1):page215_i52@pure_quanta.q_inductor4p_14(chips)',
 PATH='I52',
 DRAWING='@T6G_MB_LIB.T6G(SCH_1):PAGE190',
 PART_TYPE='SMLF',
 MATERIAL='IND',
 PHYS_PAGE='215',
 XY='(-2950,1850)',
 ROT='0',
 VER='1',
 LOCATION='PL36',
 CDS_LIB='pure_quanta',
 CDS_PART_NAME='Q_INDUCTOR4P_14-150NH,SMLF,IND,CV+15^0TZ04',
 PART_NUMBER='CV+15^0TZ04',
 VALUE='150NH',
 PRIM_FILE='./archive_libs/logical/q_inductor4p_14/chips/chips.prt';

PART_NAME
 PL37 'Q_INDUCTOR_SMLF-50NH/86A,IND,CVA50^0MZ09':;

SECTION_NUMBER 1
 '@T6G_MB_LIB.T6G(SCH_1):PAGE190_I74@PURE_QUANTA.Q_INDUCTOR(CHIPS)':
 C_PATH='@t6g_mb_lib.t6g(sch_1):page190_i74@pure_quanta.q_inductor(chips)',
 P_PATH='@t6g_mb_lib.t6g(sch_1):page215_i74@pure_quanta.q_inductor(chips)',
 PATH='I74',
 DRAWING='@T6G_MB_LIB.T6G(SCH_1):PAGE190',
 MATERIAL='IND',
 PHYS_PAGE='215',
 XY='(-3075,5800)',
 ROT='0',
 VER='1',
 PACK_TYPE='SMLF',
 LOCATION='PL37',
 CDS_LIB='pure_quanta',
 CDS_PART_NAME='Q_INDUCTOR_SMLF-50NH/86A,IND,CVA50^0MZ09',
 PART_NUMBER='CVA50^0MZ09',
 VALUE='50NH/86A',
 PRIM_FILE='./archive_libs/logical/q_inductor/chips/chips.prt';

PART_NAME
 PL38 'Q_INDUCTOR4P_14-150NH,SMLF,IND,CV+15^0TZ04':;

SECTION_NUMBER 1
 '@T6G_MB_LIB.T6G(SCH_1):PAGE191_I26@PURE_QUANTA.Q_INDUCTOR4P_14(CHIPS)':
 C_PATH='@t6g_mb_lib.t6g(sch_1):page191_i26@pure_quanta.q_inductor4p_14(chips)',
 P_PATH='@t6g_mb_lib.t6g(sch_1):page216_i26@pure_quanta.q_inductor4p_14(chips)',
 PATH='I26',
 DRAWING='@T6G_MB_LIB.T6G(SCH_1):PAGE191',
 PART_TYPE='SMLF',
 MATERIAL='IND',
 PHYS_PAGE='216',
 XY='(-2650,4375)',
 ROT='0',
 VER='1',
 LOCATION='PL38',
 CDS_LIB='pure_quanta',
 CDS_PART_NAME='Q_INDUCTOR4P_14-150NH,SMLF,IND,CV+15^0TZ04',
 PART_NUMBER='CV+15^0TZ04',
 VALUE='150NH',
 PRIM_FILE='./archive_libs/logical/q_inductor4p_14/chips/chips.prt';

PART_NAME
 PL39 'Q_INDUCTOR_SMLF-120NH/69A,IND,CV+12^0EZ03':;

SECTION_NUMBER 1
 '@T6G_MB_LIB.T6G(SCH_1):PAGE195_I37@PURE_QUANTA.Q_INDUCTOR(CHIPS)':
 C_PATH='@t6g_mb_lib.t6g(sch_1):page195_i37@pure_quanta.q_inductor(chips)',
 P_PATH='@t6g_mb_lib.t6g(sch_1):page220_i37@pure_quanta.q_inductor(chips)',
 PATH='I37',
 DRAWING='@T6G_MB_LIB.T6G(SCH_1):PAGE195',
 MATERIAL='IND',
 PHYS_PAGE='220',
 XY='(5575,2000)',
 ROT='2',
 VER='1',
 PACK_TYPE='SMLF',
 LOCATION='PL39',
 CDS_LIB='pure_quanta',
 CDS_PART_NAME='Q_INDUCTOR_SMLF-120NH/69A,IND,CV+12^0EZ03',
 PART_NUMBER='CV+12^0EZ03',
 VALUE='120NH/69A',
 PRIM_FILE='./archive_libs/logical/q_inductor/chips/chips.prt';

PART_NAME
 PL40 'Q_INDUCTOR4P_14-150NH,SMLF,IND,CV+15^0TZ04':;

SECTION_NUMBER 1
 '@T6G_MB_LIB.T6G(SCH_1):PAGE193_I77@PURE_QUANTA.Q_INDUCTOR4P_14(CHIPS)':
 C_PATH='@t6g_mb_lib.t6g(sch_1):page193_i77@pure_quanta.q_inductor4p_14(chips)',
 P_PATH='@t6g_mb_lib.t6g(sch_1):page218_i77@pure_quanta.q_inductor4p_14(chips)',
 PATH='I77',
 DRAWING='@T6G_MB_LIB.T6G(SCH_1):PAGE193',
 PART_TYPE='SMLF',
 MATERIAL='IND',
 PHYS_PAGE='218',
 XY='(-3450,4475)',
 ROT='0',
 VER='1',
 LOCATION='PL40',
 CDS_LIB='pure_quanta',
 CDS_PART_NAME='Q_INDUCTOR4P_14-150NH,SMLF,IND,CV+15^0TZ04',
 PART_NUMBER='CV+15^0TZ04',
 VALUE='150NH',
 PRIM_FILE='./archive_libs/logical/q_inductor4p_14/chips/chips.prt';

PART_NAME
 PL41 'Q_INDUCTOR4P_14-150NH,SMLF,IND,CV+15^0TZ04':;

SECTION_NUMBER 1
 '@T6G_MB_LIB.T6G(SCH_1):PAGE193_I62@PURE_QUANTA.Q_INDUCTOR4P_14(CHIPS)':
 C_PATH='@t6g_mb_lib.t6g(sch_1):page193_i62@pure_quanta.q_inductor4p_14(chips)',
 P_PATH='@t6g_mb_lib.t6g(sch_1):page218_i62@pure_quanta.q_inductor4p_14(chips)',
 PATH='I62',
 DRAWING='@T6G_MB_LIB.T6G(SCH_1):PAGE193',
 PART_TYPE='SMLF',
 MATERIAL='IND',
 PHYS_PAGE='218',
 XY='(-3050,1850)',
 ROT='0',
 VER='1',
 LOCATION='PL41',
 CDS_LIB='pure_quanta',
 CDS_PART_NAME='Q_INDUCTOR4P_14-150NH,SMLF,IND,CV+15^0TZ04',
 PART_NUMBER='CV+15^0TZ04',
 VALUE='150NH',
 PRIM_FILE='./archive_libs/logical/q_inductor4p_14/chips/chips.prt';

PART_NAME
 PL42 'Q_INDUCTOR_SMLF-50NH/86A,IND,CVA50^0MZ09':;

SECTION_NUMBER 1
 '@T6G_MB_LIB.T6G(SCH_1):PAGE193_I79@PURE_QUANTA.Q_INDUCTOR(CHIPS)':
 C_PATH='@t6g_mb_lib.t6g(sch_1):page193_i79@pure_quanta.q_inductor(chips)',
 P_PATH='@t6g_mb_lib.t6g(sch_1):page218_i79@pure_quanta.q_inductor(chips)',
 PATH='I79',
 DRAWING='@T6G_MB_LIB.T6G(SCH_1):PAGE193',
 MATERIAL='IND',
 PHYS_PAGE='218',
 XY='(-3350,5775)',
 ROT='0',
 VER='1',
 PACK_TYPE='SMLF',
 LOCATION='PL42',
 CDS_LIB='pure_quanta',
 CDS_PART_NAME='Q_INDUCTOR_SMLF-50NH/86A,IND,CVA50^0MZ09',
 PART_NUMBER='CVA50^0MZ09',
 VALUE='50NH/86A',
 PRIM_FILE='./archive_libs/logical/q_inductor/chips/chips.prt';

PART_NAME
 PL43 'Q_INDUCTOR4P_14-150NH,SMLF,IND,CV+15^0TZ04':;

SECTION_NUMBER 1
 '@T6G_MB_LIB.T6G(SCH_1):PAGE194_I50@PURE_QUANTA.Q_INDUCTOR4P_14(CHIPS)':
 C_PATH='@t6g_mb_lib.t6g(sch_1):page194_i50@pure_quanta.q_inductor4p_14(chips)',
 P_PATH='@t6g_mb_lib.t6g(sch_1):page219_i50@pure_quanta.q_inductor4p_14(chips)',
 PATH='I50',
 DRAWING='@T6G_MB_LIB.T6G(SCH_1):PAGE194',
 PART_TYPE='SMLF',
 MATERIAL='IND',
 PHYS_PAGE='219',
 XY='(6650,1350)',
 ROT='0',
 VER='1',
 LOCATION='PL43',
 CDS_LIB='pure_quanta',
 CDS_PART_NAME='Q_INDUCTOR4P_14-150NH,SMLF,IND,CV+15^0TZ04',
 PART_NUMBER='CV+15^0TZ04',
 VALUE='150NH',
 PRIM_FILE='./archive_libs/logical/q_inductor4p_14/chips/chips.prt';

PART_NAME
 PL44 'Q_INDUCTOR4P_14-150NH,SMLF,IND,CV+15^0TZ04':;

SECTION_NUMBER 1
 '@T6G_MB_LIB.T6G(SCH_1):PAGE194_I62@PURE_QUANTA.Q_INDUCTOR4P_14(CHIPS)':
 C_PATH='@t6g_mb_lib.t6g(sch_1):page194_i62@pure_quanta.q_inductor4p_14(chips)',
 P_PATH='@t6g_mb_lib.t6g(sch_1):page219_i62@pure_quanta.q_inductor4p_14(chips)',
 PATH='I62',
 DRAWING='@T6G_MB_LIB.T6G(SCH_1):PAGE194',
 PART_TYPE='SMLF',
 MATERIAL='IND',
 PHYS_PAGE='219',
 XY='(6700,4175)',
 ROT='0',
 VER='1',
 LOCATION='PL44',
 CDS_LIB='pure_quanta',
 CDS_PART_NAME='Q_INDUCTOR4P_14-150NH,SMLF,IND,CV+15^0TZ04',
 PART_NUMBER='CV+15^0TZ04',
 VALUE='150NH',
 PRIM_FILE='./archive_libs/logical/q_inductor4p_14/chips/chips.prt';

PART_NAME
 PL45 'Q_INDUCTOR4P_14-150NH,SMLF,IND,CV+15^0TZ04':;

SECTION_NUMBER 1
 '@T6G_MB_LIB.T6G(SCH_1):PAGE195_I63@PURE_QUANTA.Q_INDUCTOR4P_14(CHIPS)':
 C_PATH='@t6g_mb_lib.t6g(sch_1):page195_i63@pure_quanta.q_inductor4p_14(chips)',
 P_PATH='@t6g_mb_lib.t6g(sch_1):page220_i63@pure_quanta.q_inductor4p_14(chips)',
 PATH='I63',
 DRAWING='@T6G_MB_LIB.T6G(SCH_1):PAGE195',
 PART_TYPE='SMLF',
 MATERIAL='IND',
 PHYS_PAGE='220',
 XY='(6600,4725)',
 ROT='0',
 VER='1',
 LOCATION='PL45',
 CDS_LIB='pure_quanta',
 CDS_PART_NAME='Q_INDUCTOR4P_14-150NH,SMLF,IND,CV+15^0TZ04',
 PART_NUMBER='CV+15^0TZ04',
 VALUE='150NH',
 PRIM_FILE='./archive_libs/logical/q_inductor4p_14/chips/chips.prt';

PART_NAME
 PL46 'Q_INDUCTOR_SMLF-0.22UH/33A,IND,CV+22Y0EZ00':;

SECTION_NUMBER 1
 '@T6G_MB_LIB.T6G(SCH_1):PAGE198_I43@PURE_QUANTA.Q_INDUCTOR(CHIPS)':
 C_PATH='@t6g_mb_lib.t6g(sch_1):page198_i43@pure_quanta.q_inductor(chips)',
 P_PATH='@t6g_mb_lib.t6g(sch_1):page223_i43@pure_quanta.q_inductor(chips)',
 PATH='I43',
 DRAWING='@T6G_MB_LIB.T6G(SCH_1):PAGE198',
 MATERIAL='IND',
 PHYS_PAGE='223',
 XY='(-7300,2075)',
 ROT='2',
 VER='1',
 PACK_TYPE='SMLF',
 LOCATION='PL46',
 CDS_LIB='pure_quanta',
 CDS_PART_NAME='Q_INDUCTOR_SMLF-0.22UH/33A,IND,CV+22Y0EZ00',
 PART_NUMBER='CV+22Y0EZ00',
 VALUE='0.22UH/33A',
 PRIM_FILE='./archive_libs/logical/q_inductor/chips/chips.prt';

PART_NAME
 PL47 'Q_INDUCTOR4P_14-150NH,SMLF,IND,CV+15^0TZ04':;

SECTION_NUMBER 1
 '@T6G_MB_LIB.T6G(SCH_1):PAGE197_I71@PURE_QUANTA.Q_INDUCTOR4P_14(CHIPS)':
 C_PATH='@t6g_mb_lib.t6g(sch_1):page197_i71@pure_quanta.q_inductor4p_14(chips)',
 P_PATH='@t6g_mb_lib.t6g(sch_1):page222_i71@pure_quanta.q_inductor4p_14(chips)',
 PATH='I71',
 DRAWING='@T6G_MB_LIB.T6G(SCH_1):PAGE197',
 PART_TYPE='SMLF',
 MATERIAL='IND',
 PHYS_PAGE='222',
 XY='(5850,4875)',
 ROT='0',
 VER='1',
 LOCATION='PL47',
 CDS_LIB='pure_quanta',
 CDS_PART_NAME='Q_INDUCTOR4P_14-150NH,SMLF,IND,CV+15^0TZ04',
 PART_NUMBER='CV+15^0TZ04',
 VALUE='150NH',
 PRIM_FILE='./archive_libs/logical/q_inductor4p_14/chips/chips.prt';

PART_NAME
 PL48 'Q_INDUCTOR4P_14-150NH,SMLF,IND,CV+15^0TZ04':;

SECTION_NUMBER 1
 '@T6G_MB_LIB.T6G(SCH_1):PAGE197_I83@PURE_QUANTA.Q_INDUCTOR4P_14(CHIPS)':
 C_PATH='@t6g_mb_lib.t6g(sch_1):page197_i83@pure_quanta.q_inductor4p_14(chips)',
 P_PATH='@t6g_mb_lib.t6g(sch_1):page222_i83@pure_quanta.q_inductor4p_14(chips)',
 PATH='I83',
 DRAWING='@T6G_MB_LIB.T6G(SCH_1):PAGE197',
 PART_TYPE='SMLF',
 MATERIAL='IND',
 PHYS_PAGE='222',
 XY='(6025,2125)',
 ROT='0',
 VER='1',
 LOCATION='PL48',
 CDS_LIB='pure_quanta',
 CDS_PART_NAME='Q_INDUCTOR4P_14-150NH,SMLF,IND,CV+15^0TZ04',
 PART_NUMBER='CV+15^0TZ04',
 VALUE='150NH',
 PRIM_FILE='./archive_libs/logical/q_inductor4p_14/chips/chips.prt';

PART_NAME
 PL49 'Q_INDUCTOR_SMLF-50NH/86A,IND,CVA50^0MZ09':;

SECTION_NUMBER 1
 '@T6G_MB_LIB.T6G(SCH_1):PAGE197_I72@PURE_QUANTA.Q_INDUCTOR(CHIPS)':
 C_PATH='@t6g_mb_lib.t6g(sch_1):page197_i72@pure_quanta.q_inductor(chips)',
 P_PATH='@t6g_mb_lib.t6g(sch_1):page222_i72@pure_quanta.q_inductor(chips)',
 PATH='I72',
 DRAWING='@T6G_MB_LIB.T6G(SCH_1):PAGE197',
 MATERIAL='IND',
 PHYS_PAGE='222',
 XY='(5450,6175)',
 ROT='0',
 VER='1',
 PACK_TYPE='SMLF',
 LOCATION='PL49',
 CDS_LIB='pure_quanta',
 CDS_PART_NAME='Q_INDUCTOR_SMLF-50NH/86A,IND,CVA50^0MZ09',
 PART_NUMBER='CVA50^0MZ09',
 VALUE='50NH/86A',
 PRIM_FILE='./archive_libs/logical/q_inductor/chips/chips.prt';

PART_NAME
 PL50 'Q_INDUCTOR_SMLF-120NH/69A,IND,CV+12^0EZ03':;

SECTION_NUMBER 1
 '@T6G_MB_LIB.T6G(SCH_1):PAGE171_I51@PURE_QUANTA.Q_INDUCTOR(CHIPS)':
 C_PATH='@t6g_mb_lib.t6g(sch_1):page171_i51@pure_quanta.q_inductor(chips)',
 P_PATH='@t6g_mb_lib.t6g(sch_1):page196_i51@pure_quanta.q_inductor(chips)',
 PATH='I51',
 DRAWING='@T6G_MB_LIB.T6G(SCH_1):PAGE171',
 MATERIAL='IND',
 PHYS_PAGE='196',
 XY='(-3450,1625)',
 ROT='0',
 VER='1',
 PACK_TYPE='SMLF',
 LOCATION='PL50',
 CDS_LIB='pure_quanta',
 CDS_PART_NAME='Q_INDUCTOR_SMLF-120NH/69A,IND,CV+12^0EZ03',
 PART_NUMBER='CV+12^0EZ03',
 VALUE='120NH/69A',
 PRIM_FILE='./archive_libs/logical/q_inductor/chips/chips.prt';

PART_NAME
 PL51 'Q_INDUCTOR4P_14-150NH,SMLF,IND,CV+15^0TZ04':;

SECTION_NUMBER 1
 '@T6G_MB_LIB.T6G(SCH_1):PAGE169_I77@PURE_QUANTA.Q_INDUCTOR4P_14(CHIPS)':
 C_PATH='@t6g_mb_lib.t6g(sch_1):page169_i77@pure_quanta.q_inductor4p_14(chips)',
 P_PATH='@t6g_mb_lib.t6g(sch_1):page194_i77@pure_quanta.q_inductor4p_14(chips)',
 PATH='I77',
 DRAWING='@T6G_MB_LIB.T6G(SCH_1):PAGE169',
 PART_TYPE='SMLF',
 MATERIAL='IND',
 PHYS_PAGE='194',
 XY='(-3250,4225)',
 ROT='0',
 VER='1',
 LOCATION='PL51',
 CDS_LIB='pure_quanta',
 CDS_PART_NAME='Q_INDUCTOR4P_14-150NH,SMLF,IND,CV+15^0TZ04',
 PART_NUMBER='CV+15^0TZ04',
 VALUE='150NH',
 PRIM_FILE='./archive_libs/logical/q_inductor4p_14/chips/chips.prt';

PART_NAME
 PL52 'Q_INDUCTOR4P_14-150NH,SMLF,IND,CV+15^0TZ04':;

SECTION_NUMBER 1
 '@T6G_MB_LIB.T6G(SCH_1):PAGE169_I62@PURE_QUANTA.Q_INDUCTOR4P_14(CHIPS)':
 C_PATH='@t6g_mb_lib.t6g(sch_1):page169_i62@pure_quanta.q_inductor4p_14(chips)',
 P_PATH='@t6g_mb_lib.t6g(sch_1):page194_i62@pure_quanta.q_inductor4p_14(chips)',
 PATH='I62',
 DRAWING='@T6G_MB_LIB.T6G(SCH_1):PAGE169',
 PART_TYPE='SMLF',
 MATERIAL='IND',
 PHYS_PAGE='194',
 XY='(-3075,1475)',
 ROT='0',
 VER='1',
 LOCATION='PL52',
 CDS_LIB='pure_quanta',
 CDS_PART_NAME='Q_INDUCTOR4P_14-150NH,SMLF,IND,CV+15^0TZ04',
 PART_NUMBER='CV+15^0TZ04',
 VALUE='150NH',
 PRIM_FILE='./archive_libs/logical/q_inductor4p_14/chips/chips.prt';

PART_NAME
 PL53 'Q_INDUCTOR_SMLF-50NH/86A,IND,CVA50^0MZ09':;

SECTION_NUMBER 1
 '@T6G_MB_LIB.T6G(SCH_1):PAGE169_I82@PURE_QUANTA.Q_INDUCTOR(CHIPS)':
 C_PATH='@t6g_mb_lib.t6g(sch_1):page169_i82@pure_quanta.q_inductor(chips)',
 P_PATH='@t6g_mb_lib.t6g(sch_1):page194_i82@pure_quanta.q_inductor(chips)',
 PATH='I82',
 DRAWING='@T6G_MB_LIB.T6G(SCH_1):PAGE169',
 MATERIAL='IND',
 PHYS_PAGE='194',
 XY='(-3075,5425)',
 ROT='0',
 VER='1',
 PACK_TYPE='SMLF',
 LOCATION='PL53',
 CDS_LIB='pure_quanta',
 CDS_PART_NAME='Q_INDUCTOR_SMLF-50NH/86A,IND,CVA50^0MZ09',
 PART_NUMBER='CVA50^0MZ09',
 VALUE='50NH/86A',
 PRIM_FILE='./archive_libs/logical/q_inductor/chips/chips.prt';

PART_NAME
 PL54 'Q_INDUCTOR_SMLF-90NH/155A,IND,CVA90^0KZ13':;

SECTION_NUMBER 1
 '@T6G_MB_LIB.T6G(SCH_1):PAGE200_I78@PURE_QUANTA.Q_INDUCTOR(CHIPS)':
 C_PATH='@t6g_mb_lib.t6g(sch_1):page200_i78@pure_quanta.q_inductor(chips)',
 P_PATH='@t6g_mb_lib.t6g(sch_1):page225_i78@pure_quanta.q_inductor(chips)',
 PATH='I78',
 DRAWING='@T6G_MB_LIB.T6G(SCH_1):PAGE200',
 MATERIAL='IND',
 PHYS_PAGE='225',
 XY='(-3325,4650)',
 ROT='0',
 VER='1',
 PACK_TYPE='SMLF',
 LOCATION='PL54',
 CDS_LIB='pure_quanta',
 CDS_PART_NAME='Q_INDUCTOR_SMLF-90NH/155A,IND,CVA90^0KZ13',
 PART_NUMBER='CVA90^0KZ13',
 VALUE='90NH/155A',
 PRIM_FILE='./archive_libs/logical/q_inductor/chips/chips.prt';

PART_NAME
 PL55 'Q_INDUCTOR_SMLF-90NH/155A,IND,CVA90^0KZ13':;

SECTION_NUMBER 1
 '@T6G_MB_LIB.T6G(SCH_1):PAGE200_I55@PURE_QUANTA.Q_INDUCTOR(CHIPS)':
 C_PATH='@t6g_mb_lib.t6g(sch_1):page200_i55@pure_quanta.q_inductor(chips)',
 P_PATH='@t6g_mb_lib.t6g(sch_1):page225_i55@pure_quanta.q_inductor(chips)',
 PATH='I55',
 DRAWING='@T6G_MB_LIB.T6G(SCH_1):PAGE200',
 MATERIAL='IND',
 PHYS_PAGE='225',
 XY='(-3275,1725)',
 ROT='0',
 VER='1',
 PACK_TYPE='SMLF',
 LOCATION='PL55',
 CDS_LIB='pure_quanta',
 CDS_PART_NAME='Q_INDUCTOR_SMLF-90NH/155A,IND,CVA90^0KZ13',
 PART_NUMBER='CVA90^0KZ13',
 VALUE='90NH/155A',
 PRIM_FILE='./archive_libs/logical/q_inductor/chips/chips.prt';

PART_NAME
 PL56 'Q_INDUCTOR_SMLF-100NH/16A,IND,CV+10G0MZ04':;

SECTION_NUMBER 1
 '@T6G_MB_LIB.T6G(SCH_1):PAGE200_I84@PURE_QUANTA.Q_INDUCTOR(CHIPS)':
 C_PATH='@t6g_mb_lib.t6g(sch_1):page200_i84@pure_quanta.q_inductor(chips)',
 P_PATH='@t6g_mb_lib.t6g(sch_1):page225_i84@pure_quanta.q_inductor(chips)',
 PATH='I84',
 DRAWING='@T6G_MB_LIB.T6G(SCH_1):PAGE200',
 MATERIAL='IND',
 PHYS_PAGE='225',
 XY='(-2925,5725)',
 ROT='0',
 VER='1',
 PACK_TYPE='SMLF',
 LOCATION='PL56',
 CDS_LIB='pure_quanta',
 CDS_PART_NAME='Q_INDUCTOR_SMLF-100NH/16A,IND,CV+10G0MZ04',
 PART_NUMBER='CV+10G0MZ04',
 VALUE='100NH/16A',
 PRIM_FILE='./archive_libs/logical/q_inductor/chips/chips.prt';

PART_NAME
 PL57 'Q_INDUCTOR_SMLF-1.0UH/18A,IND,CV-10I0MZ01':;

SECTION_NUMBER 1
 '@T6G_MB_LIB.T6G(SCH_1):PAGE201_I33@PURE_QUANTA.Q_INDUCTOR(CHIPS)':
 C_PATH='@t6g_mb_lib.t6g(sch_1):page201_i33@pure_quanta.q_inductor(chips)',
 P_PATH='@t6g_mb_lib.t6g(sch_1):page226_i33@pure_quanta.q_inductor(chips)',
 PATH='I33',
 DRAWING='@T6G_MB_LIB.T6G(SCH_1):PAGE201',
 MATERIAL='IND',
 PHYS_PAGE='226',
 XY='(-3275,4025)',
 ROT='0',
 VER='1',
 PACK_TYPE='SMLF',
 LOCATION='PL57',
 CDS_LIB='pure_quanta',
 CDS_PART_NAME='Q_INDUCTOR_SMLF-1.0UH/18A,IND,CV-10I0MZ01',
 PART_NUMBER='CV-10I0MZ01',
 VALUE='1.0UH/18A',
 PRIM_FILE='./archive_libs/logical/q_inductor/chips/chips.prt';

PART_NAME
 PL59 'Q_INDUCTOR4P_14-150NH,SMLF,IND,CV+15^0TZ04':;

SECTION_NUMBER 1
 '@T6G_MB_LIB.T6G(SCH_1):PAGE170_I64@PURE_QUANTA.Q_INDUCTOR4P_14(CHIPS)':
 C_PATH='@t6g_mb_lib.t6g(sch_1):page170_i64@pure_quanta.q_inductor4p_14(chips)',
 P_PATH='@t6g_mb_lib.t6g(sch_1):page195_i64@pure_quanta.q_inductor4p_14(chips)',
 PATH='I64',
 DRAWING='@T6G_MB_LIB.T6G(SCH_1):PAGE170',
 PART_TYPE='SMLF',
 MATERIAL='IND',
 PHYS_PAGE='195',
 XY='(-2725,4675)',
 ROT='0',
 VER='1',
 LOCATION='PL59',
 CDS_LIB='pure_quanta',
 CDS_PART_NAME='Q_INDUCTOR4P_14-150NH,SMLF,IND,CV+15^0TZ04',
 PART_NUMBER='CV+15^0TZ04',
 VALUE='150NH',
 PRIM_FILE='./archive_libs/logical/q_inductor4p_14/chips/chips.prt';

PART_NAME
 PL60 'Q_INDUCTOR4P_14-150NH,SMLF,IND,CV+15^0TZ04':;

SECTION_NUMBER 1
 '@T6G_MB_LIB.T6G(SCH_1):PAGE170_I52@PURE_QUANTA.Q_INDUCTOR4P_14(CHIPS)':
 C_PATH='@t6g_mb_lib.t6g(sch_1):page170_i52@pure_quanta.q_inductor4p_14(chips)',
 P_PATH='@t6g_mb_lib.t6g(sch_1):page195_i52@pure_quanta.q_inductor4p_14(chips)',
 PATH='I52',
 DRAWING='@T6G_MB_LIB.T6G(SCH_1):PAGE170',
 PART_TYPE='SMLF',
 MATERIAL='IND',
 PHYS_PAGE='195',
 XY='(-2700,1375)',
 ROT='0',
 VER='1',
 LOCATION='PL60',
 CDS_LIB='pure_quanta',
 CDS_PART_NAME='Q_INDUCTOR4P_14-150NH,SMLF,IND,CV+15^0TZ04',
 PART_NUMBER='CV+15^0TZ04',
 VALUE='150NH',
 PRIM_FILE='./archive_libs/logical/q_inductor4p_14/chips/chips.prt';

PART_NAME
 PL61 'Q_INDUCTOR4P_14-150NH,SMLF,IND,CV+15^0TZ04':;

SECTION_NUMBER 1
 '@T6G_MB_LIB.T6G(SCH_1):PAGE171_I64@PURE_QUANTA.Q_INDUCTOR4P_14(CHIPS)':
 C_PATH='@t6g_mb_lib.t6g(sch_1):page171_i64@pure_quanta.q_inductor4p_14(chips)',
 P_PATH='@t6g_mb_lib.t6g(sch_1):page196_i64@pure_quanta.q_inductor4p_14(chips)',
 PATH='I64',
 DRAWING='@T6G_MB_LIB.T6G(SCH_1):PAGE171',
 PART_TYPE='SMLF',
 MATERIAL='IND',
 PHYS_PAGE='196',
 XY='(-2475,4450)',
 ROT='0',
 VER='1',
 LOCATION='PL61',
 CDS_LIB='pure_quanta',
 CDS_PART_NAME='Q_INDUCTOR4P_14-150NH,SMLF,IND,CV+15^0TZ04',
 PART_NUMBER='CV+15^0TZ04',
 VALUE='150NH',
 PRIM_FILE='./archive_libs/logical/q_inductor4p_14/chips/chips.prt';

PART_NAME
 PL62 'Q_INDUCTOR_SMLF-0.22UH/33A,IND,CV+22Y0EZ00':;

SECTION_NUMBER 1
 '@T6G_MB_LIB.T6G(SCH_1):PAGE174_I24@PURE_QUANTA.Q_INDUCTOR(CHIPS)':
 C_PATH='@t6g_mb_lib.t6g(sch_1):page174_i24@pure_quanta.q_inductor(chips)',
 P_PATH='@t6g_mb_lib.t6g(sch_1):page199_i24@pure_quanta.q_inductor(chips)',
 PATH='I24',
 DRAWING='@T6G_MB_LIB.T6G(SCH_1):PAGE174',
 MATERIAL='IND',
 PHYS_PAGE='199',
 XY='(-3775,4000)',
 ROT='0',
 VER='1',
 PACK_TYPE='SMLF',
 LOCATION='PL62',
 CDS_LIB='pure_quanta',
 CDS_PART_NAME='Q_INDUCTOR_SMLF-0.22UH/33A,IND,CV+22Y0EZ00',
 PART_NUMBER='CV+22Y0EZ00',
 VALUE='0.22UH/33A',
 PRIM_FILE='./archive_libs/logical/q_inductor/chips/chips.prt';

PART_NAME
 PL63 'Q_INDUCTOR4P_14-150NH,SMLF,IND,CV+15^0TZ04':;

SECTION_NUMBER 1
 '@T6G_MB_LIB.T6G(SCH_1):PAGE173_I69@PURE_QUANTA.Q_INDUCTOR4P_14(CHIPS)':
 C_PATH='@t6g_mb_lib.t6g(sch_1):page173_i69@pure_quanta.q_inductor4p_14(chips)',
 P_PATH='@t6g_mb_lib.t6g(sch_1):page198_i69@pure_quanta.q_inductor4p_14(chips)',
 PATH='I69',
 DRAWING='@T6G_MB_LIB.T6G(SCH_1):PAGE173',
 PART_TYPE='SMLF',
 MATERIAL='IND',
 PHYS_PAGE='198',
 XY='(-2900,4950)',
 ROT='0',
 VER='1',
 LOCATION='PL63',
 CDS_LIB='pure_quanta',
 CDS_PART_NAME='Q_INDUCTOR4P_14-150NH,SMLF,IND,CV+15^0TZ04',
 PART_NUMBER='CV+15^0TZ04',
 VALUE='150NH',
 PRIM_FILE='./archive_libs/logical/q_inductor4p_14/chips/chips.prt';

PART_NAME
 PL64 'Q_INDUCTOR4P_14-150NH,SMLF,IND,CV+15^0TZ04':;

SECTION_NUMBER 1
 '@T6G_MB_LIB.T6G(SCH_1):PAGE173_I53@PURE_QUANTA.Q_INDUCTOR4P_14(CHIPS)':
 C_PATH='@t6g_mb_lib.t6g(sch_1):page173_i53@pure_quanta.q_inductor4p_14(chips)',
 P_PATH='@t6g_mb_lib.t6g(sch_1):page198_i53@pure_quanta.q_inductor4p_14(chips)',
 PATH='I53',
 DRAWING='@T6G_MB_LIB.T6G(SCH_1):PAGE173',
 PART_TYPE='SMLF',
 MATERIAL='IND',
 PHYS_PAGE='198',
 XY='(-2825,1850)',
 ROT='0',
 VER='1',
 LOCATION='PL64',
 CDS_LIB='pure_quanta',
 CDS_PART_NAME='Q_INDUCTOR4P_14-150NH,SMLF,IND,CV+15^0TZ04',
 PART_NUMBER='CV+15^0TZ04',
 VALUE='150NH',
 PRIM_FILE='./archive_libs/logical/q_inductor4p_14/chips/chips.prt';

PART_NAME
 PL65 'Q_INDUCTOR_SMLF-50NH/86A,IND,CVA50^0MZ09':;

SECTION_NUMBER 1
 '@T6G_MB_LIB.T6G(SCH_1):PAGE173_I74@PURE_QUANTA.Q_INDUCTOR(CHIPS)':
 C_PATH='@t6g_mb_lib.t6g(sch_1):page173_i74@pure_quanta.q_inductor(chips)',
 P_PATH='@t6g_mb_lib.t6g(sch_1):page198_i74@pure_quanta.q_inductor(chips)',
 PATH='I74',
 DRAWING='@T6G_MB_LIB.T6G(SCH_1):PAGE173',
 MATERIAL='IND',
 PHYS_PAGE='198',
 XY='(-2775,6125)',
 ROT='0',
 VER='1',
 PACK_TYPE='SMLF',
 LOCATION='PL65',
 CDS_LIB='pure_quanta',
 CDS_PART_NAME='Q_INDUCTOR_SMLF-50NH/86A,IND,CVA50^0MZ09',
 PART_NUMBER='CVA50^0MZ09',
 VALUE='50NH/86A',
 PRIM_FILE='./archive_libs/logical/q_inductor/chips/chips.prt';

PART_NAME
 PL66 'Q_INDUCTOR4P_14-150NH,SMLF,IND,CV+15^0TZ04':;

SECTION_NUMBER 1
 '@T6G_MB_LIB.T6G(SCH_1):PAGE174_I25@PURE_QUANTA.Q_INDUCTOR4P_14(CHIPS)':
 C_PATH='@t6g_mb_lib.t6g(sch_1):page174_i25@pure_quanta.q_inductor4p_14(chips)',
 P_PATH='@t6g_mb_lib.t6g(sch_1):page199_i25@pure_quanta.q_inductor4p_14(chips)',
 PATH='I25',
 DRAWING='@T6G_MB_LIB.T6G(SCH_1):PAGE174',
 PART_TYPE='SMLF',
 MATERIAL='IND',
 PHYS_PAGE='199',
 XY='(-2825,4100)',
 ROT='0',
 VER='1',
 LOCATION='PL66',
 CDS_LIB='pure_quanta',
 CDS_PART_NAME='Q_INDUCTOR4P_14-150NH,SMLF,IND,CV+15^0TZ04',
 PART_NUMBER='CV+15^0TZ04',
 VALUE='150NH',
 PRIM_FILE='./archive_libs/logical/q_inductor4p_14/chips/chips.prt';

PART_NAME
 PL67 'Q_INDUCTOR4P_14-150NH,SMLF,IND,CV+15^0TZ04':;

SECTION_NUMBER 1
 '@T6G_MB_LIB.T6G(SCH_1):PAGE198_I42@PURE_QUANTA.Q_INDUCTOR4P_14(CHIPS)':
 C_PATH='@t6g_mb_lib.t6g(sch_1):page198_i42@pure_quanta.q_inductor4p_14(chips)',
 P_PATH='@t6g_mb_lib.t6g(sch_1):page223_i42@pure_quanta.q_inductor4p_14(chips)',
 PATH='I42',
 DRAWING='@T6G_MB_LIB.T6G(SCH_1):PAGE198',
 PART_TYPE='SMLF',
 MATERIAL='IND',
 PHYS_PAGE='223',
 XY='(-6275,2175)',
 ROT='0',
 VER='1',
 LOCATION='PL67',
 CDS_LIB='pure_quanta',
 CDS_PART_NAME='Q_INDUCTOR4P_14-150NH,SMLF,IND,CV+15^0TZ04',
 PART_NUMBER='CV+15^0TZ04',
 VALUE='150NH',
 PRIM_FILE='./archive_libs/logical/q_inductor4p_14/chips/chips.prt';

PART_NAME
 PL68 'Q_INDUCTOR4P_14-150NH,SMLF,IND,CV+15^0TZ04':;

SECTION_NUMBER 1
 '@T6G_MB_LIB.T6G(SCH_1):PAGE198_I62@PURE_QUANTA.Q_INDUCTOR4P_14(CHIPS)':
 C_PATH='@t6g_mb_lib.t6g(sch_1):page198_i62@pure_quanta.q_inductor4p_14(chips)',
 P_PATH='@t6g_mb_lib.t6g(sch_1):page223_i62@pure_quanta.q_inductor4p_14(chips)',
 PATH='I62',
 DRAWING='@T6G_MB_LIB.T6G(SCH_1):PAGE198',
 PART_TYPE='SMLF',
 MATERIAL='IND',
 PHYS_PAGE='223',
 XY='(-6025,4975)',
 ROT='0',
 VER='1',
 LOCATION='PL68',
 CDS_LIB='pure_quanta',
 CDS_PART_NAME='Q_INDUCTOR4P_14-150NH,SMLF,IND,CV+15^0TZ04',
 PART_NUMBER='CV+15^0TZ04',
 VALUE='150NH',
 PRIM_FILE='./archive_libs/logical/q_inductor4p_14/chips/chips.prt';

PART_NAME
 PL69 'Q_INDUCTOR4P_14-150NH,SMLF,IND,CV+15^0TZ04':;

SECTION_NUMBER 1
 '@T6G_MB_LIB.T6G(SCH_1):PAGE195_I50@PURE_QUANTA.Q_INDUCTOR4P_14(CHIPS)':
 C_PATH='@t6g_mb_lib.t6g(sch_1):page195_i50@pure_quanta.q_inductor4p_14(chips)',
 P_PATH='@t6g_mb_lib.t6g(sch_1):page220_i50@pure_quanta.q_inductor4p_14(chips)',
 PATH='I50',
 DRAWING='@T6G_MB_LIB.T6G(SCH_1):PAGE195',
 PART_TYPE='SMLF',
 MATERIAL='IND',
 PHYS_PAGE='220',
 XY='(6650,2100)',
 ROT='0',
 VER='1',
 LOCATION='PL69',
 CDS_LIB='pure_quanta',
 CDS_PART_NAME='Q_INDUCTOR4P_14-150NH,SMLF,IND,CV+15^0TZ04',
 PART_NUMBER='CV+15^0TZ04',
 VALUE='150NH',
 PRIM_FILE='./archive_libs/logical/q_inductor4p_14/chips/chips.prt';

PART_NAME
 PL70 'Q_INDUCTOR4P_14-150NH,SMLF,IND,CV+15^0TZ04':;

SECTION_NUMBER 1
 '@T6G_MB_LIB.T6G(SCH_1):PAGE171_I52@PURE_QUANTA.Q_INDUCTOR4P_14(CHIPS)':
 C_PATH='@t6g_mb_lib.t6g(sch_1):page171_i52@pure_quanta.q_inductor4p_14(chips)',
 P_PATH='@t6g_mb_lib.t6g(sch_1):page196_i52@pure_quanta.q_inductor4p_14(chips)',
 PATH='I52',
 DRAWING='@T6G_MB_LIB.T6G(SCH_1):PAGE171',
 PART_TYPE='SMLF',
 MATERIAL='IND',
 PHYS_PAGE='196',
 XY='(-2475,1725)',
 ROT='0',
 VER='1',
 LOCATION='PL70',
 CDS_LIB='pure_quanta',
 CDS_PART_NAME='Q_INDUCTOR4P_14-150NH,SMLF,IND,CV+15^0TZ04',
 PART_NUMBER='CV+15^0TZ04',
 VALUE='150NH',
 PRIM_FILE='./archive_libs/logical/q_inductor4p_14/chips/chips.prt';

PART_NAME
 PL71 'Q_INDUCTOR_SMLF-BLM18SN220TN1D/8000MA,IND,CX220TN1A':;

SECTION_NUMBER 1
 '@T6G_MB_LIB.T6G(SCH_1):PAGE167_I10@PURE_QUANTA.Q_INDUCTOR(CHIPS)':
 C_PATH='@t6g_mb_lib.t6g(sch_1):page167_i10@pure_quanta.q_inductor(chips)',
 P_PATH='@t6g_mb_lib.t6g(sch_1):page192_i10@pure_quanta.q_inductor(chips)',
 PATH='I10',
 DRAWING='@T6G_MB_LIB.T6G(SCH_1):PAGE167',
 SEC_TYPE='SMLF',
 MATERIAL='IND',
 PHYS_PAGE='192',
 XY='(-10050,4675)',
 ROT='0',
 VER='1',
 PACK_TYPE='SMLF',
 LOCATION='PL71',
 SEC='1',
 CDS_LIB='pure_quanta',
 CDS_PART_NAME='Q_INDUCTOR_SMLF-BLM18SN220TN1D/8000MA,IND,CX220TN1A',
 PART_NUMBER='CX220TN1001',
 VALUE='BLM18SN220TN1D/8000MA',
 PRIM_FILE='./archive_libs/logical/q_inductor/chips/chips.prt';

PART_NAME
 PL72 'Q_INDUCTOR_SMLF-1.5UH,IND,CV-15I0MZ28':;

SECTION_NUMBER 1
 '@T6G_MB_LIB.T6G(SCH_1):PAGE167_I47@PURE_QUANTA.Q_INDUCTOR(CHIPS)':
 C_PATH='@t6g_mb_lib.t6g(sch_1):page167_i47@pure_quanta.q_inductor(chips)',
 P_PATH='@t6g_mb_lib.t6g(sch_1):page192_i47@pure_quanta.q_inductor(chips)',
 PATH='I47',
 DRAWING='@T6G_MB_LIB.T6G(SCH_1):PAGE167',
 SEC_TYPE='SMLF',
 MATERIAL='IND',
 PHYS_PAGE='192',
 XY='(-4850,3625)',
 ROT='0',
 VER='1',
 PACK_TYPE='SMLF',
 LOCATION='PL72',
 SEC='1',
 CDS_LIB='pure_quanta',
 CDS_PART_NAME='Q_INDUCTOR_SMLF-1.5UH,IND,CV-15I0MZ28',
 PART_NUMBER='CV-15I0MZ28',
 VALUE='1.5UH',
 PRIM_FILE='./archive_libs/logical/q_inductor/chips/chips.prt';

PART_NAME
 PL77 'Q_INDUCTOR_SMLF-BLM18SN220TN1D/8000MA,IND,CX220TN1A':;

SECTION_NUMBER 1
 '@T6G_MB_LIB.T6G(SCH_1):PAGE184_I7@PURE_QUANTA.Q_INDUCTOR(CHIPS)':
 C_PATH='@t6g_mb_lib.t6g(sch_1):page184_i7@pure_quanta.q_inductor(chips)',
 P_PATH='@t6g_mb_lib.t6g(sch_1):page209_i7@pure_quanta.q_inductor(chips)',
 PATH='I7',
 DRAWING='@T6G_MB_LIB.T6G(SCH_1):PAGE184',
 MATERIAL='IND',
 PHYS_PAGE='209',
 XY='(-8875,4375)',
 ROT='0',
 VER='1',
 PACK_TYPE='SMLF',
 LOCATION='PL77',
 CDS_LIB='pure_quanta',
 CDS_PART_NAME='Q_INDUCTOR_SMLF-BLM18SN220TN1D/8000MA,IND,CX220TN1A',
 PART_NUMBER='CX220TN1001',
 VALUE='BLM18SN220TN1D/8000MA',
 PRIM_FILE='./archive_libs/logical/q_inductor/chips/chips.prt';

PART_NAME
 PL78 'Q_INDUCTOR_SMLF-1.0UH/18A,IND,CV-10I0MZ01':;

SECTION_NUMBER 1
 '@T6G_MB_LIB.T6G(SCH_1):PAGE184_I36@PURE_QUANTA.Q_INDUCTOR(CHIPS)':
 C_PATH='@t6g_mb_lib.t6g(sch_1):page184_i36@pure_quanta.q_inductor(chips)',
 P_PATH='@t6g_mb_lib.t6g(sch_1):page209_i36@pure_quanta.q_inductor(chips)',
 PATH='I36',
 DRAWING='@T6G_MB_LIB.T6G(SCH_1):PAGE184',
 MATERIAL='IND',
 PHYS_PAGE='209',
 XY='(-3575,3600)',
 ROT='0',
 VER='1',
 PACK_TYPE='SMLF',
 LOCATION='PL78',
 CDS_LIB='pure_quanta',
 CDS_PART_NAME='Q_INDUCTOR_SMLF-1.0UH/18A,IND,CV-10I0MZ01',
 PART_NUMBER='CV-10I0MZ01',
 VALUE='1.0UH/18A',
 PRIM_FILE='./archive_libs/logical/q_inductor/chips/chips.prt';

PART_NAME
 PL6000 'Q_INDUCTOR_SMLF-3.3UH/6A,IND,CV-3360MZ07':;

SECTION_NUMBER 1
 '@T6G_MB_LIB.T6G(SCH_1):PAGE315_I25@PURE_QUANTA.Q_INDUCTOR(CHIPS)':
 C_PATH='@t6g_mb_lib.t6g(sch_1):page315_i25@pure_quanta.q_inductor(chips)',
 P_PATH='@t6g_mb_lib.t6g(sch_1):page269_i25@pure_quanta.q_inductor(chips)',
 PATH='I25',
 DRAWING='@T6G_MB_LIB.T6G(SCH_1):PAGE315',
 MATERIAL='IND',
 PHYS_PAGE='269',
 XY='(825,2050)',
 ROT='0',
 VER='1',
 PACK_TYPE='SMLF',
 LOCATION='PL6000',
 CDS_LIB='pure_quanta',
 CDS_PART_NAME='Q_INDUCTOR_SMLF-3.3UH/6A,IND,CV-3360MZ07',
 PART_NUMBER='CV-3360MZ07',
 VALUE='3.3UH/6A',
 PRIM_FILE='./archive_libs/logical/q_inductor/chips/chips.prt';

PART_NAME
 PL6001 'Q_INDUCTOR_SMLF-2.2UH,IND,CV-2280MZ15':;

SECTION_NUMBER 1
 '@T6G_MB_LIB.T6G(SCH_1):PAGE380_I24@PURE_QUANTA.Q_INDUCTOR(CHIPS)':
 C_PATH='@t6g_mb_lib.t6g(sch_1):page380_i24@pure_quanta.q_inductor(chips)',
 P_PATH='@t6g_mb_lib.t6g(sch_1):page270_i24@pure_quanta.q_inductor(chips)',
 PATH='I24',
 DRAWING='@T6G_MB_LIB.T6G(SCH_1):PAGE380',
 MATERIAL='IND',
 PHYS_PAGE='270',
 XY='(-2725,2025)',
 ROT='0',
 VER='1',
 PACK_TYPE='SMLF',
 LOCATION='PL6001',
 CDS_LIB='pure_quanta',
 CDS_PART_NAME='Q_INDUCTOR_SMLF-2.2UH,IND,CV-2280MZ15',
 PART_NUMBER='CV-2280MZ15',
 VALUE='2.2UH',
 PRIM_FILE='./archive_libs/logical/q_inductor/chips/chips.prt';

PART_NAME
 PL6002 'Q_INDUCTOR_SMLF-BLM18SN220TN1D/8000MA,IND,CX220TN1A':;

SECTION_NUMBER 1
 '@T6G_MB_LIB.T6G(SCH_1):PAGE315_I7@PURE_QUANTA.Q_INDUCTOR(CHIPS)':
 C_PATH='@t6g_mb_lib.t6g(sch_1):page315_i7@pure_quanta.q_inductor(chips)',
 P_PATH='@t6g_mb_lib.t6g(sch_1):page269_i7@pure_quanta.q_inductor(chips)',
 PATH='I7',
 DRAWING='@T6G_MB_LIB.T6G(SCH_1):PAGE315',
 MATERIAL='IND',
 PHYS_PAGE='269',
 XY='(-3625,2750)',
 ROT='0',
 VER='1',
 PACK_TYPE='SMLF',
 LOCATION='PL6002',
 CDS_LIB='pure_quanta',
 CDS_PART_NAME='Q_INDUCTOR_SMLF-BLM18SN220TN1D/8000MA,IND,CX220TN1A',
 PART_NUMBER='CX220TN1001',
 VALUE='BLM18SN220TN1D/8000MA',
 PRIM_FILE='./archive_libs/logical/q_inductor/chips/chips.prt';

PART_NAME
 PL6003 'Q_INDUCTOR_SMLF-BLM18SN220TN1D/8000MA,IND,CX220TN1A':;

SECTION_NUMBER 1
 '@T6G_MB_LIB.T6G(SCH_1):PAGE380_I2@PURE_QUANTA.Q_INDUCTOR(CHIPS)':
 C_PATH='@t6g_mb_lib.t6g(sch_1):page380_i2@pure_quanta.q_inductor(chips)',
 P_PATH='@t6g_mb_lib.t6g(sch_1):page270_i2@pure_quanta.q_inductor(chips)',
 PATH='I2',
 DRAWING='@T6G_MB_LIB.T6G(SCH_1):PAGE380',
 MATERIAL='IND',
 PHYS_PAGE='270',
 XY='(-7200,2725)',
 ROT='0',
 VER='1',
 PACK_TYPE='SMLF',
 LOCATION='PL6003',
 CDS_LIB='pure_quanta',
 CDS_PART_NAME='Q_INDUCTOR_SMLF-BLM18SN220TN1D/8000MA,IND,CX220TN1A',
 PART_NUMBER='CX220TN1001',
 VALUE='BLM18SN220TN1D/8000MA',
 PRIM_FILE='./archive_libs/logical/q_inductor/chips/chips.prt';

PART_NAME
 PL6500 'Q_INDUCTOR_SMLF-100NH/16A,IND,CV+10G0MZ04':;

SECTION_NUMBER 1
 '@T6G_MB_LIB.T6G(SCH_1):PAGE469_I9@PURE_QUANTA.Q_INDUCTOR(CHIPS)':
 C_PATH='@t6g_mb_lib.t6g(sch_1):page469_i9@pure_quanta.q_inductor(chips)',
 P_PATH='@t6g_mb_lib.t6g(sch_1):page360_i9@pure_quanta.q_inductor(chips)',
 PATH='I9',
 DRAWING='@T6G_MB_LIB.T6G(SCH_1):PAGE469',
 MATERIAL='IND',
 PHYS_PAGE='360',
 XY='(-8750,4200)',
 ROT='0',
 VER='1',
 PACK_TYPE='SMLF',
 LOCATION='PL6500',
 CDS_LIB='pure_quanta',
 CDS_PART_NAME='Q_INDUCTOR_SMLF-100NH/16A,IND,CV+10G0MZ04',
 PART_NUMBER='CV+10G0MZ04',
 VALUE='100NH/16A',
 PRIM_FILE='./archive_libs/logical/q_inductor/chips/chips.prt';

PART_NAME
 PL6501 'Q_INDUCTOR_SMLF-1UH,IND,CV-10U0MZ01':;

SECTION_NUMBER 1
 '@T6G_MB_LIB.T6G(SCH_1):PAGE469_I36@PURE_QUANTA.Q_INDUCTOR(CHIPS)':
 C_PATH='@t6g_mb_lib.t6g(sch_1):page469_i36@pure_quanta.q_inductor(chips)',
 P_PATH='@t6g_mb_lib.t6g(sch_1):page360_i36@pure_quanta.q_inductor(chips)',
 PATH='I36',
 DRAWING='@T6G_MB_LIB.T6G(SCH_1):PAGE469',
 MATERIAL='IND',
 PHYS_PAGE='360',
 XY='(-3450,3425)',
 ROT='0',
 VER='1',
 PACK_TYPE='SMLF',
 LOCATION='PL6501',
 CDS_LIB='pure_quanta',
 CDS_PART_NAME='Q_INDUCTOR_SMLF-1UH,IND,CV-10U0MZ01',
 PART_NUMBER='CV-10U0MZ01',
 VALUE='1UH',
 PRIM_FILE='./archive_libs/logical/q_inductor/chips/chips.prt';

PART_NAME
 PL6502 'Q_INDUCTOR_SMLF-1UH,IND,CV-10U0MZ01':;

SECTION_NUMBER 1
 '@T6G_MB_LIB.T6G(SCH_1):PAGE470_I37@PURE_QUANTA.Q_INDUCTOR(CHIPS)':
 C_PATH='@t6g_mb_lib.t6g(sch_1):page470_i37@pure_quanta.q_inductor(chips)',
 P_PATH='@t6g_mb_lib.t6g(sch_1):page361_i37@pure_quanta.q_inductor(chips)',
 PATH='I37',
 DRAWING='@T6G_MB_LIB.T6G(SCH_1):PAGE470',
 MATERIAL='IND',
 PHYS_PAGE='361',
 XY='(-3500,3475)',
 ROT='0',
 VER='1',
 PACK_TYPE='SMLF',
 LOCATION='PL6502',
 CDS_LIB='pure_quanta',
 CDS_PART_NAME='Q_INDUCTOR_SMLF-1UH,IND,CV-10U0MZ01',
 PART_NUMBER='CV-10U0MZ01',
 VALUE='1UH',
 PRIM_FILE='./archive_libs/logical/q_inductor/chips/chips.prt';

PART_NAME
 PL6503 'Q_INDUCTOR_SMLF-100NH/16A,IND,CV+10G0MZ04':;

SECTION_NUMBER 1
 '@T6G_MB_LIB.T6G(SCH_1):PAGE470_I9@PURE_QUANTA.Q_INDUCTOR(CHIPS)':
 C_PATH='@t6g_mb_lib.t6g(sch_1):page470_i9@pure_quanta.q_inductor(chips)',
 P_PATH='@t6g_mb_lib.t6g(sch_1):page361_i9@pure_quanta.q_inductor(chips)',
 PATH='I9',
 DRAWING='@T6G_MB_LIB.T6G(SCH_1):PAGE470',
 MATERIAL='IND',
 PHYS_PAGE='361',
 XY='(-8800,4250)',
 ROT='0',
 VER='1',
 PACK_TYPE='SMLF',
 LOCATION='PL6503',
 CDS_LIB='pure_quanta',
 CDS_PART_NAME='Q_INDUCTOR_SMLF-100NH/16A,IND,CV+10G0MZ04',
 PART_NUMBER='CV+10G0MZ04',
 VALUE='100NH/16A',
 PRIM_FILE='./archive_libs/logical/q_inductor/chips/chips.prt';

PART_NAME
 PL6504 'Q_INDUCTOR_SMLF-100NH/16A,IND,CV+10G0MZ04':;

SECTION_NUMBER 1
 '@T6G_MB_LIB.T6G(SCH_1):PAGE476_I182@PURE_QUANTA.Q_INDUCTOR(CHIPS)':
 C_PATH='@t6g_mb_lib.t6g(sch_1):page476_i182@pure_quanta.q_inductor(chips)',
 P_PATH='@t6g_mb_lib.t6g(sch_1):page363_i182@pure_quanta.q_inductor(chips)',
 PATH='I182',
 DRAWING='@T6G_MB_LIB.T6G(SCH_1):PAGE476',
 SEC_TYPE='SMLF',
 MATERIAL='IND',
 PHYS_PAGE='363',
 XY='(1150,-5450)',
 ROT='0',
 VER='1',
 PACK_TYPE='SMLF',
 LOCATION='PL6504',
 SEC='1',
 CDS_LIB='pure_quanta',
 CDS_PART_NAME='Q_INDUCTOR_SMLF-100NH/16A,IND,CV+10G0MZ04',
 PART_NUMBER='CV+10G0MZ04',
 VALUE='100NH/16A',
 PRIM_FILE='./archive_libs/logical/q_inductor/chips/chips.prt';

PART_NAME
 PL6505 'Q_INDUCTOR_SMLF-120NH/69A,IND,CV+12^0EZ03':;

SECTION_NUMBER 1
 '@T6G_MB_LIB.T6G(SCH_1):PAGE476_I34@PURE_QUANTA.Q_INDUCTOR(CHIPS)':
 C_PATH='@t6g_mb_lib.t6g(sch_1):page476_i34@pure_quanta.q_inductor(chips)',
 P_PATH='@t6g_mb_lib.t6g(sch_1):page363_i34@pure_quanta.q_inductor(chips)',
 PATH='I34',
 DRAWING='@T6G_MB_LIB.T6G(SCH_1):PAGE476',
 SEC_TYPE='SMLF',
 BOM_COST='VR_DIMM ',
 MATERIAL='IND',
 PHYS_PAGE='363',
 XY='(-1925,-6425)',
 ROT='0',
 VER='1',
 PACK_TYPE='SMLF',
 LOCATION='PL6505',
 SEC='1',
 CDS_LIB='pure_quanta',
 CDS_PART_NAME='Q_INDUCTOR_SMLF-120NH/69A,IND,CV+12^0EZ03',
 PART_NUMBER='CV+12^0EZ03',
 VALUE='120NH/69A',
 PRIM_FILE='./archive_libs/logical/q_inductor/chips/chips.prt';

PART_NAME
 PL6506 'Q_INDUCTOR_SMLF-120NH/69A,IND,CV+12^0EZ03':;

SECTION_NUMBER 1
 '@T6G_MB_LIB.T6G(SCH_1):PAGE476_I257@PURE_QUANTA.Q_INDUCTOR(CHIPS)':
 C_PATH='@t6g_mb_lib.t6g(sch_1):page476_i257@pure_quanta.q_inductor(chips)',
 P_PATH='@t6g_mb_lib.t6g(sch_1):page363_i257@pure_quanta.q_inductor(chips)',
 PATH='I257',
 DRAWING='@T6G_MB_LIB.T6G(SCH_1):PAGE476',
 BOM_COST='VR_DIMM ',
 MATERIAL='IND',
 PHYS_PAGE='363',
 XY='(-1825,-9325)',
 ROT='0',
 VER='1',
 PACK_TYPE='SMLF',
 LOCATION='PL6506',
 CDS_LIB='pure_quanta',
 CDS_PART_NAME='Q_INDUCTOR_SMLF-120NH/69A,IND,CV+12^0EZ03',
 PART_NUMBER='CV+12^0EZ03',
 VALUE='120NH/69A',
 PRIM_FILE='./archive_libs/logical/q_inductor/chips/chips.prt';

PART_NAME
 PL6510 'Q_INDUCTOR_SMLF-100NH/16A,IND,CV+10G0MZ04':;

SECTION_NUMBER 1
 '@T6G_MB_LIB.T6G(SCH_1):PAGE478_I104@PURE_QUANTA.Q_INDUCTOR(CHIPS)':
 C_PATH='@t6g_mb_lib.t6g(sch_1):page478_i104@pure_quanta.q_inductor(chips)',
 P_PATH='@t6g_mb_lib.t6g(sch_1):page365_i104@pure_quanta.q_inductor(chips)',
 PATH='I104',
 DRAWING='@T6G_MB_LIB.T6G(SCH_1):PAGE478',
 MATERIAL='IND',
 PHYS_PAGE='365',
 XY='(-1825,5350)',
 ROT='0',
 VER='1',
 PACK_TYPE='SMLF',
 LOCATION='PL6510',
 CDS_LIB='pure_quanta',
 CDS_PART_NAME='Q_INDUCTOR_SMLF-100NH/16A,IND,CV+10G0MZ04',
 PART_NUMBER='CV+10G0MZ04',
 VALUE='100NH/16A',
 PRIM_FILE='./archive_libs/logical/q_inductor/chips/chips.prt';

PART_NAME
 PL6511 'Q_INDUCTOR_SMLF-120NH/69A,IND,CV+12^0EZ03':;

SECTION_NUMBER 1
 '@T6G_MB_LIB.T6G(SCH_1):PAGE478_I65@PURE_QUANTA.Q_INDUCTOR(CHIPS)':
 C_PATH='@t6g_mb_lib.t6g(sch_1):page478_i65@pure_quanta.q_inductor(chips)',
 P_PATH='@t6g_mb_lib.t6g(sch_1):page365_i65@pure_quanta.q_inductor(chips)',
 PATH='I65',
 DRAWING='@T6G_MB_LIB.T6G(SCH_1):PAGE478',
 BOM_COST='VR_DIMM ',
 MATERIAL='IND',
 PHYS_PAGE='365',
 XY='(-4900,4375)',
 ROT='0',
 VER='1',
 PACK_TYPE='SMLF',
 LOCATION='PL6511',
 CDS_LIB='pure_quanta',
 CDS_PART_NAME='Q_INDUCTOR_SMLF-120NH/69A,IND,CV+12^0EZ03',
 PART_NUMBER='CV+12^0EZ03',
 VALUE='120NH/69A',
 PRIM_FILE='./archive_libs/logical/q_inductor/chips/chips.prt';

PART_NAME
 PL6512 'Q_INDUCTOR_SMLF-120NH/69A,IND,CV+12^0EZ03':;

SECTION_NUMBER 1
 '@T6G_MB_LIB.T6G(SCH_1):PAGE478_I22@PURE_QUANTA.Q_INDUCTOR(CHIPS)':
 C_PATH='@t6g_mb_lib.t6g(sch_1):page478_i22@pure_quanta.q_inductor(chips)',
 P_PATH='@t6g_mb_lib.t6g(sch_1):page365_i22@pure_quanta.q_inductor(chips)',
 PATH='I22',
 DRAWING='@T6G_MB_LIB.T6G(SCH_1):PAGE478',
 BOM_COST='VR_DIMM ',
 MATERIAL='IND',
 PHYS_PAGE='365',
 XY='(-4775,1475)',
 ROT='0',
 VER='1',
 PACK_TYPE='SMLF',
 LOCATION='PL6512',
 CDS_LIB='pure_quanta',
 CDS_PART_NAME='Q_INDUCTOR_SMLF-120NH/69A,IND,CV+12^0EZ03',
 PART_NUMBER='CV+12^0EZ03',
 VALUE='120NH/69A',
 PRIM_FILE='./archive_libs/logical/q_inductor/chips/chips.prt';

PART_NAME
 PL8045 'Q_INDUCTOR_SMLF-100NH/16A,IND,CV+10G0MZ04':;

SECTION_NUMBER 1
 '@T6G_MB_LIB.T6G(SCH_1):PAGE245_I24@PURE_QUANTA.Q_INDUCTOR(CHIPS)':
 C_PATH='@t6g_mb_lib.t6g(sch_1):page245_i24@pure_quanta.q_inductor(chips)',
 P_PATH='@t6g_mb_lib.t6g(sch_1):page190_i24@pure_quanta.q_inductor(chips)',
 PATH='I24',
 DRAWING='@T6G_MB_LIB.T6G(SCH_1):PAGE245',
 MATERIAL='IND',
 PHYS_PAGE='190',
 XY='(-4300,1325)',
 ROT='0',
 VER='1',
 PACK_TYPE='SMLF',
 LOCATION='PL8045',
 CDS_LIB='pure_quanta',
 CDS_PART_NAME='Q_INDUCTOR_SMLF-100NH/16A,IND,CV+10G0MZ04',
 PART_NUMBER='CV+10G0MZ04',
 VALUE='100NH/16A',
 PRIM_FILE='./archive_libs/logical/q_inductor/chips/chips.prt';

PART_NAME
 PL8064 'Q_INDUCTOR_SMLF-BLM18SN220TN1D/8000MA,IND,CX220TN1A':;

SECTION_NUMBER 1
 '@T6G_MB_LIB.T6G(SCH_1):PAGE244_I5@PURE_QUANTA.Q_INDUCTOR(CHIPS)':
 C_PATH='@t6g_mb_lib.t6g(sch_1):page244_i5@pure_quanta.q_inductor(chips)',
 P_PATH='@t6g_mb_lib.t6g(sch_1):page189_i5@pure_quanta.q_inductor(chips)',
 PATH='I5',
 DRAWING='@T6G_MB_LIB.T6G(SCH_1):PAGE244',
 MATERIAL='IND',
 PHYS_PAGE='189',
 XY='(-7925,9150)',
 ROT='0',
 VER='1',
 PACK_TYPE='SMLF',
 LOCATION='PL8064',
 CDS_LIB='pure_quanta',
 CDS_PART_NAME='Q_INDUCTOR_SMLF-BLM18SN220TN1D/8000MA,IND,CX220TN1A',
 PART_NUMBER='CX220TN1001',
 VALUE='BLM18SN220TN1D/8000MA',
 PRIM_FILE='./archive_libs/logical/q_inductor/chips/chips.prt';

PART_NAME
 PL8065 'Q_INDUCTOR_SMLF-4.7UH,IND,CV-47A0MZ10':;

SECTION_NUMBER 1
 '@T6G_MB_LIB.T6G(SCH_1):PAGE244_I28@PURE_QUANTA.Q_INDUCTOR(CHIPS)':
 C_PATH='@t6g_mb_lib.t6g(sch_1):page244_i28@pure_quanta.q_inductor(chips)',
 P_PATH='@t6g_mb_lib.t6g(sch_1):page189_i28@pure_quanta.q_inductor(chips)',
 PATH='I28',
 DRAWING='@T6G_MB_LIB.T6G(SCH_1):PAGE244',
 MATERIAL='IND',
 PHYS_PAGE='189',
 XY='(-2825,7775)',
 ROT='0',
 VER='1',
 PACK_TYPE='SMLF',
 LOCATION='PL8065',
 CDS_LIB='pure_quanta',
 CDS_PART_NAME='Q_INDUCTOR_SMLF-4.7UH,IND,CV-47A0MZ10',
 PART_NUMBER='CV-47A0MZ10',
 VALUE='4.7UH',
 PRIM_FILE='./archive_libs/logical/q_inductor/chips/chips.prt';

PART_NAME
 PL8066 'Q_INDUCTOR_SMLF-1.5UH/53A,IND,CV-15^0MZ02':;

SECTION_NUMBER 1
 '@T6G_MB_LIB.T6G(SCH_1):PAGE245_I55@PURE_QUANTA.Q_INDUCTOR(CHIPS)':
 C_PATH='@t6g_mb_lib.t6g(sch_1):page245_i55@pure_quanta.q_inductor(chips)',
 P_PATH='@t6g_mb_lib.t6g(sch_1):page190_i55@pure_quanta.q_inductor(chips)',
 PATH='I55',
 DRAWING='@T6G_MB_LIB.T6G(SCH_1):PAGE245',
 MATERIAL='IND',
 PHYS_PAGE='190',
 XY='(1425,-475)',
 ROT='0',
 VER='1',
 PACK_TYPE='SMLF',
 LOCATION='PL8066',
 CDS_LIB='pure_quanta',
 CDS_PART_NAME='Q_INDUCTOR_SMLF-1.5UH/53A,IND,CV-15^0MZ02',
 PART_NUMBER='CV-15^0MZ02',
 VALUE='1.5UH/53A',
 PRIM_FILE='./archive_libs/logical/q_inductor/chips/chips.prt';

PART_NAME
 PPQ1 'MOSFET_NCH_1D3S-PSMNR58-30YLH,SMLF,IC,BAMNR580000':
 ROOM='HSC BOM2';

SECTION_NUMBER 1
 '@T6G_MB_LIB.T6G(SCH_1):PAGE302_I61@PURE_QUANTA.MOSFET_NCH_1D3S(CHIPS)':
 C_PATH='@t6g_mb_lib.t6g(sch_1):page302_i61@pure_quanta.mosfet_nch_1d3s(chips)',
 P_PATH='@t6g_mb_lib.t6g(sch_1):page266_i61@pure_quanta.mosfet_nch_1d3s(chips)',
 PATH='I61',
 DRAWING='@T6G_MB_LIB.T6G(SCH_1):PAGE302',
 SEC_TYPE='',
 PART_TYPE='SMLF',
 MATERIAL='IC',
 PHYS_PAGE='266',
 XY='(-2700,2350)',
 ROT='6',
 VER='1',
 LOCATION='PPQ1',
 SEC='1',
 CDS_LIB='pure_quanta',
 CDS_PART_NAME='MOSFET_NCH_1D3S-PSMNR58-30YLH,SMLF,IC,BAMNR580000',
 ROOM='HSC BOM2',
 PART_NUMBER='BAMNR580000',
 VALUE='PSMNR58-30YLH',
 PRIM_FILE='./archive_libs/logical/mosfet_nch_1d3s/chips/chips.prt';

PART_NAME
 PPQ2 'MOSFET_NCH_1D3S-PSMNR58-30YLH,SMLF,IC,BAMNR580000':
 ROOM='HSC BOM2';

SECTION_NUMBER 1
 '@T6G_MB_LIB.T6G(SCH_1):PAGE302_I64@PURE_QUANTA.MOSFET_NCH_1D3S(CHIPS)':
 C_PATH='@t6g_mb_lib.t6g(sch_1):page302_i64@pure_quanta.mosfet_nch_1d3s(chips)',
 P_PATH='@t6g_mb_lib.t6g(sch_1):page266_i64@pure_quanta.mosfet_nch_1d3s(chips)',
 PATH='I64',
 DRAWING='@T6G_MB_LIB.T6G(SCH_1):PAGE302',
 SEC_TYPE='',
 PART_TYPE='SMLF',
 MATERIAL='IC',
 PHYS_PAGE='266',
 XY='(-1825,2375)',
 ROT='6',
 VER='1',
 LOCATION='PPQ2',
 SEC='1',
 CDS_LIB='pure_quanta',
 CDS_PART_NAME='MOSFET_NCH_1D3S-PSMNR58-30YLH,SMLF,IC,BAMNR580000',
 ROOM='HSC BOM2',
 PART_NUMBER='BAMNR580000',
 VALUE='PSMNR58-30YLH',
 PRIM_FILE='./archive_libs/logical/mosfet_nch_1d3s/chips/chips.prt';

PART_NAME
 PPQ5 'MOSFET_NCH_1D3S-PSMNR58-30YLH,SMLF,IC,BAMNR580000':
 ROOM='HSC BOM2';

SECTION_NUMBER 1
 '@T6G_MB_LIB.T6G(SCH_1):PAGE302_I29@PURE_QUANTA.MOSFET_NCH_1D3S(CHIPS)':
 C_PATH='@t6g_mb_lib.t6g(sch_1):page302_i29@pure_quanta.mosfet_nch_1d3s(chips)',
 P_PATH='@t6g_mb_lib.t6g(sch_1):page266_i29@pure_quanta.mosfet_nch_1d3s(chips)',
 PATH='I29',
 DRAWING='@T6G_MB_LIB.T6G(SCH_1):PAGE302',
 PART_TYPE='SMLF',
 MATERIAL='IC',
 PHYS_PAGE='266',
 XY='(-6200,2275)',
 ROT='6',
 VER='1',
 LOCATION='PPQ5',
 CDS_LIB='pure_quanta',
 CDS_PART_NAME='MOSFET_NCH_1D3S-PSMNR58-30YLH,SMLF,IC,BAMNR580000',
 ROOM='HSC BOM2',
 PART_NUMBER='BAMNR580000',
 VALUE='PSMNR58-30YLH',
 PRIM_FILE='./archive_libs/logical/mosfet_nch_1d3s/chips/chips.prt';

PART_NAME
 PPQ6 'MOSFET_NCH_1D3S-PSMNR58-30YLH,SMLF,IC,BAMNR580000':
 ROOM='HSC BOM2';

SECTION_NUMBER 1
 '@T6G_MB_LIB.T6G(SCH_1):PAGE302_I46@PURE_QUANTA.MOSFET_NCH_1D3S(CHIPS)':
 C_PATH='@t6g_mb_lib.t6g(sch_1):page302_i46@pure_quanta.mosfet_nch_1d3s(chips)',
 P_PATH='@t6g_mb_lib.t6g(sch_1):page266_i46@pure_quanta.mosfet_nch_1d3s(chips)',
 PATH='I46',
 DRAWING='@T6G_MB_LIB.T6G(SCH_1):PAGE302',
 PART_TYPE='SMLF',
 MATERIAL='IC',
 PHYS_PAGE='266',
 XY='(-5325,2300)',
 ROT='6',
 VER='1',
 LOCATION='PPQ6',
 CDS_LIB='pure_quanta',
 CDS_PART_NAME='MOSFET_NCH_1D3S-PSMNR58-30YLH,SMLF,IC,BAMNR580000',
 ROOM='HSC BOM2',
 PART_NUMBER='BAMNR580000',
 VALUE='PSMNR58-30YLH',
 PRIM_FILE='./archive_libs/logical/mosfet_nch_1d3s/chips/chips.prt';

PART_NAME
 PPQ7 'MOSFET_NCH_1D3S-PSMNR58-30YLH,SMLF,IC,BAMNR580000':
 ROOM='HSC BOM2';

SECTION_NUMBER 1
 '@T6G_MB_LIB.T6G(SCH_1):PAGE302_I80@PURE_QUANTA.MOSFET_NCH_1D3S(CHIPS)':
 C_PATH='@t6g_mb_lib.t6g(sch_1):page302_i80@pure_quanta.mosfet_nch_1d3s(chips)',
 P_PATH='@t6g_mb_lib.t6g(sch_1):page266_i80@pure_quanta.mosfet_nch_1d3s(chips)',
 PATH='I80',
 DRAWING='@T6G_MB_LIB.T6G(SCH_1):PAGE302',
 PART_TYPE='SMLF',
 MATERIAL='IC',
 PHYS_PAGE='266',
 XY='(-4450,2325)',
 ROT='6',
 VER='1',
 LOCATION='PPQ7',
 CDS_LIB='pure_quanta',
 CDS_PART_NAME='MOSFET_NCH_1D3S-PSMNR58-30YLH,SMLF,IC,BAMNR580000',
 ROOM='HSC BOM2',
 PART_NUMBER='BAMNR580000',
 VALUE='PSMNR58-30YLH',
 PRIM_FILE='./archive_libs/logical/mosfet_nch_1d3s/chips/chips.prt';

PART_NAME
 PPQ8 'MOSFET_NCH_1D3S-PSMNR58-30YLH,SMLF,IC,BAMNR580000':
 ROOM='HSC BOM2';

SECTION_NUMBER 1
 '@T6G_MB_LIB.T6G(SCH_1):PAGE302_I79@PURE_QUANTA.MOSFET_NCH_1D3S(CHIPS)':
 C_PATH='@t6g_mb_lib.t6g(sch_1):page302_i79@pure_quanta.mosfet_nch_1d3s(chips)',
 P_PATH='@t6g_mb_lib.t6g(sch_1):page266_i79@pure_quanta.mosfet_nch_1d3s(chips)',
 PATH='I79',
 DRAWING='@T6G_MB_LIB.T6G(SCH_1):PAGE302',
 PART_TYPE='SMLF',
 MATERIAL='IC',
 PHYS_PAGE='266',
 XY='(-3575,2325)',
 ROT='6',
 VER='1',
 LOCATION='PPQ8',
 CDS_LIB='pure_quanta',
 CDS_PART_NAME='MOSFET_NCH_1D3S-PSMNR58-30YLH,SMLF,IC,BAMNR580000',
 ROOM='HSC BOM2',
 PART_NUMBER='BAMNR580000',
 VALUE='PSMNR58-30YLH',
 PRIM_FILE='./archive_libs/logical/mosfet_nch_1d3s/chips/chips.prt';

PART_NAME
 PPQ9 'MOSFET_NCH_1D3S-PSMNR58-30YLH,SMLF,IC,BAMNR580000':
 ROOM='HSC BOM2';

SECTION_NUMBER 1
 '@T6G_MB_LIB.T6G(SCH_1):PAGE302_I75@PURE_QUANTA.MOSFET_NCH_1D3S(CHIPS)':
 C_PATH='@t6g_mb_lib.t6g(sch_1):page302_i75@pure_quanta.mosfet_nch_1d3s(chips)',
 P_PATH='@t6g_mb_lib.t6g(sch_1):page266_i75@pure_quanta.mosfet_nch_1d3s(chips)',
 PATH='I75',
 DRAWING='@T6G_MB_LIB.T6G(SCH_1):PAGE302',
 PART_TYPE='SMLF',
 MATERIAL='IC',
 PHYS_PAGE='266',
 XY='(-375,3525)',
 ROT='6',
 VER='1',
 LOCATION='PPQ9',
 CDS_LIB='pure_quanta',
 CDS_PART_NAME='MOSFET_NCH_1D3S-PSMNR58-30YLH,SMLF,IC,BAMNR580000',
 ROOM='HSC BOM2',
 PART_NUMBER='BAMNR580000',
 VALUE='PSMNR58-30YLH',
 PRIM_FILE='./archive_libs/logical/mosfet_nch_1d3s/chips/chips.prt';

PART_NAME
 PQ10 'MOSFET_PCH_GDS_ESD_PROTECTED-PJA3415AE,SMLF,IC,BAMA':;

SECTION_NUMBER 1
 '@T6G_MB_LIB.T6G(SCH_1):PAGE175_I13@PURE_QUANTA.MOSFET_PCH_GDS_ESD_PROTECTED(CHIPS)':
 C_PATH='@t6g_mb_lib.t6g(sch_1):page175_i13@pure_quanta.mosfet_pch_gds_esd_prote~
cted(chips)',
 P_PATH='@t6g_mb_lib.t6g(sch_1):page200_i13@pure_quanta.mosfet_pch_gds_esd_prote~
cted(chips)',
 PATH='I13',
 DRAWING='@T6G_MB_LIB.T6G(SCH_1):PAGE175',
 PART_TYPE='SMLF',
 MATERIAL='IC',
 PHYS_PAGE='200',
 XY='(-6975,2075)',
 ROT='6',
 VER='1',
 LOCATION='PQ10',
 CDS_LIB='pure_quanta',
 CDS_PART_NAME='MOSFET_PCH_GDS_ESD_PROTECTED-PJA3415AE,SMLF,IC,BAMA',
 PART_NUMBER='BAM34150008',
 VALUE='PJA3415AE',
 PRIM_FILE='./archive_libs/logical/mosfet_pch_gds_esd_protected/chips/chips.prt';

PART_NAME
 PQ11 'MOSFET_PCH_GDS_ESD_PROTECTED-PJA3415AE,SMLF,IC,BAMA':;

SECTION_NUMBER 1
 '@T6G_MB_LIB.T6G(SCH_1):PAGE185_I18@PURE_QUANTA.MOSFET_PCH_GDS_ESD_PROTECTED(CHIPS)':
 C_PATH='@t6g_mb_lib.t6g(sch_1):page185_i18@pure_quanta.mosfet_pch_gds_esd_prote~
cted(chips)',
 P_PATH='@t6g_mb_lib.t6g(sch_1):page210_i18@pure_quanta.mosfet_pch_gds_esd_prote~
cted(chips)',
 PATH='I18',
 DRAWING='@T6G_MB_LIB.T6G(SCH_1):PAGE185',
 PART_TYPE='SMLF',
 MATERIAL='IC',
 PHYS_PAGE='210',
 XY='(-3900,3625)',
 ROT='6',
 VER='1',
 LOCATION='PQ11',
 CDS_LIB='pure_quanta',
 CDS_PART_NAME='MOSFET_PCH_GDS_ESD_PROTECTED-PJA3415AE,SMLF,IC,BAMA',
 PART_NUMBER='BAM34150008',
 VALUE='PJA3415AE',
 PRIM_FILE='./archive_libs/logical/mosfet_pch_gds_esd_protected/chips/chips.prt';

PART_NAME
 PQ12 'MOSFET_PCH_GDS_ESD_PROTECTED-PJA3415AE,SMLF,IC,BAMA':;

SECTION_NUMBER 1
 '@T6G_MB_LIB.T6G(SCH_1):PAGE192_I13@PURE_QUANTA.MOSFET_PCH_GDS_ESD_PROTECTED(CHIPS)':
 C_PATH='@t6g_mb_lib.t6g(sch_1):page192_i13@pure_quanta.mosfet_pch_gds_esd_prote~
cted(chips)',
 P_PATH='@t6g_mb_lib.t6g(sch_1):page217_i13@pure_quanta.mosfet_pch_gds_esd_prote~
cted(chips)',
 PATH='I13',
 DRAWING='@T6G_MB_LIB.T6G(SCH_1):PAGE192',
 PART_TYPE='SMLF',
 MATERIAL='IC',
 PHYS_PAGE='217',
 XY='(-3325,3050)',
 ROT='6',
 VER='1',
 LOCATION='PQ12',
 CDS_LIB='pure_quanta',
 CDS_PART_NAME='MOSFET_PCH_GDS_ESD_PROTECTED-PJA3415AE,SMLF,IC,BAMA',
 PART_NUMBER='BAM34150008',
 VALUE='PJA3415AE',
 PRIM_FILE='./archive_libs/logical/mosfet_pch_gds_esd_protected/chips/chips.prt';

PART_NAME
 PQ13 'MOSFET_PCH_GDS_ESD_PROTECTED-PJA3415AE,SMLF,IC,BAMA':;

SECTION_NUMBER 1
 '@T6G_MB_LIB.T6G(SCH_1):PAGE168_I19@PURE_QUANTA.MOSFET_PCH_GDS_ESD_PROTECTED(CHIPS)':
 C_PATH='@t6g_mb_lib.t6g(sch_1):page168_i19@pure_quanta.mosfet_pch_gds_esd_prote~
cted(chips)',
 P_PATH='@t6g_mb_lib.t6g(sch_1):page193_i19@pure_quanta.mosfet_pch_gds_esd_prote~
cted(chips)',
 PATH='I19',
 DRAWING='@T6G_MB_LIB.T6G(SCH_1):PAGE168',
 PART_TYPE='SMLF',
 MATERIAL='IC',
 PHYS_PAGE='193',
 XY='(-6700,2250)',
 ROT='6',
 VER='1',
 LOCATION='PQ13',
 CDS_LIB='pure_quanta',
 CDS_PART_NAME='MOSFET_PCH_GDS_ESD_PROTECTED-PJA3415AE,SMLF,IC,BAMA',
 PART_NUMBER='BAM34150008',
 VALUE='PJA3415AE',
 PRIM_FILE='./archive_libs/logical/mosfet_pch_gds_esd_protected/chips/chips.prt';

PART_NAME
 PQ14 'MOSFET_N_SMLF-BSS138K,BSS138K,IC,BAM138K0000':;

SECTION_NUMBER 1
 '@T6G_MB_LIB.T6G(SCH_1):PAGE175_I6@PURE_QUANTA.MOSFET_N(CHIPS)':
 C_PATH='@t6g_mb_lib.t6g(sch_1):page175_i6@pure_quanta.mosfet_n(chips)',
 P_PATH='@t6g_mb_lib.t6g(sch_1):page200_i6@pure_quanta.mosfet_n(chips)',
 PATH='I6',
 DRAWING='@T6G_MB_LIB.T6G(SCH_1):PAGE175',
 MANUF_PN='BSS138K',
 MATERIAL='IC',
 PHYS_PAGE='200',
 XY='(-7650,1750)',
 ROT='0',
 VER='1',
 PACK_TYPE='SMLF',
 LOCATION='PQ14',
 CDS_LIB='pure_quanta',
 CDS_PART_NAME='MOSFET_N_SMLF-BSS138K,BSS138K,IC,BAM138K0000',
 PART_NUMBER='BAM138K0000',
 VALUE='BSS138K',
 PRIM_FILE='./archive_libs/logical/mosfet_n/chips/chips.prt';

PART_NAME
 PQ15 'MOSFET_N_SMLF-BSS138K,BSS138K,IC,BAM138K0000':;

SECTION_NUMBER 1
 '@T6G_MB_LIB.T6G(SCH_1):PAGE185_I16@PURE_QUANTA.MOSFET_N(CHIPS)':
 C_PATH='@t6g_mb_lib.t6g(sch_1):page185_i16@pure_quanta.mosfet_n(chips)',
 P_PATH='@t6g_mb_lib.t6g(sch_1):page210_i16@pure_quanta.mosfet_n(chips)',
 PATH='I16',
 DRAWING='@T6G_MB_LIB.T6G(SCH_1):PAGE185',
 MANUF_PN='BSS138K',
 MATERIAL='IC',
 PHYS_PAGE='210',
 XY='(-4600,3300)',
 ROT='0',
 VER='1',
 PACK_TYPE='SMLF',
 LOCATION='PQ15',
 CDS_LIB='pure_quanta',
 CDS_PART_NAME='MOSFET_N_SMLF-BSS138K,BSS138K,IC,BAM138K0000',
 PART_NUMBER='BAM138K0000',
 VALUE='BSS138K',
 PRIM_FILE='./archive_libs/logical/mosfet_n/chips/chips.prt';

PART_NAME
 PQ16 'MOSFET_N_SMLF-BSS138K,BSS138K,IC,BAM138K0000':;

SECTION_NUMBER 1
 '@T6G_MB_LIB.T6G(SCH_1):PAGE192_I6@PURE_QUANTA.MOSFET_N(CHIPS)':
 C_PATH='@t6g_mb_lib.t6g(sch_1):page192_i6@pure_quanta.mosfet_n(chips)',
 P_PATH='@t6g_mb_lib.t6g(sch_1):page217_i6@pure_quanta.mosfet_n(chips)',
 PATH='I6',
 DRAWING='@T6G_MB_LIB.T6G(SCH_1):PAGE192',
 MANUF_PN='BSS138K',
 MATERIAL='IC',
 PHYS_PAGE='217',
 XY='(-4050,2675)',
 ROT='0',
 VER='1',
 PACK_TYPE='SMLF',
 LOCATION='PQ16',
 CDS_LIB='pure_quanta',
 CDS_PART_NAME='MOSFET_N_SMLF-BSS138K,BSS138K,IC,BAM138K0000',
 PART_NUMBER='BAM138K0000',
 VALUE='BSS138K',
 PRIM_FILE='./archive_libs/logical/mosfet_n/chips/chips.prt';

PART_NAME
 PQ17 'MOSFET_N_SMLF-BSS138K,BSS138K,IC,BAM138K0000':;

SECTION_NUMBER 1
 '@T6G_MB_LIB.T6G(SCH_1):PAGE168_I17@PURE_QUANTA.MOSFET_N(CHIPS)':
 C_PATH='@t6g_mb_lib.t6g(sch_1):page168_i17@pure_quanta.mosfet_n(chips)',
 P_PATH='@t6g_mb_lib.t6g(sch_1):page193_i17@pure_quanta.mosfet_n(chips)',
 PATH='I17',
 DRAWING='@T6G_MB_LIB.T6G(SCH_1):PAGE168',
 MANUF_PN='BSS138K',
 MATERIAL='IC',
 PHYS_PAGE='193',
 XY='(-7400,1925)',
 ROT='0',
 VER='1',
 PACK_TYPE='SMLF',
 LOCATION='PQ17',
 CDS_LIB='pure_quanta',
 CDS_PART_NAME='MOSFET_N_SMLF-BSS138K,BSS138K,IC,BAM138K0000',
 PART_NUMBER='BAM138K0000',
 VALUE='BSS138K',
 PRIM_FILE='./archive_libs/logical/mosfet_n/chips/chips.prt';

PART_NAME
 PR3 'Q_RES_0402LF-10K,1%,1/16W,CHIP,CS31002FB08':;

SECTION_NUMBER 1
 '@T6G_MB_LIB.T6G(SCH_1):PAGE182_I6@PURE_QUANTA.Q_RES(CHIPS)':
 C_PATH='@t6g_mb_lib.t6g(sch_1):page182_i6@pure_quanta.q_res(chips)',
 P_PATH='@t6g_mb_lib.t6g(sch_1):page207_i6@pure_quanta.q_res(chips)',
 PATH='I6',
 DRAWING='@T6G_MB_LIB.T6G(SCH_1):PAGE182',
 SEC_TYPE='0402LF',
 WATTAGE='1/16W',
 TOLERANCE='1%',
 MATERIAL='CHIP',
 PHYS_PAGE='207',
 XY='(-6550,675)',
 ROT='0',
 VER='2',
 PACK_TYPE='0402LF',
 LOCATION='PR3',
 SEC='1',
 CDS_LIB='pure_quanta',
 CDS_PART_NAME='Q_RES_0402LF-10K,1%,1/16W,CHIP,CS31002FB08',
 PART_NUMBER='CS31002FB08',
 VALUE='10K',
 PRIM_FILE='./archive_libs/logical/q_res/chips/chips.prt';

PART_NAME
 PR4 'Q_RES_0402LF-10K,1%,1/16W,CHIP,CS31002FB08':;

SECTION_NUMBER 1
 '@T6G_MB_LIB.T6G(SCH_1):PAGE185_I20@PURE_QUANTA.Q_RES(CHIPS)':
 C_PATH='@t6g_mb_lib.t6g(sch_1):page185_i20@pure_quanta.q_res(chips)',
 P_PATH='@t6g_mb_lib.t6g(sch_1):page210_i20@pure_quanta.q_res(chips)',
 PATH='I20',
 DRAWING='@T6G_MB_LIB.T6G(SCH_1):PAGE185',
 SEC_TYPE='0402LF',
 WATTAGE='1/16W',
 TOLERANCE='1%',
 MATERIAL='CHIP',
 PHYS_PAGE='210',
 XY='(-3725,2425)',
 ROT='0',
 VER='2',
 PACK_TYPE='0402LF',
 LOCATION='PR4',
 SEC='1',
 CDS_LIB='pure_quanta',
 CDS_PART_NAME='Q_RES_0402LF-10K,1%,1/16W,CHIP,CS31002FB08',
 PART_NUMBER='CS31002FB08',
 VALUE='10K',
 PRIM_FILE='./archive_libs/logical/q_res/chips/chips.prt';

PART_NAME
 PR5 'Q_RES_0402LF-10K,1%,1/16W,CHIP,CS31002FB08':;

SECTION_NUMBER 1
 '@T6G_MB_LIB.T6G(SCH_1):PAGE168_I21@PURE_QUANTA.Q_RES(CHIPS)':
 C_PATH='@t6g_mb_lib.t6g(sch_1):page168_i21@pure_quanta.q_res(chips)',
 P_PATH='@t6g_mb_lib.t6g(sch_1):page193_i21@pure_quanta.q_res(chips)',
 PATH='I21',
 DRAWING='@T6G_MB_LIB.T6G(SCH_1):PAGE168',
 SEC_TYPE='0402LF',
 WATTAGE='1/16W',
 TOLERANCE='1%',
 MATERIAL='CHIP',
 PHYS_PAGE='193',
 XY='(-6525,1025)',
 ROT='0',
 VER='2',
 PACK_TYPE='0402LF',
 LOCATION='PR5',
 SEC='1',
 CDS_LIB='pure_quanta',
 CDS_PART_NAME='Q_RES_0402LF-10K,1%,1/16W,CHIP,CS31002FB08',
 PART_NUMBER='CS31002FB08',
 VALUE='10K',
 PRIM_FILE='./archive_libs/logical/q_res/chips/chips.prt';

PART_NAME
 PR6 'Q_RES_0402LF-10K,1%,1/16W,CHIP,CS31002FB08':;

SECTION_NUMBER 1
 '@T6G_MB_LIB.T6G(SCH_1):PAGE199_I6@PURE_QUANTA.Q_RES(CHIPS)':
 C_PATH='@t6g_mb_lib.t6g(sch_1):page199_i6@pure_quanta.q_res(chips)',
 P_PATH='@t6g_mb_lib.t6g(sch_1):page224_i6@pure_quanta.q_res(chips)',
 PATH='I6',
 DRAWING='@T6G_MB_LIB.T6G(SCH_1):PAGE199',
 SEC_TYPE='0402LF',
 WATTAGE='1/16W',
 TOLERANCE='1%',
 MATERIAL='CHIP',
 PHYS_PAGE='224',
 XY='(-6525,675)',
 ROT='0',
 VER='2',
 PACK_TYPE='0402LF',
 LOCATION='PR6',
 SEC='1',
 CDS_LIB='pure_quanta',
 CDS_PART_NAME='Q_RES_0402LF-10K,1%,1/16W,CHIP,CS31002FB08',
 PART_NUMBER='CS31002FB08',
 VALUE='10K',
 PRIM_FILE='./archive_libs/logical/q_res/chips/chips.prt';

PART_NAME
 PR7 'Q_RES_0402LF-8.87K,1%,1/16W,EMPTY,CS28872FB01':;

SECTION_NUMBER 1
 '@T6G_MB_LIB.T6G(SCH_1):PAGE178_I4@PURE_QUANTA.Q_RES(CHIPS)':
 C_PATH='@t6g_mb_lib.t6g(sch_1):page178_i4@pure_quanta.q_res(chips)',
 P_PATH='@t6g_mb_lib.t6g(sch_1):page203_i4@pure_quanta.q_res(chips)',
 PATH='I4',
 DRAWING='@T6G_MB_LIB.T6G(SCH_1):PAGE178',
 WATTAGE='1/16W',
 TOLERANCE='1%',
 MATERIAL='EMPTY',
 PHYS_PAGE='203',
 XY='(1450,1725)',
 ROT='2',
 VER='2',
 PACK_TYPE='0402LF',
 LOCATION='PR7',
 CDS_LIB='pure_quanta',
 CDS_PART_NAME='Q_RES_0402LF-8.87K,1%,1/16W,EMPTY,CS28872FB01',
 PART_NUMBER='CS28872FB01',
 VALUE='8.87K',
 PRIM_FILE='./archive_libs/logical/q_res/chips/chips.prt';

PART_NAME
 PR8 'Q_RES_0402LF-8.66K,1%,1/16W,CHIP,CS28662FB02':;

SECTION_NUMBER 1
 '@T6G_MB_LIB.T6G(SCH_1):PAGE201_I11@PURE_QUANTA.Q_RES(CHIPS)':
 C_PATH='@t6g_mb_lib.t6g(sch_1):page201_i11@pure_quanta.q_res(chips)',
 P_PATH='@t6g_mb_lib.t6g(sch_1):page226_i11@pure_quanta.q_res(chips)',
 PATH='I11',
 DRAWING='@T6G_MB_LIB.T6G(SCH_1):PAGE201',
 SEC_TYPE='0402LF',
 WATTAGE='1/16W',
 TOLERANCE='1%',
 MATERIAL='CHIP',
 PHYS_PAGE='226',
 XY='(-6375,2975)',
 ROT='0',
 VER='2',
 PACK_TYPE='0402LF',
 LOCATION='PR8',
 SEC='1',
 CDS_LIB='pure_quanta',
 CDS_PART_NAME='Q_RES_0402LF-8.66K,1%,1/16W,CHIP,CS28662FB02',
 PART_NUMBER='CS28662FB02',
 VALUE='8.66K',
 PRIM_FILE='./archive_libs/logical/q_res/chips/chips.prt';

PART_NAME
 PR12 'Q_RES_0402LF-0,5%,1/16W,CHIP,CS00002JB13':;

SECTION_NUMBER 1
 '@T6G_MB_LIB.T6G(SCH_1):PAGE192_I127@PURE_QUANTA.Q_RES(CHIPS)':
 C_PATH='@t6g_mb_lib.t6g(sch_1):page192_i127@pure_quanta.q_res(chips)',
 P_PATH='@t6g_mb_lib.t6g(sch_1):page217_i127@pure_quanta.q_res(chips)',
 PATH='I127',
 DRAWING='@T6G_MB_LIB.T6G(SCH_1):PAGE192',
 WATTAGE='1/16W',
 TOLERANCE='5%',
 MATERIAL='CHIP',
 PHYS_PAGE='217',
 XY='(925,4025)',
 ROT='0',
 VER='1',
 PACK_TYPE='0402LF',
 LOCATION='PR12',
 CDS_LIB='pure_quanta',
 CDS_PART_NAME='Q_RES_0402LF-0,5%,1/16W,CHIP,CS00002JB13',
 PART_NUMBER='CS00002JB13',
 VALUE='0',
 PRIM_FILE='./archive_libs/logical/q_res/chips/chips.prt';

PART_NAME
 PR13 'Q_RES_0402LF-0,5%,1/16W,CHIP,CS00002JB13':;

SECTION_NUMBER 1
 '@T6G_MB_LIB.T6G(SCH_1):PAGE199_I59@PURE_QUANTA.Q_RES(CHIPS)':
 C_PATH='@t6g_mb_lib.t6g(sch_1):page199_i59@pure_quanta.q_res(chips)',
 P_PATH='@t6g_mb_lib.t6g(sch_1):page224_i59@pure_quanta.q_res(chips)',
 PATH='I59',
 DRAWING='@T6G_MB_LIB.T6G(SCH_1):PAGE199',
 WATTAGE='1/16W',
 TOLERANCE='5%',
 MATERIAL='CHIP',
 PHYS_PAGE='224',
 XY='(-3125,3225)',
 ROT='0',
 VER='1',
 PACK_TYPE='0402LF',
 LOCATION='PR13',
 CDS_LIB='pure_quanta',
 CDS_PART_NAME='Q_RES_0402LF-0,5%,1/16W,CHIP,CS00002JB13',
 PART_NUMBER='CS00002JB13',
 VALUE='0',
 PRIM_FILE='./archive_libs/logical/q_res/chips/chips.prt';

PART_NAME
 PR14 'Q_RES_0402LF-0,5%,1/16W,CHIP,CS00002JB13':;

SECTION_NUMBER 1
 '@T6G_MB_LIB.T6G(SCH_1):PAGE199_I58@PURE_QUANTA.Q_RES(CHIPS)':
 C_PATH='@t6g_mb_lib.t6g(sch_1):page199_i58@pure_quanta.q_res(chips)',
 P_PATH='@t6g_mb_lib.t6g(sch_1):page224_i58@pure_quanta.q_res(chips)',
 PATH='I58',
 DRAWING='@T6G_MB_LIB.T6G(SCH_1):PAGE199',
 WATTAGE='1/16W',
 TOLERANCE='5%',
 MATERIAL='CHIP',
 PHYS_PAGE='224',
 XY='(-3125,2775)',
 ROT='0',
 VER='1',
 PACK_TYPE='0402LF',
 LOCATION='PR14',
 CDS_LIB='pure_quanta',
 CDS_PART_NAME='Q_RES_0402LF-0,5%,1/16W,CHIP,CS00002JB13',
 PART_NUMBER='CS00002JB13',
 VALUE='0',
 PRIM_FILE='./archive_libs/logical/q_res/chips/chips.prt';

PART_NAME
 PR32 'Q_RES_0402LF-0,5%,1/16W,CHIP,CS00002JB13':;

SECTION_NUMBER 1
 '@T6G_MB_LIB.T6G(SCH_1):PAGE175_I77@PURE_QUANTA.Q_RES(CHIPS)':
 C_PATH='@t6g_mb_lib.t6g(sch_1):page175_i77@pure_quanta.q_res(chips)',
 P_PATH='@t6g_mb_lib.t6g(sch_1):page200_i77@pure_quanta.q_res(chips)',
 PATH='I77',
 DRAWING='@T6G_MB_LIB.T6G(SCH_1):PAGE175',
 WATTAGE='1/16W',
 TOLERANCE='5%',
 MATERIAL='CHIP',
 PHYS_PAGE='200',
 XY='(-2675,3100)',
 ROT='0',
 VER='1',
 PACK_TYPE='0402LF',
 LOCATION='PR32',
 CDS_LIB='pure_quanta',
 CDS_PART_NAME='Q_RES_0402LF-0,5%,1/16W,CHIP,CS00002JB13',
 PART_NUMBER='CS00002JB13',
 VALUE='0',
 PRIM_FILE='./archive_libs/logical/q_res/chips/chips.prt';

PART_NAME
 PR33 'Q_RES_0402LF-0,5%,1/16W,CHIP,CS00002JB13':;

SECTION_NUMBER 1
 '@T6G_MB_LIB.T6G(SCH_1):PAGE182_I61@PURE_QUANTA.Q_RES(CHIPS)':
 C_PATH='@t6g_mb_lib.t6g(sch_1):page182_i61@pure_quanta.q_res(chips)',
 P_PATH='@t6g_mb_lib.t6g(sch_1):page207_i61@pure_quanta.q_res(chips)',
 PATH='I61',
 DRAWING='@T6G_MB_LIB.T6G(SCH_1):PAGE182',
 WATTAGE='1/16W',
 TOLERANCE='5%',
 MATERIAL='CHIP',
 PHYS_PAGE='207',
 XY='(-3150,3675)',
 ROT='0',
 VER='1',
 PACK_TYPE='0402LF',
 LOCATION='PR33',
 CDS_LIB='pure_quanta',
 CDS_PART_NAME='Q_RES_0402LF-0,5%,1/16W,CHIP,CS00002JB13',
 PART_NUMBER='CS00002JB13',
 VALUE='0',
 PRIM_FILE='./archive_libs/logical/q_res/chips/chips.prt';

PART_NAME
 PR34 'Q_RES_0402LF-0,5%,1/16W,CHIP,CS00002JB13':;

SECTION_NUMBER 1
 '@T6G_MB_LIB.T6G(SCH_1):PAGE182_I60@PURE_QUANTA.Q_RES(CHIPS)':
 C_PATH='@t6g_mb_lib.t6g(sch_1):page182_i60@pure_quanta.q_res(chips)',
 P_PATH='@t6g_mb_lib.t6g(sch_1):page207_i60@pure_quanta.q_res(chips)',
 PATH='I60',
 DRAWING='@T6G_MB_LIB.T6G(SCH_1):PAGE182',
 WATTAGE='1/16W',
 TOLERANCE='5%',
 MATERIAL='CHIP',
 PHYS_PAGE='207',
 XY='(-3150,3225)',
 ROT='0',
 VER='1',
 PACK_TYPE='0402LF',
 LOCATION='PR34',
 CDS_LIB='pure_quanta',
 CDS_PART_NAME='Q_RES_0402LF-0,5%,1/16W,CHIP,CS00002JB13',
 PART_NUMBER='CS00002JB13',
 VALUE='0',
 PRIM_FILE='./archive_libs/logical/q_res/chips/chips.prt';

PART_NAME
 PR35 'Q_RES_0402LF-0,5%,1/16W,CHIP,CS00002JB13':;

SECTION_NUMBER 1
 '@T6G_MB_LIB.T6G(SCH_1):PAGE182_I59@PURE_QUANTA.Q_RES(CHIPS)':
 C_PATH='@t6g_mb_lib.t6g(sch_1):page182_i59@pure_quanta.q_res(chips)',
 P_PATH='@t6g_mb_lib.t6g(sch_1):page207_i59@pure_quanta.q_res(chips)',
 PATH='I59',
 DRAWING='@T6G_MB_LIB.T6G(SCH_1):PAGE182',
 WATTAGE='1/16W',
 TOLERANCE='5%',
 MATERIAL='CHIP',
 PHYS_PAGE='207',
 XY='(-3150,2775)',
 ROT='0',
 VER='1',
 PACK_TYPE='0402LF',
 LOCATION='PR35',
 CDS_LIB='pure_quanta',
 CDS_PART_NAME='Q_RES_0402LF-0,5%,1/16W,CHIP,CS00002JB13',
 PART_NUMBER='CS00002JB13',
 VALUE='0',
 PRIM_FILE='./archive_libs/logical/q_res/chips/chips.prt';

PART_NAME
 PR36 'Q_RES_0402LF-0,5%,1/16W,CHIP,CS00002JB13':;

SECTION_NUMBER 1
 '@T6G_MB_LIB.T6G(SCH_1):PAGE182_I53@PURE_QUANTA.Q_RES(CHIPS)':
 C_PATH='@t6g_mb_lib.t6g(sch_1):page182_i53@pure_quanta.q_res(chips)',
 P_PATH='@t6g_mb_lib.t6g(sch_1):page207_i53@pure_quanta.q_res(chips)',
 PATH='I53',
 DRAWING='@T6G_MB_LIB.T6G(SCH_1):PAGE182',
 WATTAGE='1/16W',
 TOLERANCE='5%',
 MATERIAL='CHIP',
 PHYS_PAGE='207',
 XY='(-3150,1875)',
 ROT='0',
 VER='1',
 PACK_TYPE='0402LF',
 LOCATION='PR36',
 CDS_LIB='pure_quanta',
 CDS_PART_NAME='Q_RES_0402LF-0,5%,1/16W,CHIP,CS00002JB13',
 PART_NUMBER='CS00002JB13',
 VALUE='0',
 PRIM_FILE='./archive_libs/logical/q_res/chips/chips.prt';

PART_NAME
 PR37 'Q_RES_0402LF-0,5%,1/16W,CHIP,CS00002JB13':;

SECTION_NUMBER 1
 '@T6G_MB_LIB.T6G(SCH_1):PAGE182_I71@PURE_QUANTA.Q_RES(CHIPS)':
 C_PATH='@t6g_mb_lib.t6g(sch_1):page182_i71@pure_quanta.q_res(chips)',
 P_PATH='@t6g_mb_lib.t6g(sch_1):page207_i71@pure_quanta.q_res(chips)',
 PATH='I71',
 DRAWING='@T6G_MB_LIB.T6G(SCH_1):PAGE182',
 WATTAGE='1/16W',
 TOLERANCE='5%',
 MATERIAL='CHIP',
 PHYS_PAGE='207',
 XY='(-3125,4125)',
 ROT='0',
 VER='1',
 PACK_TYPE='0402LF',
 LOCATION='PR37',
 CDS_LIB='pure_quanta',
 CDS_PART_NAME='Q_RES_0402LF-0,5%,1/16W,CHIP,CS00002JB13',
 PART_NUMBER='CS00002JB13',
 VALUE='0',
 PRIM_FILE='./archive_libs/logical/q_res/chips/chips.prt';

PART_NAME
 PR40 'Q_RES_0402LF-0,5%,1/16W,CHIP,CS00002JB13':;

SECTION_NUMBER 1
 '@T6G_MB_LIB.T6G(SCH_1):PAGE175_I28@PURE_QUANTA.Q_RES(CHIPS)':
 C_PATH='@t6g_mb_lib.t6g(sch_1):page175_i28@pure_quanta.q_res(chips)',
 P_PATH='@t6g_mb_lib.t6g(sch_1):page200_i28@pure_quanta.q_res(chips)',
 PATH='I28',
 DRAWING='@T6G_MB_LIB.T6G(SCH_1):PAGE175',
 WATTAGE='1/16W',
 TOLERANCE='5%',
 MATERIAL='CHIP',
 PHYS_PAGE='200',
 XY='(-8650,5200)',
 ROT='0',
 VER='2',
 PACK_TYPE='0402LF',
 LOCATION='PR40',
 CDS_LIB='pure_quanta',
 CDS_PART_NAME='Q_RES_0402LF-0,5%,1/16W,CHIP,CS00002JB13',
 PART_NUMBER='CS00002JB13',
 VALUE='0',
 PRIM_FILE='./archive_libs/logical/q_res/chips/chips.prt';

PART_NAME
 PR41 'Q_RES_0402LF-1K,1%,1/16W,EMPTY,CS21002FB06':;

SECTION_NUMBER 1
 '@T6G_MB_LIB.T6G(SCH_1):PAGE175_I40@PURE_QUANTA.Q_RES(CHIPS)':
 C_PATH='@t6g_mb_lib.t6g(sch_1):page175_i40@pure_quanta.q_res(chips)',
 P_PATH='@t6g_mb_lib.t6g(sch_1):page200_i40@pure_quanta.q_res(chips)',
 PATH='I40',
 DRAWING='@T6G_MB_LIB.T6G(SCH_1):PAGE175',
 WATTAGE='1/16W',
 TOLERANCE='1%',
 MATERIAL='EMPTY',
 PHYS_PAGE='200',
 XY='(-8550,6175)',
 ROT='0',
 VER='2',
 PACK_TYPE='0402LF',
 LOCATION='PR41',
 CDS_LIB='pure_quanta',
 CDS_PART_NAME='Q_RES_0402LF-1K,1%,1/16W,EMPTY,CS21002FB06',
 PART_NUMBER='CS21002FB06',
 VALUE='1K',
 PRIM_FILE='./archive_libs/logical/q_res/chips/chips.prt';

PART_NAME
 PR46 'Q_RES_0402LF-1.5,1%,1/8W,EMPTY,CS-1504FB00':;

SECTION_NUMBER 1
 '@T6G_MB_LIB.T6G(SCH_1):PAGE188_I32@PURE_QUANTA.Q_RES(CHIPS)':
 C_PATH='@t6g_mb_lib.t6g(sch_1):page188_i32@pure_quanta.q_res(chips)',
 P_PATH='@t6g_mb_lib.t6g(sch_1):page213_i32@pure_quanta.q_res(chips)',
 PATH='I32',
 DRAWING='@T6G_MB_LIB.T6G(SCH_1):PAGE188',
 WATTAGE='1/8W',
 TOLERANCE='1%',
 MATERIAL='EMPTY',
 PHYS_PAGE='213',
 XY='(-4275,4125)',
 ROT='0',
 VER='2',
 PACK_TYPE='0402LF',
 LOCATION='PR46',
 CDS_LIB='pure_quanta',
 CDS_PART_NAME='Q_RES_0402LF-1.5,1%,1/8W,EMPTY,CS-1504FB00',
 PART_NUMBER='CS-1504FB00',
 VALUE='1.5',
 PRIM_FILE='./archive_libs/logical/q_res/chips/chips.prt';

PART_NAME
 PR49 'Q_RES_0402LF-49.9,1%,1/16W,CHIP,CS04992FB07':;

SECTION_NUMBER 1
 '@T6G_MB_LIB.T6G(SCH_1):PAGE175_I23@PURE_QUANTA.Q_RES(CHIPS)':
 C_PATH='@t6g_mb_lib.t6g(sch_1):page175_i23@pure_quanta.q_res(chips)',
 P_PATH='@t6g_mb_lib.t6g(sch_1):page200_i23@pure_quanta.q_res(chips)',
 PATH='I23',
 DRAWING='@T6G_MB_LIB.T6G(SCH_1):PAGE175',
 WATTAGE='1/16W',
 TOLERANCE='1%',
 MATERIAL='CHIP',
 PHYS_PAGE='200',
 XY='(-7150,3775)',
 ROT='0',
 VER='1',
 PACK_TYPE='0402LF',
 LOCATION='PR49',
 CDS_LIB='pure_quanta',
 CDS_PART_NAME='Q_RES_0402LF-49.9,1%,1/16W,CHIP,CS04992FB07',
 PART_NUMBER='CS04992FB07',
 VALUE='49.9',
 PRIM_FILE='./archive_libs/logical/q_res/chips/chips.prt';

PART_NAME
 PR50 'Q_RES_0402LF-49.9,1%,1/16W,CHIP,CS04992FB07':;

SECTION_NUMBER 1
 '@T6G_MB_LIB.T6G(SCH_1):PAGE175_I19@PURE_QUANTA.Q_RES(CHIPS)':
 C_PATH='@t6g_mb_lib.t6g(sch_1):page175_i19@pure_quanta.q_res(chips)',
 P_PATH='@t6g_mb_lib.t6g(sch_1):page200_i19@pure_quanta.q_res(chips)',
 PATH='I19',
 DRAWING='@T6G_MB_LIB.T6G(SCH_1):PAGE175',
 WATTAGE='1/16W',
 TOLERANCE='1%',
 MATERIAL='CHIP',
 PHYS_PAGE='200',
 XY='(-7150,2675)',
 ROT='0',
 VER='1',
 PACK_TYPE='0402LF',
 LOCATION='PR50',
 CDS_LIB='pure_quanta',
 CDS_PART_NAME='Q_RES_0402LF-49.9,1%,1/16W,CHIP,CS04992FB07',
 PART_NUMBER='CS04992FB07',
 VALUE='49.9',
 PRIM_FILE='./archive_libs/logical/q_res/chips/chips.prt';

PART_NAME
 PR51 'Q_RES_0402LF-49.9,1%,1/16W,CHIP,CS04992FB07':;

SECTION_NUMBER 1
 '@T6G_MB_LIB.T6G(SCH_1):PAGE175_I36@PURE_QUANTA.Q_RES(CHIPS)':
 C_PATH='@t6g_mb_lib.t6g(sch_1):page175_i36@pure_quanta.q_res(chips)',
 P_PATH='@t6g_mb_lib.t6g(sch_1):page200_i36@pure_quanta.q_res(chips)',
 PATH='I36',
 DRAWING='@T6G_MB_LIB.T6G(SCH_1):PAGE175',
 WATTAGE='1/16W',
 TOLERANCE='1%',
 MATERIAL='CHIP',
 PHYS_PAGE='200',
 XY='(-7100,4450)',
 ROT='0',
 VER='1',
 PACK_TYPE='0402LF',
 LOCATION='PR51',
 CDS_LIB='pure_quanta',
 CDS_PART_NAME='Q_RES_0402LF-49.9,1%,1/16W,CHIP,CS04992FB07',
 PART_NUMBER='CS04992FB07',
 VALUE='49.9',
 PRIM_FILE='./archive_libs/logical/q_res/chips/chips.prt';

PART_NAME
 PR52 'Q_RES_0402LF-49.9,1%,1/16W,CHIP,CS04992FB07':;

SECTION_NUMBER 1
 '@T6G_MB_LIB.T6G(SCH_1):PAGE175_I22@PURE_QUANTA.Q_RES(CHIPS)':
 C_PATH='@t6g_mb_lib.t6g(sch_1):page175_i22@pure_quanta.q_res(chips)',
 P_PATH='@t6g_mb_lib.t6g(sch_1):page200_i22@pure_quanta.q_res(chips)',
 PATH='I22',
 DRAWING='@T6G_MB_LIB.T6G(SCH_1):PAGE175',
 WATTAGE='1/16W',
 TOLERANCE='1%',
 MATERIAL='CHIP',
 PHYS_PAGE='200',
 XY='(-7100,3350)',
 ROT='0',
 VER='1',
 PACK_TYPE='0402LF',
 LOCATION='PR52',
 CDS_LIB='pure_quanta',
 CDS_PART_NAME='Q_RES_0402LF-49.9,1%,1/16W,CHIP,CS04992FB07',
 PART_NUMBER='CS04992FB07',
 VALUE='49.9',
 PRIM_FILE='./archive_libs/logical/q_res/chips/chips.prt';

PART_NAME
 PR53 'Q_RES_0402LF-40.2K,1%,1/16W,CHIP,CS34022FB04':;

SECTION_NUMBER 1
 '@T6G_MB_LIB.T6G(SCH_1):PAGE175_I9@PURE_QUANTA.Q_RES(CHIPS)':
 C_PATH='@t6g_mb_lib.t6g(sch_1):page175_i9@pure_quanta.q_res(chips)',
 P_PATH='@t6g_mb_lib.t6g(sch_1):page200_i9@pure_quanta.q_res(chips)',
 PATH='I9',
 DRAWING='@T6G_MB_LIB.T6G(SCH_1):PAGE175',
 WATTAGE='1/16W',
 TOLERANCE='1%',
 MATERIAL='CHIP',
 PHYS_PAGE='200',
 XY='(-6975,950)',
 ROT='0',
 VER='1',
 PACK_TYPE='0402LF',
 LOCATION='PR53',
 CDS_LIB='pure_quanta',
 CDS_PART_NAME='Q_RES_0402LF-40.2K,1%,1/16W,CHIP,CS34022FB04',
 PART_NUMBER='CS34022FB04',
 VALUE='40.2K',
 PRIM_FILE='./archive_libs/logical/q_res/chips/chips.prt';

PART_NAME
 PR54 'Q_RES_0402LF-10K,1%,1/16W,CHIP,CS31002FB08':;

SECTION_NUMBER 1
 '@T6G_MB_LIB.T6G(SCH_1):PAGE175_I8@PURE_QUANTA.Q_RES(CHIPS)':
 C_PATH='@t6g_mb_lib.t6g(sch_1):page175_i8@pure_quanta.q_res(chips)',
 P_PATH='@t6g_mb_lib.t6g(sch_1):page200_i8@pure_quanta.q_res(chips)',
 PATH='I8',
 DRAWING='@T6G_MB_LIB.T6G(SCH_1):PAGE175',
 WATTAGE='1/16W',
 TOLERANCE='1%',
 MATERIAL='CHIP',
 PHYS_PAGE='200',
 XY='(-6650,775)',
 ROT='0',
 VER='2',
 PACK_TYPE='0402LF',
 LOCATION='PR54',
 CDS_LIB='pure_quanta',
 CDS_PART_NAME='Q_RES_0402LF-10K,1%,1/16W,CHIP,CS31002FB08',
 PART_NUMBER='CS31002FB08',
 VALUE='10K',
 PRIM_FILE='./archive_libs/logical/q_res/chips/chips.prt';

PART_NAME
 PR55 'Q_RES_0402LF-1K,1%,1/16W,CHIP,CS21002FB06':;

SECTION_NUMBER 1
 '@T6G_MB_LIB.T6G(SCH_1):PAGE175_I17@PURE_QUANTA.Q_RES(CHIPS)':
 C_PATH='@t6g_mb_lib.t6g(sch_1):page175_i17@pure_quanta.q_res(chips)',
 P_PATH='@t6g_mb_lib.t6g(sch_1):page200_i17@pure_quanta.q_res(chips)',
 PATH='I17',
 DRAWING='@T6G_MB_LIB.T6G(SCH_1):PAGE175',
 WATTAGE='1/16W',
 TOLERANCE='1%',
 MATERIAL='CHIP',
 PHYS_PAGE='200',
 XY='(-7600,2275)',
 ROT='0',
 VER='2',
 PACK_TYPE='0402LF',
 LOCATION='PR55',
 CDS_LIB='pure_quanta',
 CDS_PART_NAME='Q_RES_0402LF-1K,1%,1/16W,CHIP,CS21002FB06',
 PART_NUMBER='CS21002FB06',
 VALUE='1K',
 PRIM_FILE='./archive_libs/logical/q_res/chips/chips.prt';

PART_NAME
 PR59 'Q_RES_0402LF-0,5%,1/16W,CHIP,CS00002JB13':;

SECTION_NUMBER 1
 '@T6G_MB_LIB.T6G(SCH_1):PAGE27_I318@PURE_QUANTA.Q_RES(CHIPS)':
 C_PATH='@t6g_mb_lib.t6g(sch_1):page27_i318@pure_quanta.q_res(chips)',
 P_PATH='@t6g_mb_lib.t6g(sch_1):page27_i318@pure_quanta.q_res(chips)',
 PATH='I318',
 DRAWING='@T6G_MB_LIB.T6G(SCH_1):PAGE27',
 WATTAGE='1/16W',
 TOLERANCE='5%',
 MATERIAL='CHIP',
 PHYS_PAGE='27',
 XY='(-6350,5325)',
 ROT='0',
 VER='1',
 PACK_TYPE='0402LF',
 LOCATION='PR59',
 CDS_LIB='pure_quanta',
 CDS_PART_NAME='Q_RES_0402LF-0,5%,1/16W,CHIP,CS00002JB13',
 PART_NUMBER='CS00002JB13',
 VALUE='0',
 PRIM_FILE='./archive_libs/logical/q_res/chips/chips.prt';

PART_NAME
 PR60 'Q_RES_0402LF-0,5%,1/16W,CHIP,CS00002JB13':;

SECTION_NUMBER 1
 '@T6G_MB_LIB.T6G(SCH_1):PAGE27_I319@PURE_QUANTA.Q_RES(CHIPS)':
 C_PATH='@t6g_mb_lib.t6g(sch_1):page27_i319@pure_quanta.q_res(chips)',
 P_PATH='@t6g_mb_lib.t6g(sch_1):page27_i319@pure_quanta.q_res(chips)',
 PATH='I319',
 DRAWING='@T6G_MB_LIB.T6G(SCH_1):PAGE27',
 WATTAGE='1/16W',
 TOLERANCE='5%',
 MATERIAL='CHIP',
 PHYS_PAGE='27',
 XY='(-6350,5275)',
 ROT='0',
 VER='1',
 PACK_TYPE='0402LF',
 LOCATION='PR60',
 CDS_LIB='pure_quanta',
 CDS_PART_NAME='Q_RES_0402LF-0,5%,1/16W,CHIP,CS00002JB13',
 PART_NUMBER='CS00002JB13',
 VALUE='0',
 PRIM_FILE='./archive_libs/logical/q_res/chips/chips.prt';

PART_NAME
 PR62 'Q_RES_0402LF-0,5%,1/16W,CHIP,CS00002JB13':;

SECTION_NUMBER 1
 '@T6G_MB_LIB.T6G(SCH_1):PAGE175_I84@PURE_QUANTA.Q_RES(CHIPS)':
 C_PATH='@t6g_mb_lib.t6g(sch_1):page175_i84@pure_quanta.q_res(chips)',
 P_PATH='@t6g_mb_lib.t6g(sch_1):page200_i84@pure_quanta.q_res(chips)',
 PATH='I84',
 DRAWING='@T6G_MB_LIB.T6G(SCH_1):PAGE175',
 WATTAGE='1/16W',
 TOLERANCE='5%',
 MATERIAL='CHIP',
 PHYS_PAGE='200',
 XY='(-6475,5400)',
 ROT='0',
 VER='1',
 PACK_TYPE='0402LF',
 LOCATION='PR62',
 CDS_LIB='pure_quanta',
 CDS_PART_NAME='Q_RES_0402LF-0,5%,1/16W,CHIP,CS00002JB13',
 PART_NUMBER='CS00002JB13',
 VALUE='0',
 PRIM_FILE='./archive_libs/logical/q_res/chips/chips.prt';

PART_NAME
 PR67 'Q_RES_0402LF-1.96K,1%,1/16W,CHIP,CS21962FB05':;

SECTION_NUMBER 1
 '@T6G_MB_LIB.T6G(SCH_1):PAGE175_I12@PURE_QUANTA.Q_RES(CHIPS)':
 C_PATH='@t6g_mb_lib.t6g(sch_1):page175_i12@pure_quanta.q_res(chips)',
 P_PATH='@t6g_mb_lib.t6g(sch_1):page200_i12@pure_quanta.q_res(chips)',
 PATH='I12',
 DRAWING='@T6G_MB_LIB.T6G(SCH_1):PAGE175',
 WATTAGE='1/16W',
 TOLERANCE='1%',
 MATERIAL='CHIP',
 PHYS_PAGE='200',
 XY='(-6950,1600)',
 ROT='0',
 VER='2',
 PACK_TYPE='0402LF',
 LOCATION='PR67',
 CDS_LIB='pure_quanta',
 CDS_PART_NAME='Q_RES_0402LF-1.96K,1%,1/16W,CHIP,CS21962FB05',
 PART_NUMBER='CS21962FB05',
 VALUE='1.96K',
 PRIM_FILE='./archive_libs/logical/q_res/chips/chips.prt';

PART_NAME
 PR68 'Q_RES_0402LF-0,5%,1/16W,CHIP,CS00002JB13':;

SECTION_NUMBER 1
 '@T6G_MB_LIB.T6G(SCH_1):PAGE175_I78@PURE_QUANTA.Q_RES(CHIPS)':
 C_PATH='@t6g_mb_lib.t6g(sch_1):page175_i78@pure_quanta.q_res(chips)',
 P_PATH='@t6g_mb_lib.t6g(sch_1):page200_i78@pure_quanta.q_res(chips)',
 PATH='I78',
 DRAWING='@T6G_MB_LIB.T6G(SCH_1):PAGE175',
 WATTAGE='1/16W',
 TOLERANCE='5%',
 MATERIAL='CHIP',
 PHYS_PAGE='200',
 XY='(-6125,4300)',
 ROT='0',
 VER='1',
 PACK_TYPE='0402LF',
 LOCATION='PR68',
 CDS_LIB='pure_quanta',
 CDS_PART_NAME='Q_RES_0402LF-0,5%,1/16W,CHIP,CS00002JB13',
 PART_NUMBER='CS00002JB13',
 VALUE='0',
 PRIM_FILE='./archive_libs/logical/q_res/chips/chips.prt';

PART_NAME
 PR69 'Q_RES_0402LF-0,5%,1/16W,CHIP,CS00002JB13':;

SECTION_NUMBER 1
 '@T6G_MB_LIB.T6G(SCH_1):PAGE175_I70@PURE_QUANTA.Q_RES(CHIPS)':
 C_PATH='@t6g_mb_lib.t6g(sch_1):page175_i70@pure_quanta.q_res(chips)',
 P_PATH='@t6g_mb_lib.t6g(sch_1):page200_i70@pure_quanta.q_res(chips)',
 PATH='I70',
 DRAWING='@T6G_MB_LIB.T6G(SCH_1):PAGE175',
 WATTAGE='1/16W',
 TOLERANCE='5%',
 MATERIAL='CHIP',
 PHYS_PAGE='200',
 XY='(-6075,3200)',
 ROT='0',
 VER='1',
 PACK_TYPE='0402LF',
 LOCATION='PR69',
 CDS_LIB='pure_quanta',
 CDS_PART_NAME='Q_RES_0402LF-0,5%,1/16W,CHIP,CS00002JB13',
 PART_NUMBER='CS00002JB13',
 VALUE='0',
 PRIM_FILE='./archive_libs/logical/q_res/chips/chips.prt';

PART_NAME
 PR74 'Q_RES_0402LF-0,5%,1/16W,CHIP,CS00002JB13':;

SECTION_NUMBER 1
 '@T6G_MB_LIB.T6G(SCH_1):PAGE175_I51@PURE_QUANTA.Q_RES(CHIPS)':
 C_PATH='@t6g_mb_lib.t6g(sch_1):page175_i51@pure_quanta.q_res(chips)',
 P_PATH='@t6g_mb_lib.t6g(sch_1):page200_i51@pure_quanta.q_res(chips)',
 PATH='I51',
 DRAWING='@T6G_MB_LIB.T6G(SCH_1):PAGE175',
 WATTAGE='1/16W',
 TOLERANCE='5%',
 MATERIAL='CHIP',
 PHYS_PAGE='200',
 XY='(-5750,775)',
 ROT='0',
 VER='1',
 PACK_TYPE='0402LF',
 LOCATION='PR74',
 CDS_LIB='pure_quanta',
 CDS_PART_NAME='Q_RES_0402LF-0,5%,1/16W,CHIP,CS00002JB13',
 PART_NUMBER='CS00002JB13',
 VALUE='0',
 PRIM_FILE='./archive_libs/logical/q_res/chips/chips.prt';

PART_NAME
 PR76 'Q_RES_0402LF-1,1%,1/16W,CHIP,CS-1002FB04':;

SECTION_NUMBER 1
 '@T6G_MB_LIB.T6G(SCH_1):PAGE175_I126@PURE_QUANTA.Q_RES(CHIPS)':
 C_PATH='@t6g_mb_lib.t6g(sch_1):page175_i126@pure_quanta.q_res(chips)',
 P_PATH='@t6g_mb_lib.t6g(sch_1):page200_i126@pure_quanta.q_res(chips)',
 PATH='I126',
 DRAWING='@T6G_MB_LIB.T6G(SCH_1):PAGE175',
 WATTAGE='1/16W',
 TOLERANCE='1%',
 MATERIAL='CHIP',
 PHYS_PAGE='200',
 XY='(-2300,6300)',
 ROT='0',
 VER='1',
 PACK_TYPE='0402LF',
 LOCATION='PR76',
 CDS_LIB='pure_quanta',
 CDS_PART_NAME='Q_RES_0402LF-1,1%,1/16W,CHIP,CS-1002FB04',
 PART_NUMBER='CS-1002FB04',
 VALUE='1',
 PRIM_FILE='./archive_libs/logical/q_res/chips/chips.prt';

PART_NAME
 PR77 'Q_RES_0402LF-8.87K,1%,1/16W,EMPTY,CS28872FB01':;

SECTION_NUMBER 1
 '@T6G_MB_LIB.T6G(SCH_1):PAGE176_I4@PURE_QUANTA.Q_RES(CHIPS)':
 C_PATH='@t6g_mb_lib.t6g(sch_1):page176_i4@pure_quanta.q_res(chips)',
 P_PATH='@t6g_mb_lib.t6g(sch_1):page201_i4@pure_quanta.q_res(chips)',
 PATH='I4',
 DRAWING='@T6G_MB_LIB.T6G(SCH_1):PAGE176',
 WATTAGE='1/16W',
 TOLERANCE='1%',
 MATERIAL='EMPTY',
 PHYS_PAGE='201',
 XY='(-9150,675)',
 ROT='2',
 VER='2',
 PACK_TYPE='0402LF',
 LOCATION='PR77',
 CDS_LIB='pure_quanta',
 CDS_PART_NAME='Q_RES_0402LF-8.87K,1%,1/16W,EMPTY,CS28872FB01',
 PART_NUMBER='CS28872FB01',
 VALUE='8.87K',
 PRIM_FILE='./archive_libs/logical/q_res/chips/chips.prt';

PART_NAME
 PR78 'Q_RES_0402LF-8.87K,1%,1/16W,EMPTY,CS28872FB01':;

SECTION_NUMBER 1
 '@T6G_MB_LIB.T6G(SCH_1):PAGE176_I18@PURE_QUANTA.Q_RES(CHIPS)':
 C_PATH='@t6g_mb_lib.t6g(sch_1):page176_i18@pure_quanta.q_res(chips)',
 P_PATH='@t6g_mb_lib.t6g(sch_1):page201_i18@pure_quanta.q_res(chips)',
 PATH='I18',
 DRAWING='@T6G_MB_LIB.T6G(SCH_1):PAGE176',
 WATTAGE='1/16W',
 TOLERANCE='1%',
 MATERIAL='EMPTY',
 PHYS_PAGE='201',
 XY='(-9125,3625)',
 ROT='2',
 VER='2',
 PACK_TYPE='0402LF',
 LOCATION='PR78',
 CDS_LIB='pure_quanta',
 CDS_PART_NAME='Q_RES_0402LF-8.87K,1%,1/16W,EMPTY,CS28872FB01',
 PART_NUMBER='CS28872FB01',
 VALUE='8.87K',
 PRIM_FILE='./archive_libs/logical/q_res/chips/chips.prt';

PART_NAME
 PR79 'Q_RES_0402LF-2.2,1%,1/16W,CHIP,CS-2202FB01':;

SECTION_NUMBER 1
 '@T6G_MB_LIB.T6G(SCH_1):PAGE176_I29@PURE_QUANTA.Q_RES(CHIPS)':
 C_PATH='@t6g_mb_lib.t6g(sch_1):page176_i29@pure_quanta.q_res(chips)',
 P_PATH='@t6g_mb_lib.t6g(sch_1):page201_i29@pure_quanta.q_res(chips)',
 PATH='I29',
 DRAWING='@T6G_MB_LIB.T6G(SCH_1):PAGE176',
 WATTAGE='1/16W',
 TOLERANCE='1%',
 MATERIAL='CHIP',
 PHYS_PAGE='201',
 XY='(-8975,5050)',
 ROT='0',
 VER='2',
 PACK_TYPE='0402LF',
 LOCATION='PR79',
 CDS_LIB='pure_quanta',
 CDS_PART_NAME='Q_RES_0402LF-2.2,1%,1/16W,CHIP,CS-2202FB01',
 PART_NUMBER='CS-2202FB01',
 VALUE='2.2',
 PRIM_FILE='./archive_libs/logical/q_res/chips/chips.prt';

PART_NAME
 PR80 'Q_RES_0402LF-2.2,1%,1/16W,CHIP,CS-2202FB01':;

SECTION_NUMBER 1
 '@T6G_MB_LIB.T6G(SCH_1):PAGE176_I13@PURE_QUANTA.Q_RES(CHIPS)':
 C_PATH='@t6g_mb_lib.t6g(sch_1):page176_i13@pure_quanta.q_res(chips)',
 P_PATH='@t6g_mb_lib.t6g(sch_1):page201_i13@pure_quanta.q_res(chips)',
 PATH='I13',
 DRAWING='@T6G_MB_LIB.T6G(SCH_1):PAGE176',
 WATTAGE='1/16W',
 TOLERANCE='1%',
 MATERIAL='CHIP',
 PHYS_PAGE='201',
 XY='(-8875,2150)',
 ROT='0',
 VER='2',
 PACK_TYPE='0402LF',
 LOCATION='PR80',
 CDS_LIB='pure_quanta',
 CDS_PART_NAME='Q_RES_0402LF-2.2,1%,1/16W,CHIP,CS-2202FB01',
 PART_NUMBER='CS-2202FB01',
 VALUE='2.2',
 PRIM_FILE='./archive_libs/logical/q_res/chips/chips.prt';

PART_NAME
 PR81 'Q_RES_0402LF-5.6,1%,1/16W,CHIP,CS-5602FB01':;

SECTION_NUMBER 1
 '@T6G_MB_LIB.T6G(SCH_1):PAGE176_I40@PURE_QUANTA.Q_RES(CHIPS)':
 C_PATH='@t6g_mb_lib.t6g(sch_1):page176_i40@pure_quanta.q_res(chips)',
 P_PATH='@t6g_mb_lib.t6g(sch_1):page201_i40@pure_quanta.q_res(chips)',
 PATH='I40',
 DRAWING='@T6G_MB_LIB.T6G(SCH_1):PAGE176',
 WATTAGE='1/16W',
 TOLERANCE='1%',
 MATERIAL='CHIP',
 PHYS_PAGE='201',
 XY='(-5975,1525)',
 ROT='0',
 VER='1',
 PACK_TYPE='0402LF',
 LOCATION='PR81',
 CDS_LIB='pure_quanta',
 CDS_PART_NAME='Q_RES_0402LF-5.6,1%,1/16W,CHIP,CS-5602FB01',
 PART_NUMBER='CS-5602FB01',
 VALUE='5.6',
 PRIM_FILE='./archive_libs/logical/q_res/chips/chips.prt';

PART_NAME
 PR82 'Q_RES_0402LF-5.6,1%,1/16W,CHIP,CS-5602FB01':;

SECTION_NUMBER 1
 '@T6G_MB_LIB.T6G(SCH_1):PAGE176_I56@PURE_QUANTA.Q_RES(CHIPS)':
 C_PATH='@t6g_mb_lib.t6g(sch_1):page176_i56@pure_quanta.q_res(chips)',
 P_PATH='@t6g_mb_lib.t6g(sch_1):page201_i56@pure_quanta.q_res(chips)',
 PATH='I56',
 DRAWING='@T6G_MB_LIB.T6G(SCH_1):PAGE176',
 WATTAGE='1/16W',
 TOLERANCE='1%',
 MATERIAL='CHIP',
 PHYS_PAGE='201',
 XY='(-5950,4475)',
 ROT='0',
 VER='1',
 PACK_TYPE='0402LF',
 LOCATION='PR82',
 CDS_LIB='pure_quanta',
 CDS_PART_NAME='Q_RES_0402LF-5.6,1%,1/16W,CHIP,CS-5602FB01',
 PART_NUMBER='CS-5602FB01',
 VALUE='5.6',
 PRIM_FILE='./archive_libs/logical/q_res/chips/chips.prt';

PART_NAME
 PR83 'Q_RES_0402LF-0,5%,1/16W,CHIP,CS00002JB13':;

SECTION_NUMBER 1
 '@T6G_MB_LIB.T6G(SCH_1):PAGE176_I42@PURE_QUANTA.Q_RES(CHIPS)':
 C_PATH='@t6g_mb_lib.t6g(sch_1):page176_i42@pure_quanta.q_res(chips)',
 P_PATH='@t6g_mb_lib.t6g(sch_1):page201_i42@pure_quanta.q_res(chips)',
 PATH='I42',
 DRAWING='@T6G_MB_LIB.T6G(SCH_1):PAGE176',
 WATTAGE='1/16W',
 TOLERANCE='5%',
 MATERIAL='CHIP',
 PHYS_PAGE='201',
 XY='(-4925,275)',
 ROT='0',
 VER='1',
 PACK_TYPE='0402LF',
 LOCATION='PR83',
 CDS_LIB='pure_quanta',
 CDS_PART_NAME='Q_RES_0402LF-0,5%,1/16W,CHIP,CS00002JB13',
 PART_NUMBER='CS00002JB13',
 VALUE='0',
 PRIM_FILE='./archive_libs/logical/q_res/chips/chips.prt';

PART_NAME
 PR84 'Q_RES_0402LF-0,5%,1/16W,CHIP,CS00002JB13':;

SECTION_NUMBER 1
 '@T6G_MB_LIB.T6G(SCH_1):PAGE176_I54@PURE_QUANTA.Q_RES(CHIPS)':
 C_PATH='@t6g_mb_lib.t6g(sch_1):page176_i54@pure_quanta.q_res(chips)',
 P_PATH='@t6g_mb_lib.t6g(sch_1):page201_i54@pure_quanta.q_res(chips)',
 PATH='I54',
 DRAWING='@T6G_MB_LIB.T6G(SCH_1):PAGE176',
 WATTAGE='1/16W',
 TOLERANCE='5%',
 MATERIAL='CHIP',
 PHYS_PAGE='201',
 XY='(-4850,3225)',
 ROT='0',
 VER='1',
 PACK_TYPE='0402LF',
 LOCATION='PR84',
 CDS_LIB='pure_quanta',
 CDS_PART_NAME='Q_RES_0402LF-0,5%,1/16W,CHIP,CS00002JB13',
 PART_NUMBER='CS00002JB13',
 VALUE='0',
 PRIM_FILE='./archive_libs/logical/q_res/chips/chips.prt';

PART_NAME
 PR85 'Q_RES_0402LF-8.87K,1%,1/16W,EMPTY,CS28872FB01':;

SECTION_NUMBER 1
 '@T6G_MB_LIB.T6G(SCH_1):PAGE177_I4@PURE_QUANTA.Q_RES(CHIPS)':
 C_PATH='@t6g_mb_lib.t6g(sch_1):page177_i4@pure_quanta.q_res(chips)',
 P_PATH='@t6g_mb_lib.t6g(sch_1):page202_i4@pure_quanta.q_res(chips)',
 PATH='I4',
 DRAWING='@T6G_MB_LIB.T6G(SCH_1):PAGE177',
 WATTAGE='1/16W',
 TOLERANCE='1%',
 MATERIAL='EMPTY',
 PHYS_PAGE='202',
 XY='(1325,1025)',
 ROT='2',
 VER='2',
 PACK_TYPE='0402LF',
 LOCATION='PR85',
 CDS_LIB='pure_quanta',
 CDS_PART_NAME='Q_RES_0402LF-8.87K,1%,1/16W,EMPTY,CS28872FB01',
 PART_NUMBER='CS28872FB01',
 VALUE='8.87K',
 PRIM_FILE='./archive_libs/logical/q_res/chips/chips.prt';

PART_NAME
 PR86 'Q_RES_0402LF-8.87K,1%,1/16W,EMPTY,CS28872FB01':;

SECTION_NUMBER 1
 '@T6G_MB_LIB.T6G(SCH_1):PAGE177_I18@PURE_QUANTA.Q_RES(CHIPS)':
 C_PATH='@t6g_mb_lib.t6g(sch_1):page177_i18@pure_quanta.q_res(chips)',
 P_PATH='@t6g_mb_lib.t6g(sch_1):page202_i18@pure_quanta.q_res(chips)',
 PATH='I18',
 DRAWING='@T6G_MB_LIB.T6G(SCH_1):PAGE177',
 WATTAGE='1/16W',
 TOLERANCE='1%',
 MATERIAL='EMPTY',
 PHYS_PAGE='202',
 XY='(1350,3850)',
 ROT='2',
 VER='2',
 PACK_TYPE='0402LF',
 LOCATION='PR86',
 CDS_LIB='pure_quanta',
 CDS_PART_NAME='Q_RES_0402LF-8.87K,1%,1/16W,EMPTY,CS28872FB01',
 PART_NUMBER='CS28872FB01',
 VALUE='8.87K',
 PRIM_FILE='./archive_libs/logical/q_res/chips/chips.prt';

PART_NAME
 PR87 'Q_RES_0402LF-2.2,1%,1/16W,CHIP,CS-2202FB01':;

SECTION_NUMBER 1
 '@T6G_MB_LIB.T6G(SCH_1):PAGE177_I13@PURE_QUANTA.Q_RES(CHIPS)':
 C_PATH='@t6g_mb_lib.t6g(sch_1):page177_i13@pure_quanta.q_res(chips)',
 P_PATH='@t6g_mb_lib.t6g(sch_1):page202_i13@pure_quanta.q_res(chips)',
 PATH='I13',
 DRAWING='@T6G_MB_LIB.T6G(SCH_1):PAGE177',
 WATTAGE='1/16W',
 TOLERANCE='1%',
 MATERIAL='CHIP',
 PHYS_PAGE='202',
 XY='(1475,2525)',
 ROT='0',
 VER='2',
 PACK_TYPE='0402LF',
 LOCATION='PR87',
 CDS_LIB='pure_quanta',
 CDS_PART_NAME='Q_RES_0402LF-2.2,1%,1/16W,CHIP,CS-2202FB01',
 PART_NUMBER='CS-2202FB01',
 VALUE='2.2',
 PRIM_FILE='./archive_libs/logical/q_res/chips/chips.prt';

PART_NAME
 PR88 'Q_RES_0402LF-2.2,1%,1/16W,CHIP,CS-2202FB01':;

SECTION_NUMBER 1
 '@T6G_MB_LIB.T6G(SCH_1):PAGE177_I30@PURE_QUANTA.Q_RES(CHIPS)':
 C_PATH='@t6g_mb_lib.t6g(sch_1):page177_i30@pure_quanta.q_res(chips)',
 P_PATH='@t6g_mb_lib.t6g(sch_1):page202_i30@pure_quanta.q_res(chips)',
 PATH='I30',
 DRAWING='@T6G_MB_LIB.T6G(SCH_1):PAGE177',
 WATTAGE='1/16W',
 TOLERANCE='1%',
 MATERIAL='CHIP',
 PHYS_PAGE='202',
 XY='(1650,5350)',
 ROT='0',
 VER='2',
 PACK_TYPE='0402LF',
 LOCATION='PR88',
 CDS_LIB='pure_quanta',
 CDS_PART_NAME='Q_RES_0402LF-2.2,1%,1/16W,CHIP,CS-2202FB01',
 PART_NUMBER='CS-2202FB01',
 VALUE='2.2',
 PRIM_FILE='./archive_libs/logical/q_res/chips/chips.prt';

PART_NAME
 PR89 'Q_RES_0402LF-5.6,1%,1/16W,CHIP,CS-5602FB01':;

SECTION_NUMBER 1
 '@T6G_MB_LIB.T6G(SCH_1):PAGE177_I37@PURE_QUANTA.Q_RES(CHIPS)':
 C_PATH='@t6g_mb_lib.t6g(sch_1):page177_i37@pure_quanta.q_res(chips)',
 P_PATH='@t6g_mb_lib.t6g(sch_1):page202_i37@pure_quanta.q_res(chips)',
 PATH='I37',
 DRAWING='@T6G_MB_LIB.T6G(SCH_1):PAGE177',
 WATTAGE='1/16W',
 TOLERANCE='1%',
 MATERIAL='CHIP',
 PHYS_PAGE='202',
 XY='(4500,1875)',
 ROT='0',
 VER='1',
 PACK_TYPE='0402LF',
 LOCATION='PR89',
 CDS_LIB='pure_quanta',
 CDS_PART_NAME='Q_RES_0402LF-5.6,1%,1/16W,CHIP,CS-5602FB01',
 PART_NUMBER='CS-5602FB01',
 VALUE='5.6',
 PRIM_FILE='./archive_libs/logical/q_res/chips/chips.prt';

PART_NAME
 PR90 'Q_RES_0402LF-5.6,1%,1/16W,CHIP,CS-5602FB01':;

SECTION_NUMBER 1
 '@T6G_MB_LIB.T6G(SCH_1):PAGE177_I57@PURE_QUANTA.Q_RES(CHIPS)':
 C_PATH='@t6g_mb_lib.t6g(sch_1):page177_i57@pure_quanta.q_res(chips)',
 P_PATH='@t6g_mb_lib.t6g(sch_1):page202_i57@pure_quanta.q_res(chips)',
 PATH='I57',
 DRAWING='@T6G_MB_LIB.T6G(SCH_1):PAGE177',
 WATTAGE='1/16W',
 TOLERANCE='1%',
 MATERIAL='CHIP',
 PHYS_PAGE='202',
 XY='(4525,4700)',
 ROT='0',
 VER='1',
 PACK_TYPE='0402LF',
 LOCATION='PR90',
 CDS_LIB='pure_quanta',
 CDS_PART_NAME='Q_RES_0402LF-5.6,1%,1/16W,CHIP,CS-5602FB01',
 PART_NUMBER='CS-5602FB01',
 VALUE='5.6',
 PRIM_FILE='./archive_libs/logical/q_res/chips/chips.prt';

PART_NAME
 PR91 'Q_RES_0402LF-0,5%,1/16W,CHIP,CS00002JB13':;

SECTION_NUMBER 1
 '@T6G_MB_LIB.T6G(SCH_1):PAGE177_I40@PURE_QUANTA.Q_RES(CHIPS)':
 C_PATH='@t6g_mb_lib.t6g(sch_1):page177_i40@pure_quanta.q_res(chips)',
 P_PATH='@t6g_mb_lib.t6g(sch_1):page202_i40@pure_quanta.q_res(chips)',
 PATH='I40',
 DRAWING='@T6G_MB_LIB.T6G(SCH_1):PAGE177',
 WATTAGE='1/16W',
 TOLERANCE='5%',
 MATERIAL='CHIP',
 PHYS_PAGE='202',
 XY='(5850,525)',
 ROT='0',
 VER='1',
 PACK_TYPE='0402LF',
 LOCATION='PR91',
 CDS_LIB='pure_quanta',
 CDS_PART_NAME='Q_RES_0402LF-0,5%,1/16W,CHIP,CS00002JB13',
 PART_NUMBER='CS00002JB13',
 VALUE='0',
 PRIM_FILE='./archive_libs/logical/q_res/chips/chips.prt';

PART_NAME
 PR92 'Q_RES_0402LF-0,5%,1/16W,CHIP,CS00002JB13':;

SECTION_NUMBER 1
 '@T6G_MB_LIB.T6G(SCH_1):PAGE177_I51@PURE_QUANTA.Q_RES(CHIPS)':
 C_PATH='@t6g_mb_lib.t6g(sch_1):page177_i51@pure_quanta.q_res(chips)',
 P_PATH='@t6g_mb_lib.t6g(sch_1):page202_i51@pure_quanta.q_res(chips)',
 PATH='I51',
 DRAWING='@T6G_MB_LIB.T6G(SCH_1):PAGE177',
 WATTAGE='1/16W',
 TOLERANCE='5%',
 MATERIAL='CHIP',
 PHYS_PAGE='202',
 XY='(5850,3250)',
 ROT='0',
 VER='1',
 PACK_TYPE='0402LF',
 LOCATION='PR92',
 CDS_LIB='pure_quanta',
 CDS_PART_NAME='Q_RES_0402LF-0,5%,1/16W,CHIP,CS00002JB13',
 PART_NUMBER='CS00002JB13',
 VALUE='0',
 PRIM_FILE='./archive_libs/logical/q_res/chips/chips.prt';

PART_NAME
 PR93 'Q_RES_0402LF-8.87K,1%,1/16W,EMPTY,CS28872FB01':;

SECTION_NUMBER 1
 '@T6G_MB_LIB.T6G(SCH_1):PAGE178_I15@PURE_QUANTA.Q_RES(CHIPS)':
 C_PATH='@t6g_mb_lib.t6g(sch_1):page178_i15@pure_quanta.q_res(chips)',
 P_PATH='@t6g_mb_lib.t6g(sch_1):page203_i15@pure_quanta.q_res(chips)',
 PATH='I15',
 DRAWING='@T6G_MB_LIB.T6G(SCH_1):PAGE178',
 WATTAGE='1/16W',
 TOLERANCE='1%',
 MATERIAL='EMPTY',
 PHYS_PAGE='203',
 XY='(1475,4375)',
 ROT='2',
 VER='2',
 PACK_TYPE='0402LF',
 LOCATION='PR93',
 CDS_LIB='pure_quanta',
 CDS_PART_NAME='Q_RES_0402LF-8.87K,1%,1/16W,EMPTY,CS28872FB01',
 PART_NUMBER='CS28872FB01',
 VALUE='8.87K',
 PRIM_FILE='./archive_libs/logical/q_res/chips/chips.prt';

PART_NAME
 PR94 'Q_RES_0402LF-2.2,1%,1/16W,CHIP,CS-2202FB01':;

SECTION_NUMBER 1
 '@T6G_MB_LIB.T6G(SCH_1):PAGE178_I28@PURE_QUANTA.Q_RES(CHIPS)':
 C_PATH='@t6g_mb_lib.t6g(sch_1):page178_i28@pure_quanta.q_res(chips)',
 P_PATH='@t6g_mb_lib.t6g(sch_1):page203_i28@pure_quanta.q_res(chips)',
 PATH='I28',
 DRAWING='@T6G_MB_LIB.T6G(SCH_1):PAGE178',
 WATTAGE='1/16W',
 TOLERANCE='1%',
 MATERIAL='CHIP',
 PHYS_PAGE='203',
 XY='(1925,5850)',
 ROT='0',
 VER='2',
 PACK_TYPE='0402LF',
 LOCATION='PR94',
 CDS_LIB='pure_quanta',
 CDS_PART_NAME='Q_RES_0402LF-2.2,1%,1/16W,CHIP,CS-2202FB01',
 PART_NUMBER='CS-2202FB01',
 VALUE='2.2',
 PRIM_FILE='./archive_libs/logical/q_res/chips/chips.prt';

PART_NAME
 PR95 'Q_RES_0402LF-5.6,1%,1/16W,CHIP,CS-5602FB01':;

SECTION_NUMBER 1
 '@T6G_MB_LIB.T6G(SCH_1):PAGE178_I56@PURE_QUANTA.Q_RES(CHIPS)':
 C_PATH='@t6g_mb_lib.t6g(sch_1):page178_i56@pure_quanta.q_res(chips)',
 P_PATH='@t6g_mb_lib.t6g(sch_1):page203_i56@pure_quanta.q_res(chips)',
 PATH='I56',
 DRAWING='@T6G_MB_LIB.T6G(SCH_1):PAGE178',
 WATTAGE='1/16W',
 TOLERANCE='1%',
 MATERIAL='CHIP',
 PHYS_PAGE='203',
 XY='(4650,5225)',
 ROT='0',
 VER='1',
 PACK_TYPE='0402LF',
 LOCATION='PR95',
 CDS_LIB='pure_quanta',
 CDS_PART_NAME='Q_RES_0402LF-5.6,1%,1/16W,CHIP,CS-5602FB01',
 PART_NUMBER='CS-5602FB01',
 VALUE='5.6',
 PRIM_FILE='./archive_libs/logical/q_res/chips/chips.prt';

PART_NAME
 PR96 'Q_RES_0402LF-0,5%,1/16W,CHIP,CS00002JB13':;

SECTION_NUMBER 1
 '@T6G_MB_LIB.T6G(SCH_1):PAGE178_I49@PURE_QUANTA.Q_RES(CHIPS)':
 C_PATH='@t6g_mb_lib.t6g(sch_1):page178_i49@pure_quanta.q_res(chips)',
 P_PATH='@t6g_mb_lib.t6g(sch_1):page203_i49@pure_quanta.q_res(chips)',
 PATH='I49',
 DRAWING='@T6G_MB_LIB.T6G(SCH_1):PAGE178',
 WATTAGE='1/16W',
 TOLERANCE='5%',
 MATERIAL='CHIP',
 PHYS_PAGE='203',
 XY='(6050,3800)',
 ROT='0',
 VER='1',
 PACK_TYPE='0402LF',
 LOCATION='PR96',
 CDS_LIB='pure_quanta',
 CDS_PART_NAME='Q_RES_0402LF-0,5%,1/16W,CHIP,CS00002JB13',
 PART_NUMBER='CS00002JB13',
 VALUE='0',
 PRIM_FILE='./archive_libs/logical/q_res/chips/chips.prt';

PART_NAME
 PR97 'Q_RES_0402LF-8.87K,1%,1/16W,EMPTY,CS28872FB01':;

SECTION_NUMBER 1
 '@T6G_MB_LIB.T6G(SCH_1):PAGE180_I4@PURE_QUANTA.Q_RES(CHIPS)':
 C_PATH='@t6g_mb_lib.t6g(sch_1):page180_i4@pure_quanta.q_res(chips)',
 P_PATH='@t6g_mb_lib.t6g(sch_1):page205_i4@pure_quanta.q_res(chips)',
 PATH='I4',
 DRAWING='@T6G_MB_LIB.T6G(SCH_1):PAGE180',
 WATTAGE='1/16W',
 TOLERANCE='1%',
 MATERIAL='EMPTY',
 PHYS_PAGE='205',
 XY='(850,1675)',
 ROT='2',
 VER='2',
 PACK_TYPE='0402LF',
 LOCATION='PR97',
 CDS_LIB='pure_quanta',
 CDS_PART_NAME='Q_RES_0402LF-8.87K,1%,1/16W,EMPTY,CS28872FB01',
 PART_NUMBER='CS28872FB01',
 VALUE='8.87K',
 PRIM_FILE='./archive_libs/logical/q_res/chips/chips.prt';

PART_NAME
 PR98 'Q_RES_0402LF-8.87K,1%,1/16W,EMPTY,CS28872FB01':;

SECTION_NUMBER 1
 '@T6G_MB_LIB.T6G(SCH_1):PAGE180_I22@PURE_QUANTA.Q_RES(CHIPS)':
 C_PATH='@t6g_mb_lib.t6g(sch_1):page180_i22@pure_quanta.q_res(chips)',
 P_PATH='@t6g_mb_lib.t6g(sch_1):page205_i22@pure_quanta.q_res(chips)',
 PATH='I22',
 DRAWING='@T6G_MB_LIB.T6G(SCH_1):PAGE180',
 WATTAGE='1/16W',
 TOLERANCE='1%',
 MATERIAL='EMPTY',
 PHYS_PAGE='205',
 XY='(875,4525)',
 ROT='2',
 VER='2',
 PACK_TYPE='0402LF',
 LOCATION='PR98',
 CDS_LIB='pure_quanta',
 CDS_PART_NAME='Q_RES_0402LF-8.87K,1%,1/16W,EMPTY,CS28872FB01',
 PART_NUMBER='CS28872FB01',
 VALUE='8.87K',
 PRIM_FILE='./archive_libs/logical/q_res/chips/chips.prt';

PART_NAME
 PR99 'Q_RES_0402LF-2.2,1%,1/16W,CHIP,CS-2202FB01':;

SECTION_NUMBER 1
 '@T6G_MB_LIB.T6G(SCH_1):PAGE180_I12@PURE_QUANTA.Q_RES(CHIPS)':
 C_PATH='@t6g_mb_lib.t6g(sch_1):page180_i12@pure_quanta.q_res(chips)',
 P_PATH='@t6g_mb_lib.t6g(sch_1):page205_i12@pure_quanta.q_res(chips)',
 PATH='I12',
 DRAWING='@T6G_MB_LIB.T6G(SCH_1):PAGE180',
 WATTAGE='1/16W',
 TOLERANCE='1%',
 MATERIAL='CHIP',
 PHYS_PAGE='205',
 XY='(1175,3125)',
 ROT='0',
 VER='2',
 PACK_TYPE='0402LF',
 LOCATION='PR99',
 CDS_LIB='pure_quanta',
 CDS_PART_NAME='Q_RES_0402LF-2.2,1%,1/16W,CHIP,CS-2202FB01',
 PART_NUMBER='CS-2202FB01',
 VALUE='2.2',
 PRIM_FILE='./archive_libs/logical/q_res/chips/chips.prt';

PART_NAME
 PR100 'Q_RES_0402LF-2.2,1%,1/16W,CHIP,CS-2202FB01':;

SECTION_NUMBER 1
 '@T6G_MB_LIB.T6G(SCH_1):PAGE180_I29@PURE_QUANTA.Q_RES(CHIPS)':
 C_PATH='@t6g_mb_lib.t6g(sch_1):page180_i29@pure_quanta.q_res(chips)',
 P_PATH='@t6g_mb_lib.t6g(sch_1):page205_i29@pure_quanta.q_res(chips)',
 PATH='I29',
 DRAWING='@T6G_MB_LIB.T6G(SCH_1):PAGE180',
 WATTAGE='1/16W',
 TOLERANCE='1%',
 MATERIAL='CHIP',
 PHYS_PAGE='205',
 XY='(1275,5800)',
 ROT='0',
 VER='2',
 PACK_TYPE='0402LF',
 LOCATION='PR100',
 CDS_LIB='pure_quanta',
 CDS_PART_NAME='Q_RES_0402LF-2.2,1%,1/16W,CHIP,CS-2202FB01',
 PART_NUMBER='CS-2202FB01',
 VALUE='2.2',
 PRIM_FILE='./archive_libs/logical/q_res/chips/chips.prt';

PART_NAME
 PR101 'Q_RES_0402LF-5.6,1%,1/16W,CHIP,CS-5602FB01':;

SECTION_NUMBER 1
 '@T6G_MB_LIB.T6G(SCH_1):PAGE180_I34@PURE_QUANTA.Q_RES(CHIPS)':
 C_PATH='@t6g_mb_lib.t6g(sch_1):page180_i34@pure_quanta.q_res(chips)',
 P_PATH='@t6g_mb_lib.t6g(sch_1):page205_i34@pure_quanta.q_res(chips)',
 PATH='I34',
 DRAWING='@T6G_MB_LIB.T6G(SCH_1):PAGE180',
 WATTAGE='1/16W',
 TOLERANCE='1%',
 MATERIAL='CHIP',
 PHYS_PAGE='205',
 XY='(3950,5325)',
 ROT='0',
 VER='1',
 PACK_TYPE='0402LF',
 LOCATION='PR101',
 CDS_LIB='pure_quanta',
 CDS_PART_NAME='Q_RES_0402LF-5.6,1%,1/16W,CHIP,CS-5602FB01',
 PART_NUMBER='CS-5602FB01',
 VALUE='5.6',
 PRIM_FILE='./archive_libs/logical/q_res/chips/chips.prt';

PART_NAME
 PR102 'Q_RES_0402LF-5.6,1%,1/16W,CHIP,CS-5602FB01':;

SECTION_NUMBER 1
 '@T6G_MB_LIB.T6G(SCH_1):PAGE180_I17@PURE_QUANTA.Q_RES(CHIPS)':
 C_PATH='@t6g_mb_lib.t6g(sch_1):page180_i17@pure_quanta.q_res(chips)',
 P_PATH='@t6g_mb_lib.t6g(sch_1):page205_i17@pure_quanta.q_res(chips)',
 PATH='I17',
 DRAWING='@T6G_MB_LIB.T6G(SCH_1):PAGE180',
 WATTAGE='1/16W',
 TOLERANCE='1%',
 MATERIAL='CHIP',
 PHYS_PAGE='205',
 XY='(4125,2525)',
 ROT='0',
 VER='1',
 PACK_TYPE='0402LF',
 LOCATION='PR102',
 CDS_LIB='pure_quanta',
 CDS_PART_NAME='Q_RES_0402LF-5.6,1%,1/16W,CHIP,CS-5602FB01',
 PART_NUMBER='CS-5602FB01',
 VALUE='5.6',
 PRIM_FILE='./archive_libs/logical/q_res/chips/chips.prt';

PART_NAME
 PR103 'Q_RES_0402LF-0,5%,1/16W,CHIP,CS00002JB13':;

SECTION_NUMBER 1
 '@T6G_MB_LIB.T6G(SCH_1):PAGE180_I49@PURE_QUANTA.Q_RES(CHIPS)':
 C_PATH='@t6g_mb_lib.t6g(sch_1):page180_i49@pure_quanta.q_res(chips)',
 P_PATH='@t6g_mb_lib.t6g(sch_1):page205_i49@pure_quanta.q_res(chips)',
 PATH='I49',
 DRAWING='@T6G_MB_LIB.T6G(SCH_1):PAGE180',
 WATTAGE='1/16W',
 TOLERANCE='5%',
 MATERIAL='CHIP',
 PHYS_PAGE='205',
 XY='(5450,3875)',
 ROT='0',
 VER='1',
 PACK_TYPE='0402LF',
 LOCATION='PR103',
 CDS_LIB='pure_quanta',
 CDS_PART_NAME='Q_RES_0402LF-0,5%,1/16W,CHIP,CS00002JB13',
 PART_NUMBER='CS00002JB13',
 VALUE='0',
 PRIM_FILE='./archive_libs/logical/q_res/chips/chips.prt';

PART_NAME
 PR104 'Q_RES_0402LF-0,5%,1/16W,CHIP,CS00002JB13':;

SECTION_NUMBER 1
 '@T6G_MB_LIB.T6G(SCH_1):PAGE180_I39@PURE_QUANTA.Q_RES(CHIPS)':
 C_PATH='@t6g_mb_lib.t6g(sch_1):page180_i39@pure_quanta.q_res(chips)',
 P_PATH='@t6g_mb_lib.t6g(sch_1):page205_i39@pure_quanta.q_res(chips)',
 PATH='I39',
 DRAWING='@T6G_MB_LIB.T6G(SCH_1):PAGE180',
 WATTAGE='1/16W',
 TOLERANCE='5%',
 MATERIAL='CHIP',
 PHYS_PAGE='205',
 XY='(5450,1150)',
 ROT='0',
 VER='1',
 PACK_TYPE='0402LF',
 LOCATION='PR104',
 CDS_LIB='pure_quanta',
 CDS_PART_NAME='Q_RES_0402LF-0,5%,1/16W,CHIP,CS00002JB13',
 PART_NUMBER='CS00002JB13',
 VALUE='0',
 PRIM_FILE='./archive_libs/logical/q_res/chips/chips.prt';

PART_NAME
 PR105 'Q_RES_0402LF-8.87K,1%,1/16W,EMPTY,CS28872FB01':;

SECTION_NUMBER 1
 '@T6G_MB_LIB.T6G(SCH_1):PAGE181_I4@PURE_QUANTA.Q_RES(CHIPS)':
 C_PATH='@t6g_mb_lib.t6g(sch_1):page181_i4@pure_quanta.q_res(chips)',
 P_PATH='@t6g_mb_lib.t6g(sch_1):page206_i4@pure_quanta.q_res(chips)',
 PATH='I4',
 DRAWING='@T6G_MB_LIB.T6G(SCH_1):PAGE181',
 WATTAGE='1/16W',
 TOLERANCE='1%',
 MATERIAL='EMPTY',
 PHYS_PAGE='206',
 XY='(-11375,2125)',
 ROT='2',
 VER='2',
 PACK_TYPE='0402LF',
 LOCATION='PR105',
 CDS_LIB='pure_quanta',
 CDS_PART_NAME='Q_RES_0402LF-8.87K,1%,1/16W,EMPTY,CS28872FB01',
 PART_NUMBER='CS28872FB01',
 VALUE='8.87K',
 PRIM_FILE='./archive_libs/logical/q_res/chips/chips.prt';

PART_NAME
 PR106 'Q_RES_0402LF-8.87K,1%,1/16W,EMPTY,CS28872FB01':;

SECTION_NUMBER 1
 '@T6G_MB_LIB.T6G(SCH_1):PAGE181_I21@PURE_QUANTA.Q_RES(CHIPS)':
 C_PATH='@t6g_mb_lib.t6g(sch_1):page181_i21@pure_quanta.q_res(chips)',
 P_PATH='@t6g_mb_lib.t6g(sch_1):page206_i21@pure_quanta.q_res(chips)',
 PATH='I21',
 DRAWING='@T6G_MB_LIB.T6G(SCH_1):PAGE181',
 WATTAGE='1/16W',
 TOLERANCE='1%',
 MATERIAL='EMPTY',
 PHYS_PAGE='206',
 XY='(-11350,4975)',
 ROT='2',
 VER='2',
 PACK_TYPE='0402LF',
 LOCATION='PR106',
 CDS_LIB='pure_quanta',
 CDS_PART_NAME='Q_RES_0402LF-8.87K,1%,1/16W,EMPTY,CS28872FB01',
 PART_NUMBER='CS28872FB01',
 VALUE='8.87K',
 PRIM_FILE='./archive_libs/logical/q_res/chips/chips.prt';

PART_NAME
 PR107 'Q_RES_0402LF-2.2,1%,1/16W,CHIP,CS-2202FB01':;

SECTION_NUMBER 1
 '@T6G_MB_LIB.T6G(SCH_1):PAGE181_I12@PURE_QUANTA.Q_RES(CHIPS)':
 C_PATH='@t6g_mb_lib.t6g(sch_1):page181_i12@pure_quanta.q_res(chips)',
 P_PATH='@t6g_mb_lib.t6g(sch_1):page206_i12@pure_quanta.q_res(chips)',
 PATH='I12',
 DRAWING='@T6G_MB_LIB.T6G(SCH_1):PAGE181',
 WATTAGE='1/16W',
 TOLERANCE='1%',
 MATERIAL='CHIP',
 PHYS_PAGE='206',
 XY='(-11050,3575)',
 ROT='0',
 VER='2',
 PACK_TYPE='0402LF',
 LOCATION='PR107',
 CDS_LIB='pure_quanta',
 CDS_PART_NAME='Q_RES_0402LF-2.2,1%,1/16W,CHIP,CS-2202FB01',
 PART_NUMBER='CS-2202FB01',
 VALUE='2.2',
 PRIM_FILE='./archive_libs/logical/q_res/chips/chips.prt';

PART_NAME
 PR108 'Q_RES_0402LF-2.2,1%,1/16W,CHIP,CS-2202FB01':;

SECTION_NUMBER 1
 '@T6G_MB_LIB.T6G(SCH_1):PAGE181_I28@PURE_QUANTA.Q_RES(CHIPS)':
 C_PATH='@t6g_mb_lib.t6g(sch_1):page181_i28@pure_quanta.q_res(chips)',
 P_PATH='@t6g_mb_lib.t6g(sch_1):page206_i28@pure_quanta.q_res(chips)',
 PATH='I28',
 DRAWING='@T6G_MB_LIB.T6G(SCH_1):PAGE181',
 WATTAGE='1/16W',
 TOLERANCE='1%',
 MATERIAL='CHIP',
 PHYS_PAGE='206',
 XY='(-11025,6275)',
 ROT='0',
 VER='2',
 PACK_TYPE='0402LF',
 LOCATION='PR108',
 CDS_LIB='pure_quanta',
 CDS_PART_NAME='Q_RES_0402LF-2.2,1%,1/16W,CHIP,CS-2202FB01',
 PART_NUMBER='CS-2202FB01',
 VALUE='2.2',
 PRIM_FILE='./archive_libs/logical/q_res/chips/chips.prt';

PART_NAME
 PR109 'Q_RES_0402LF-5.6,1%,1/16W,CHIP,CS-5602FB01':;

SECTION_NUMBER 1
 '@T6G_MB_LIB.T6G(SCH_1):PAGE181_I16@PURE_QUANTA.Q_RES(CHIPS)':
 C_PATH='@t6g_mb_lib.t6g(sch_1):page181_i16@pure_quanta.q_res(chips)',
 P_PATH='@t6g_mb_lib.t6g(sch_1):page206_i16@pure_quanta.q_res(chips)',
 PATH='I16',
 DRAWING='@T6G_MB_LIB.T6G(SCH_1):PAGE181',
 WATTAGE='1/16W',
 TOLERANCE='1%',
 MATERIAL='CHIP',
 PHYS_PAGE='206',
 XY='(-8225,2975)',
 ROT='0',
 VER='1',
 PACK_TYPE='0402LF',
 LOCATION='PR109',
 CDS_LIB='pure_quanta',
 CDS_PART_NAME='Q_RES_0402LF-5.6,1%,1/16W,CHIP,CS-5602FB01',
 PART_NUMBER='CS-5602FB01',
 VALUE='5.6',
 PRIM_FILE='./archive_libs/logical/q_res/chips/chips.prt';

PART_NAME
 PR110 'Q_RES_0402LF-5.6,1%,1/16W,CHIP,CS-5602FB01':;

SECTION_NUMBER 1
 '@T6G_MB_LIB.T6G(SCH_1):PAGE181_I34@PURE_QUANTA.Q_RES(CHIPS)':
 C_PATH='@t6g_mb_lib.t6g(sch_1):page181_i34@pure_quanta.q_res(chips)',
 P_PATH='@t6g_mb_lib.t6g(sch_1):page206_i34@pure_quanta.q_res(chips)',
 PATH='I34',
 DRAWING='@T6G_MB_LIB.T6G(SCH_1):PAGE181',
 WATTAGE='1/16W',
 TOLERANCE='1%',
 MATERIAL='CHIP',
 PHYS_PAGE='206',
 XY='(-8000,5775)',
 ROT='0',
 VER='1',
 PACK_TYPE='0402LF',
 LOCATION='PR110',
 CDS_LIB='pure_quanta',
 CDS_PART_NAME='Q_RES_0402LF-5.6,1%,1/16W,CHIP,CS-5602FB01',
 PART_NUMBER='CS-5602FB01',
 VALUE='5.6',
 PRIM_FILE='./archive_libs/logical/q_res/chips/chips.prt';

PART_NAME
 PR111 'Q_RES_0402LF-0,5%,1/16W,CHIP,CS00002JB13':;

SECTION_NUMBER 1
 '@T6G_MB_LIB.T6G(SCH_1):PAGE181_I50@PURE_QUANTA.Q_RES(CHIPS)':
 C_PATH='@t6g_mb_lib.t6g(sch_1):page181_i50@pure_quanta.q_res(chips)',
 P_PATH='@t6g_mb_lib.t6g(sch_1):page206_i50@pure_quanta.q_res(chips)',
 PATH='I50',
 DRAWING='@T6G_MB_LIB.T6G(SCH_1):PAGE181',
 WATTAGE='1/16W',
 TOLERANCE='5%',
 MATERIAL='CHIP',
 PHYS_PAGE='206',
 XY='(-6700,4300)',
 ROT='0',
 VER='1',
 PACK_TYPE='0402LF',
 LOCATION='PR111',
 CDS_LIB='pure_quanta',
 CDS_PART_NAME='Q_RES_0402LF-0,5%,1/16W,CHIP,CS00002JB13',
 PART_NUMBER='CS00002JB13',
 VALUE='0',
 PRIM_FILE='./archive_libs/logical/q_res/chips/chips.prt';

PART_NAME
 PR112 'Q_RES_0402LF-0,5%,1/16W,CHIP,CS00002JB13':;

SECTION_NUMBER 1
 '@T6G_MB_LIB.T6G(SCH_1):PAGE181_I41@PURE_QUANTA.Q_RES(CHIPS)':
 C_PATH='@t6g_mb_lib.t6g(sch_1):page181_i41@pure_quanta.q_res(chips)',
 P_PATH='@t6g_mb_lib.t6g(sch_1):page206_i41@pure_quanta.q_res(chips)',
 PATH='I41',
 DRAWING='@T6G_MB_LIB.T6G(SCH_1):PAGE181',
 WATTAGE='1/16W',
 TOLERANCE='5%',
 MATERIAL='CHIP',
 PHYS_PAGE='206',
 XY='(-6800,1500)',
 ROT='0',
 VER='1',
 PACK_TYPE='0402LF',
 LOCATION='PR112',
 CDS_LIB='pure_quanta',
 CDS_PART_NAME='Q_RES_0402LF-0,5%,1/16W,CHIP,CS00002JB13',
 PART_NUMBER='CS00002JB13',
 VALUE='0',
 PRIM_FILE='./archive_libs/logical/q_res/chips/chips.prt';

PART_NAME
 PR113 'Q_RES_0402LF-40.2K,1%,1/16W,CHIP,CS34022FB04':;

SECTION_NUMBER 1
 '@T6G_MB_LIB.T6G(SCH_1):PAGE182_I2@PURE_QUANTA.Q_RES(CHIPS)':
 C_PATH='@t6g_mb_lib.t6g(sch_1):page182_i2@pure_quanta.q_res(chips)',
 P_PATH='@t6g_mb_lib.t6g(sch_1):page207_i2@pure_quanta.q_res(chips)',
 PATH='I2',
 DRAWING='@T6G_MB_LIB.T6G(SCH_1):PAGE182',
 WATTAGE='1/16W',
 TOLERANCE='1%',
 MATERIAL='CHIP',
 PHYS_PAGE='207',
 XY='(-7300,850)',
 ROT='0',
 VER='1',
 PACK_TYPE='0402LF',
 LOCATION='PR113',
 CDS_LIB='pure_quanta',
 CDS_PART_NAME='Q_RES_0402LF-40.2K,1%,1/16W,CHIP,CS34022FB04',
 PART_NUMBER='CS34022FB04',
 VALUE='40.2K',
 PRIM_FILE='./archive_libs/logical/q_res/chips/chips.prt';

PART_NAME
 PR114 'Q_RES_0402LF-49.9,1%,1/16W,CHIP,CS04992FB07':;

SECTION_NUMBER 1
 '@T6G_MB_LIB.T6G(SCH_1):PAGE182_I30@PURE_QUANTA.Q_RES(CHIPS)':
 C_PATH='@t6g_mb_lib.t6g(sch_1):page182_i30@pure_quanta.q_res(chips)',
 P_PATH='@t6g_mb_lib.t6g(sch_1):page207_i30@pure_quanta.q_res(chips)',
 PATH='I30',
 DRAWING='@T6G_MB_LIB.T6G(SCH_1):PAGE182',
 WATTAGE='1/16W',
 TOLERANCE='1%',
 MATERIAL='CHIP',
 PHYS_PAGE='207',
 XY='(-6900,4250)',
 ROT='0',
 VER='2',
 PACK_TYPE='0402LF',
 LOCATION='PR114',
 CDS_LIB='pure_quanta',
 CDS_PART_NAME='Q_RES_0402LF-49.9,1%,1/16W,CHIP,CS04992FB07',
 PART_NUMBER='CS04992FB07',
 VALUE='49.9',
 PRIM_FILE='./archive_libs/logical/q_res/chips/chips.prt';

PART_NAME
 PR115 'Q_RES_0402LF-49.9,1%,1/16W,CHIP,CS04992FB07':;

SECTION_NUMBER 1
 '@T6G_MB_LIB.T6G(SCH_1):PAGE182_I15@PURE_QUANTA.Q_RES(CHIPS)':
 C_PATH='@t6g_mb_lib.t6g(sch_1):page182_i15@pure_quanta.q_res(chips)',
 P_PATH='@t6g_mb_lib.t6g(sch_1):page207_i15@pure_quanta.q_res(chips)',
 PATH='I15',
 DRAWING='@T6G_MB_LIB.T6G(SCH_1):PAGE182',
 WATTAGE='1/16W',
 TOLERANCE='1%',
 MATERIAL='CHIP',
 PHYS_PAGE='207',
 XY='(-6900,3675)',
 ROT='0',
 VER='2',
 PACK_TYPE='0402LF',
 LOCATION='PR115',
 CDS_LIB='pure_quanta',
 CDS_PART_NAME='Q_RES_0402LF-49.9,1%,1/16W,CHIP,CS04992FB07',
 PART_NUMBER='CS04992FB07',
 VALUE='49.9',
 PRIM_FILE='./archive_libs/logical/q_res/chips/chips.prt';

PART_NAME
 PR121 'Q_RES_0402LF-0,5%,1/16W,CHIP,CS00002JB13':;

SECTION_NUMBER 1
 '@T6G_MB_LIB.T6G(SCH_1):PAGE182_I28@PURE_QUANTA.Q_RES(CHIPS)':
 C_PATH='@t6g_mb_lib.t6g(sch_1):page182_i28@pure_quanta.q_res(chips)',
 P_PATH='@t6g_mb_lib.t6g(sch_1):page207_i28@pure_quanta.q_res(chips)',
 PATH='I28',
 DRAWING='@T6G_MB_LIB.T6G(SCH_1):PAGE182',
 WATTAGE='1/16W',
 TOLERANCE='5%',
 MATERIAL='CHIP',
 PHYS_PAGE='207',
 XY='(-6075,4075)',
 ROT='0',
 VER='1',
 PACK_TYPE='0402LF',
 LOCATION='PR121',
 CDS_LIB='pure_quanta',
 CDS_PART_NAME='Q_RES_0402LF-0,5%,1/16W,CHIP,CS00002JB13',
 PART_NUMBER='CS00002JB13',
 VALUE='0',
 PRIM_FILE='./archive_libs/logical/q_res/chips/chips.prt';

PART_NAME
 PR125 'Q_RES_0402LF-0,5%,1/16W,CHIP,CS00002JB13':;

SECTION_NUMBER 1
 '@T6G_MB_LIB.T6G(SCH_1):PAGE182_I16@PURE_QUANTA.Q_RES(CHIPS)':
 C_PATH='@t6g_mb_lib.t6g(sch_1):page182_i16@pure_quanta.q_res(chips)',
 P_PATH='@t6g_mb_lib.t6g(sch_1):page207_i16@pure_quanta.q_res(chips)',
 PATH='I16',
 DRAWING='@T6G_MB_LIB.T6G(SCH_1):PAGE182',
 WATTAGE='1/16W',
 TOLERANCE='5%',
 MATERIAL='CHIP',
 PHYS_PAGE='207',
 XY='(-6050,675)',
 ROT='0',
 VER='1',
 PACK_TYPE='0402LF',
 LOCATION='PR125',
 CDS_LIB='pure_quanta',
 CDS_PART_NAME='Q_RES_0402LF-0,5%,1/16W,CHIP,CS00002JB13',
 PART_NUMBER='CS00002JB13',
 VALUE='0',
 PRIM_FILE='./archive_libs/logical/q_res/chips/chips.prt';

PART_NAME
 PR126 'Q_RES_0402LF-3.09K,1%,1/16W,CHIP,CS23092FB04':;

SECTION_NUMBER 1
 '@T6G_MB_LIB.T6G(SCH_1):PAGE182_I22@PURE_QUANTA.Q_RES(CHIPS)':
 C_PATH='@t6g_mb_lib.t6g(sch_1):page182_i22@pure_quanta.q_res(chips)',
 P_PATH='@t6g_mb_lib.t6g(sch_1):page207_i22@pure_quanta.q_res(chips)',
 PATH='I22',
 DRAWING='@T6G_MB_LIB.T6G(SCH_1):PAGE182',
 WATTAGE='1/16W',
 TOLERANCE='1%',
 MATERIAL='CHIP',
 PHYS_PAGE='207',
 XY='(-5700,1275)',
 ROT='0',
 VER='2',
 PACK_TYPE='0402LF',
 LOCATION='PR126',
 CDS_LIB='pure_quanta',
 CDS_PART_NAME='Q_RES_0402LF-3.09K,1%,1/16W,CHIP,CS23092FB04',
 PART_NUMBER='CS23092FB04',
 VALUE='3.09K',
 PRIM_FILE='./archive_libs/logical/q_res/chips/chips.prt';

PART_NAME
 PR127 'Q_RES_0402LF-0,5%,1/16W,EMPTY,CS00002JB13':;

SECTION_NUMBER 1
 '@T6G_MB_LIB.T6G(SCH_1):PAGE182_I57@PURE_QUANTA.Q_RES(CHIPS)':
 C_PATH='@t6g_mb_lib.t6g(sch_1):page182_i57@pure_quanta.q_res(chips)',
 P_PATH='@t6g_mb_lib.t6g(sch_1):page207_i57@pure_quanta.q_res(chips)',
 PATH='I57',
 DRAWING='@T6G_MB_LIB.T6G(SCH_1):PAGE182',
 WATTAGE='1/16W',
 TOLERANCE='5%',
 MATERIAL='EMPTY',
 PHYS_PAGE='207',
 XY='(-2175,1425)',
 ROT='0',
 VER='2',
 PACK_TYPE='0402LF',
 LOCATION='PR127',
 CDS_LIB='pure_quanta',
 CDS_PART_NAME='Q_RES_0402LF-0,5%,1/16W,EMPTY,CS00002JB13',
 PART_NUMBER='CS00002JB13',
 VALUE='0',
 PRIM_FILE='./archive_libs/logical/q_res/chips/chips.prt';

PART_NAME
 PR128 'Q_RES_0402LF-1K,1%,1/16W,EMPTY,CS21002FB06':;

SECTION_NUMBER 1
 '@T6G_MB_LIB.T6G(SCH_1):PAGE182_I68@PURE_QUANTA.Q_RES(CHIPS)':
 C_PATH='@t6g_mb_lib.t6g(sch_1):page182_i68@pure_quanta.q_res(chips)',
 P_PATH='@t6g_mb_lib.t6g(sch_1):page207_i68@pure_quanta.q_res(chips)',
 PATH='I68',
 DRAWING='@T6G_MB_LIB.T6G(SCH_1):PAGE182',
 WATTAGE='1/16W',
 TOLERANCE='1%',
 MATERIAL='EMPTY',
 PHYS_PAGE='207',
 XY='(-1750,1850)',
 ROT='0',
 VER='1',
 PACK_TYPE='0402LF',
 LOCATION='PR128',
 CDS_LIB='pure_quanta',
 CDS_PART_NAME='Q_RES_0402LF-1K,1%,1/16W,EMPTY,CS21002FB06',
 PART_NUMBER='CS21002FB06',
 VALUE='1K',
 PRIM_FILE='./archive_libs/logical/q_res/chips/chips.prt';

PART_NAME
 PR129 'Q_RES_0402LF-0,5%,1/16W,EMPTY,CS00002JB13':;

SECTION_NUMBER 1
 '@T6G_MB_LIB.T6G(SCH_1):PAGE182_I67@PURE_QUANTA.Q_RES(CHIPS)':
 C_PATH='@t6g_mb_lib.t6g(sch_1):page182_i67@pure_quanta.q_res(chips)',
 P_PATH='@t6g_mb_lib.t6g(sch_1):page207_i67@pure_quanta.q_res(chips)',
 PATH='I67',
 DRAWING='@T6G_MB_LIB.T6G(SCH_1):PAGE182',
 WATTAGE='1/16W',
 TOLERANCE='5%',
 MATERIAL='EMPTY',
 PHYS_PAGE='207',
 XY='(-1700,1625)',
 ROT='0',
 VER='1',
 PACK_TYPE='0402LF',
 LOCATION='PR129',
 CDS_LIB='pure_quanta',
 CDS_PART_NAME='Q_RES_0402LF-0,5%,1/16W,EMPTY,CS00002JB13',
 PART_NUMBER='CS00002JB13',
 VALUE='0',
 PRIM_FILE='./archive_libs/logical/q_res/chips/chips.prt';

PART_NAME
 PR130 'Q_RES_0402LF-1,1%,1/16W,CHIP,CS-1002FB04':;

SECTION_NUMBER 1
 '@T6G_MB_LIB.T6G(SCH_1):PAGE182_I85@PURE_QUANTA.Q_RES(CHIPS)':
 C_PATH='@t6g_mb_lib.t6g(sch_1):page182_i85@pure_quanta.q_res(chips)',
 P_PATH='@t6g_mb_lib.t6g(sch_1):page207_i85@pure_quanta.q_res(chips)',
 PATH='I85',
 DRAWING='@T6G_MB_LIB.T6G(SCH_1):PAGE182',
 WATTAGE='1/16W',
 TOLERANCE='1%',
 MATERIAL='CHIP',
 PHYS_PAGE='207',
 XY='(-2600,6300)',
 ROT='0',
 VER='1',
 PACK_TYPE='0402LF',
 LOCATION='PR130',
 CDS_LIB='pure_quanta',
 CDS_PART_NAME='Q_RES_0402LF-1,1%,1/16W,CHIP,CS-1002FB04',
 PART_NUMBER='CS-1002FB04',
 VALUE='1',
 PRIM_FILE='./archive_libs/logical/q_res/chips/chips.prt';

PART_NAME
 PR131 'Q_RES_0402LF-2.2,1%,1/16W,CHIP,CS-2202FB01':;

SECTION_NUMBER 1
 '@T6G_MB_LIB.T6G(SCH_1):PAGE183_I40@PURE_QUANTA.Q_RES(CHIPS)':
 C_PATH='@t6g_mb_lib.t6g(sch_1):page183_i40@pure_quanta.q_res(chips)',
 P_PATH='@t6g_mb_lib.t6g(sch_1):page208_i40@pure_quanta.q_res(chips)',
 PATH='I40',
 DRAWING='@T6G_MB_LIB.T6G(SCH_1):PAGE183',
 WATTAGE='1/16W',
 TOLERANCE='1%',
 MATERIAL='CHIP',
 PHYS_PAGE='208',
 XY='(-7775,5300)',
 ROT='0',
 VER='2',
 PACK_TYPE='0402LF',
 LOCATION='PR131',
 CDS_LIB='pure_quanta',
 CDS_PART_NAME='Q_RES_0402LF-2.2,1%,1/16W,CHIP,CS-2202FB01',
 PART_NUMBER='CS-2202FB01',
 VALUE='2.2',
 PRIM_FILE='./archive_libs/logical/q_res/chips/chips.prt';

PART_NAME
 PR132 'Q_RES_0402LF-2.2,1%,1/16W,CHIP,CS-2202FB01':;

SECTION_NUMBER 1
 '@T6G_MB_LIB.T6G(SCH_1):PAGE183_I14@PURE_QUANTA.Q_RES(CHIPS)':
 C_PATH='@t6g_mb_lib.t6g(sch_1):page183_i14@pure_quanta.q_res(chips)',
 P_PATH='@t6g_mb_lib.t6g(sch_1):page208_i14@pure_quanta.q_res(chips)',
 PATH='I14',
 DRAWING='@T6G_MB_LIB.T6G(SCH_1):PAGE183',
 WATTAGE='1/16W',
 TOLERANCE='1%',
 MATERIAL='CHIP',
 PHYS_PAGE='208',
 XY='(-7775,2375)',
 ROT='0',
 VER='2',
 PACK_TYPE='0402LF',
 LOCATION='PR132',
 CDS_LIB='pure_quanta',
 CDS_PART_NAME='Q_RES_0402LF-2.2,1%,1/16W,CHIP,CS-2202FB01',
 PART_NUMBER='CS-2202FB01',
 VALUE='2.2',
 PRIM_FILE='./archive_libs/logical/q_res/chips/chips.prt';

PART_NAME
 PR133 'Q_RES_0402LF-4.87K,1%,1/16W,EMPTY,CS24872FB01':;

SECTION_NUMBER 1
 '@T6G_MB_LIB.T6G(SCH_1):PAGE183_I37@PURE_QUANTA.Q_RES(CHIPS)':
 C_PATH='@t6g_mb_lib.t6g(sch_1):page183_i37@pure_quanta.q_res(chips)',
 P_PATH='@t6g_mb_lib.t6g(sch_1):page208_i37@pure_quanta.q_res(chips)',
 PATH='I37',
 DRAWING='@T6G_MB_LIB.T6G(SCH_1):PAGE183',
 WATTAGE='1/16W',
 TOLERANCE='1%',
 MATERIAL='EMPTY',
 PHYS_PAGE='208',
 XY='(-7200,4125)',
 ROT='0',
 VER='1',
 PACK_TYPE='0402LF',
 LOCATION='PR133',
 CDS_LIB='pure_quanta',
 CDS_PART_NAME='Q_RES_0402LF-4.87K,1%,1/16W,EMPTY,CS24872FB01',
 PART_NUMBER='CS24872FB01',
 VALUE='4.87K',
 PRIM_FILE='./archive_libs/logical/q_res/chips/chips.prt';

PART_NAME
 PR134 'Q_RES_0402LF-4.87K,1%,1/16W,EMPTY,CS24872FB01':;

SECTION_NUMBER 1
 '@T6G_MB_LIB.T6G(SCH_1):PAGE183_I11@PURE_QUANTA.Q_RES(CHIPS)':
 C_PATH='@t6g_mb_lib.t6g(sch_1):page183_i11@pure_quanta.q_res(chips)',
 P_PATH='@t6g_mb_lib.t6g(sch_1):page208_i11@pure_quanta.q_res(chips)',
 PATH='I11',
 DRAWING='@T6G_MB_LIB.T6G(SCH_1):PAGE183',
 WATTAGE='1/16W',
 TOLERANCE='1%',
 MATERIAL='EMPTY',
 PHYS_PAGE='208',
 XY='(-7175,1200)',
 ROT='0',
 VER='1',
 PACK_TYPE='0402LF',
 LOCATION='PR134',
 CDS_LIB='pure_quanta',
 CDS_PART_NAME='Q_RES_0402LF-4.87K,1%,1/16W,EMPTY,CS24872FB01',
 PART_NUMBER='CS24872FB01',
 VALUE='4.87K',
 PRIM_FILE='./archive_libs/logical/q_res/chips/chips.prt';

PART_NAME
 PR135 'Q_RES_0402LF-5.6,1%,1/16W,CHIP,CS-5602FB01':;

SECTION_NUMBER 1
 '@T6G_MB_LIB.T6G(SCH_1):PAGE183_I46@PURE_QUANTA.Q_RES(CHIPS)':
 C_PATH='@t6g_mb_lib.t6g(sch_1):page183_i46@pure_quanta.q_res(chips)',
 P_PATH='@t6g_mb_lib.t6g(sch_1):page208_i46@pure_quanta.q_res(chips)',
 PATH='I46',
 DRAWING='@T6G_MB_LIB.T6G(SCH_1):PAGE183',
 WATTAGE='1/16W',
 TOLERANCE='1%',
 MATERIAL='CHIP',
 PHYS_PAGE='208',
 XY='(-4750,4775)',
 ROT='0',
 VER='1',
 PACK_TYPE='0402LF',
 LOCATION='PR135',
 CDS_LIB='pure_quanta',
 CDS_PART_NAME='Q_RES_0402LF-5.6,1%,1/16W,CHIP,CS-5602FB01',
 PART_NUMBER='CS-5602FB01',
 VALUE='5.6',
 PRIM_FILE='./archive_libs/logical/q_res/chips/chips.prt';

PART_NAME
 PR136 'Q_RES_0402LF-5.6,1%,1/16W,CHIP,CS-5602FB01':;

SECTION_NUMBER 1
 '@T6G_MB_LIB.T6G(SCH_1):PAGE183_I25@PURE_QUANTA.Q_RES(CHIPS)':
 C_PATH='@t6g_mb_lib.t6g(sch_1):page183_i25@pure_quanta.q_res(chips)',
 P_PATH='@t6g_mb_lib.t6g(sch_1):page208_i25@pure_quanta.q_res(chips)',
 PATH='I25',
 DRAWING='@T6G_MB_LIB.T6G(SCH_1):PAGE183',
 WATTAGE='1/16W',
 TOLERANCE='1%',
 MATERIAL='CHIP',
 PHYS_PAGE='208',
 XY='(-4675,1850)',
 ROT='0',
 VER='1',
 PACK_TYPE='0402LF',
 LOCATION='PR136',
 CDS_LIB='pure_quanta',
 CDS_PART_NAME='Q_RES_0402LF-5.6,1%,1/16W,CHIP,CS-5602FB01',
 PART_NUMBER='CS-5602FB01',
 VALUE='5.6',
 PRIM_FILE='./archive_libs/logical/q_res/chips/chips.prt';

PART_NAME
 PR137 'Q_RES_0402LF-0,5%,1/16W,CHIP,CS00002JB13':;

SECTION_NUMBER 1
 '@T6G_MB_LIB.T6G(SCH_1):PAGE183_I56@PURE_QUANTA.Q_RES(CHIPS)':
 C_PATH='@t6g_mb_lib.t6g(sch_1):page183_i56@pure_quanta.q_res(chips)',
 P_PATH='@t6g_mb_lib.t6g(sch_1):page208_i56@pure_quanta.q_res(chips)',
 PATH='I56',
 DRAWING='@T6G_MB_LIB.T6G(SCH_1):PAGE183',
 WATTAGE='1/16W',
 TOLERANCE='5%',
 MATERIAL='CHIP',
 PHYS_PAGE='208',
 XY='(-3775,3450)',
 ROT='0',
 VER='1',
 PACK_TYPE='0402LF',
 LOCATION='PR137',
 CDS_LIB='pure_quanta',
 CDS_PART_NAME='Q_RES_0402LF-0,5%,1/16W,CHIP,CS00002JB13',
 PART_NUMBER='CS00002JB13',
 VALUE='0',
 PRIM_FILE='./archive_libs/logical/q_res/chips/chips.prt';

PART_NAME
 PR138 'Q_RES_0402LF-0,5%,1/16W,CHIP,CS00002JB13':;

SECTION_NUMBER 1
 '@T6G_MB_LIB.T6G(SCH_1):PAGE183_I91@PURE_QUANTA.Q_RES(CHIPS)':
 C_PATH='@t6g_mb_lib.t6g(sch_1):page183_i91@pure_quanta.q_res(chips)',
 P_PATH='@t6g_mb_lib.t6g(sch_1):page208_i91@pure_quanta.q_res(chips)',
 PATH='I91',
 DRAWING='@T6G_MB_LIB.T6G(SCH_1):PAGE183',
 WATTAGE='1/16W',
 TOLERANCE='5%',
 MATERIAL='CHIP',
 PHYS_PAGE='208',
 XY='(-3450,550)',
 ROT='0',
 VER='1',
 PACK_TYPE='0402LF',
 LOCATION='PR138',
 CDS_LIB='pure_quanta',
 CDS_PART_NAME='Q_RES_0402LF-0,5%,1/16W,CHIP,CS00002JB13',
 PART_NUMBER='CS00002JB13',
 VALUE='0',
 PRIM_FILE='./archive_libs/logical/q_res/chips/chips.prt';

PART_NAME
 PR147 'Q_RES_0402LF-10K,1%,1/16W,CHIP,CS31002FB08':;

SECTION_NUMBER 1
 '@T6G_MB_LIB.T6G(SCH_1):PAGE201_I30@PURE_QUANTA.Q_RES(CHIPS)':
 C_PATH='@t6g_mb_lib.t6g(sch_1):page201_i30@pure_quanta.q_res(chips)',
 P_PATH='@t6g_mb_lib.t6g(sch_1):page226_i30@pure_quanta.q_res(chips)',
 PATH='I30',
 DRAWING='@T6G_MB_LIB.T6G(SCH_1):PAGE201',
 WATTAGE='1/16W',
 TOLERANCE='1%',
 MATERIAL='CHIP',
 PHYS_PAGE='226',
 XY='(-3875,3250)',
 ROT='0',
 VER='2',
 PACK_TYPE='0402LF',
 LOCATION='PR147',
 CDS_LIB='pure_quanta',
 CDS_PART_NAME='Q_RES_0402LF-10K,1%,1/16W,CHIP,CS31002FB08',
 PART_NUMBER='CS31002FB08',
 VALUE='10K',
 PRIM_FILE='./archive_libs/logical/q_res/chips/chips.prt';

PART_NAME
 PR148 'Q_RES_0402LF-20K,1%,1/16W,CHIP,CS32002FB06':;

SECTION_NUMBER 1
 '@T6G_MB_LIB.T6G(SCH_1):PAGE201_I32@PURE_QUANTA.Q_RES(CHIPS)':
 C_PATH='@t6g_mb_lib.t6g(sch_1):page201_i32@pure_quanta.q_res(chips)',
 P_PATH='@t6g_mb_lib.t6g(sch_1):page226_i32@pure_quanta.q_res(chips)',
 PATH='I32',
 DRAWING='@T6G_MB_LIB.T6G(SCH_1):PAGE201',
 WATTAGE='1/16W',
 TOLERANCE='1%',
 MATERIAL='CHIP',
 PHYS_PAGE='226',
 XY='(-3275,3550)',
 ROT='0',
 VER='1',
 PACK_TYPE='0402LF',
 LOCATION='PR148',
 CDS_LIB='pure_quanta',
 CDS_PART_NAME='Q_RES_0402LF-20K,1%,1/16W,CHIP,CS32002FB06',
 PART_NUMBER='CS32002FB06',
 VALUE='20K',
 PRIM_FILE='./archive_libs/logical/q_res/chips/chips.prt';

PART_NAME
 PR150 'Q_RES_0402LF-0,5%,1/16W,CHIP,CS00002JB13':;

SECTION_NUMBER 1
 '@T6G_MB_LIB.T6G(SCH_1):PAGE185_I4@PURE_QUANTA.Q_RES(CHIPS)':
 C_PATH='@t6g_mb_lib.t6g(sch_1):page185_i4@pure_quanta.q_res(chips)',
 P_PATH='@t6g_mb_lib.t6g(sch_1):page210_i4@pure_quanta.q_res(chips)',
 PATH='I4',
 DRAWING='@T6G_MB_LIB.T6G(SCH_1):PAGE185',
 WATTAGE='1/16W',
 TOLERANCE='5%',
 MATERIAL='CHIP',
 PHYS_PAGE='210',
 XY='(-5300,6800)',
 ROT='0',
 VER='2',
 PACK_TYPE='0402LF',
 LOCATION='PR150',
 CDS_LIB='pure_quanta',
 CDS_PART_NAME='Q_RES_0402LF-0,5%,1/16W,CHIP,CS00002JB13',
 PART_NUMBER='CS00002JB13',
 VALUE='0',
 PRIM_FILE='./archive_libs/logical/q_res/chips/chips.prt';

PART_NAME
 PR151 'Q_RES_0402LF-1K,1%,1/16W,EMPTY,CS21002FB06':;

SECTION_NUMBER 1
 '@T6G_MB_LIB.T6G(SCH_1):PAGE185_I10@PURE_QUANTA.Q_RES(CHIPS)':
 C_PATH='@t6g_mb_lib.t6g(sch_1):page185_i10@pure_quanta.q_res(chips)',
 P_PATH='@t6g_mb_lib.t6g(sch_1):page210_i10@pure_quanta.q_res(chips)',
 PATH='I10',
 DRAWING='@T6G_MB_LIB.T6G(SCH_1):PAGE185',
 WATTAGE='1/16W',
 TOLERANCE='1%',
 MATERIAL='EMPTY',
 PHYS_PAGE='210',
 XY='(-5125,7750)',
 ROT='0',
 VER='2',
 PACK_TYPE='0402LF',
 LOCATION='PR151',
 CDS_LIB='pure_quanta',
 CDS_PART_NAME='Q_RES_0402LF-1K,1%,1/16W,EMPTY,CS21002FB06',
 PART_NUMBER='CS21002FB06',
 VALUE='1K',
 PRIM_FILE='./archive_libs/logical/q_res/chips/chips.prt';

PART_NAME
 PR152 'Q_RES_0402LF-1K,1%,1/16W,CHIP,CS21002FB06':;

SECTION_NUMBER 1
 '@T6G_MB_LIB.T6G(SCH_1):PAGE185_I17@PURE_QUANTA.Q_RES(CHIPS)':
 C_PATH='@t6g_mb_lib.t6g(sch_1):page185_i17@pure_quanta.q_res(chips)',
 P_PATH='@t6g_mb_lib.t6g(sch_1):page210_i17@pure_quanta.q_res(chips)',
 PATH='I17',
 DRAWING='@T6G_MB_LIB.T6G(SCH_1):PAGE185',
 WATTAGE='1/16W',
 TOLERANCE='1%',
 MATERIAL='CHIP',
 PHYS_PAGE='210',
 XY='(-4550,3850)',
 ROT='0',
 VER='2',
 PACK_TYPE='0402LF',
 LOCATION='PR152',
 CDS_LIB='pure_quanta',
 CDS_PART_NAME='Q_RES_0402LF-1K,1%,1/16W,CHIP,CS21002FB06',
 PART_NUMBER='CS21002FB06',
 VALUE='1K',
 PRIM_FILE='./archive_libs/logical/q_res/chips/chips.prt';

PART_NAME
 PR155 'Q_RES_0402LF-1.5,1%,1/8W,EMPTY,CS-1504FB00':;

SECTION_NUMBER 1
 '@T6G_MB_LIB.T6G(SCH_1):PAGE178_I33@PURE_QUANTA.Q_RES(CHIPS)':
 C_PATH='@t6g_mb_lib.t6g(sch_1):page178_i33@pure_quanta.q_res(chips)',
 P_PATH='@t6g_mb_lib.t6g(sch_1):page203_i33@pure_quanta.q_res(chips)',
 PATH='I33',
 DRAWING='@T6G_MB_LIB.T6G(SCH_1):PAGE178',
 WATTAGE='1/8W',
 TOLERANCE='1%',
 MATERIAL='EMPTY',
 PHYS_PAGE='203',
 XY='(4800,1475)',
 ROT='0',
 VER='2',
 PACK_TYPE='0402LF',
 LOCATION='PR155',
 CDS_LIB='pure_quanta',
 CDS_PART_NAME='Q_RES_0402LF-1.5,1%,1/8W,EMPTY,CS-1504FB00',
 PART_NUMBER='CS-1504FB00',
 VALUE='1.5',
 PRIM_FILE='./archive_libs/logical/q_res/chips/chips.prt';

PART_NAME
 PR157 'Q_RES_0402LF-40.2K,1%,1/16W,CHIP,CS34022FB04':;

SECTION_NUMBER 1
 '@T6G_MB_LIB.T6G(SCH_1):PAGE185_I14@PURE_QUANTA.Q_RES(CHIPS)':
 C_PATH='@t6g_mb_lib.t6g(sch_1):page185_i14@pure_quanta.q_res(chips)',
 P_PATH='@t6g_mb_lib.t6g(sch_1):page210_i14@pure_quanta.q_res(chips)',
 PATH='I14',
 DRAWING='@T6G_MB_LIB.T6G(SCH_1):PAGE185',
 WATTAGE='1/16W',
 TOLERANCE='1%',
 MATERIAL='CHIP',
 PHYS_PAGE='210',
 XY='(-4025,2600)',
 ROT='0',
 VER='1',
 PACK_TYPE='0402LF',
 LOCATION='PR157',
 CDS_LIB='pure_quanta',
 CDS_PART_NAME='Q_RES_0402LF-40.2K,1%,1/16W,CHIP,CS34022FB04',
 PART_NUMBER='CS34022FB04',
 VALUE='40.2K',
 PRIM_FILE='./archive_libs/logical/q_res/chips/chips.prt';

PART_NAME
 PR158 'Q_RES_0402LF-1.5,1%,1/8W,EMPTY,CS-1504FB00':;

SECTION_NUMBER 1
 '@T6G_MB_LIB.T6G(SCH_1):PAGE178_I44@PURE_QUANTA.Q_RES(CHIPS)':
 C_PATH='@t6g_mb_lib.t6g(sch_1):page178_i44@pure_quanta.q_res(chips)',
 P_PATH='@t6g_mb_lib.t6g(sch_1):page203_i44@pure_quanta.q_res(chips)',
 PATH='I44',
 DRAWING='@T6G_MB_LIB.T6G(SCH_1):PAGE178',
 WATTAGE='1/8W',
 TOLERANCE='1%',
 MATERIAL='EMPTY',
 PHYS_PAGE='203',
 XY='(4900,4150)',
 ROT='0',
 VER='2',
 PACK_TYPE='0402LF',
 LOCATION='PR158',
 CDS_LIB='pure_quanta',
 CDS_PART_NAME='Q_RES_0402LF-1.5,1%,1/8W,EMPTY,CS-1504FB00',
 PART_NUMBER='CS-1504FB00',
 VALUE='1.5',
 PRIM_FILE='./archive_libs/logical/q_res/chips/chips.prt';

PART_NAME
 PR159 'Q_RES_0402LF-5.23K,1%,1/16W,CHIP,CS25232FB08':;

SECTION_NUMBER 1
 '@T6G_MB_LIB.T6G(SCH_1):PAGE185_I142@PURE_QUANTA.Q_RES(CHIPS)':
 C_PATH='@t6g_mb_lib.t6g(sch_1):page185_i142@pure_quanta.q_res(chips)',
 P_PATH='@t6g_mb_lib.t6g(sch_1):page210_i142@pure_quanta.q_res(chips)',
 PATH='I142',
 DRAWING='@T6G_MB_LIB.T6G(SCH_1):PAGE185',
 WATTAGE='1/16W',
 TOLERANCE='1%',
 MATERIAL='CHIP',
 PHYS_PAGE='210',
 XY='(-3875,3150)',
 ROT='0',
 VER='2',
 PACK_TYPE='0402LF',
 LOCATION='PR159',
 CDS_LIB='pure_quanta',
 CDS_PART_NAME='Q_RES_0402LF-5.23K,1%,1/16W,CHIP,CS25232FB08',
 PART_NUMBER='CS25232FB08',
 VALUE='5.23K',
 PRIM_FILE='./archive_libs/logical/q_res/chips/chips.prt';

PART_NAME
 PR161 'Q_RES_0402LF-49.9,1%,1/16W,CHIP,CS04992FB07':;

SECTION_NUMBER 1
 '@T6G_MB_LIB.T6G(SCH_1):PAGE185_I70@PURE_QUANTA.Q_RES(CHIPS)':
 C_PATH='@t6g_mb_lib.t6g(sch_1):page185_i70@pure_quanta.q_res(chips)',
 P_PATH='@t6g_mb_lib.t6g(sch_1):page210_i70@pure_quanta.q_res(chips)',
 PATH='I70',
 DRAWING='@T6G_MB_LIB.T6G(SCH_1):PAGE185',
 WATTAGE='1/16W',
 TOLERANCE='1%',
 MATERIAL='CHIP',
 PHYS_PAGE='210',
 XY='(-3875,6025)',
 ROT='0',
 VER='2',
 PACK_TYPE='0402LF',
 LOCATION='PR161',
 CDS_LIB='pure_quanta',
 CDS_PART_NAME='Q_RES_0402LF-49.9,1%,1/16W,CHIP,CS04992FB07',
 PART_NUMBER='CS04992FB07',
 VALUE='49.9',
 PRIM_FILE='./archive_libs/logical/q_res/chips/chips.prt';

PART_NAME
 PR162 'Q_RES_0402LF-49.9,1%,1/16W,CHIP,CS04992FB07':;

SECTION_NUMBER 1
 '@T6G_MB_LIB.T6G(SCH_1):PAGE185_I45@PURE_QUANTA.Q_RES(CHIPS)':
 C_PATH='@t6g_mb_lib.t6g(sch_1):page185_i45@pure_quanta.q_res(chips)',
 P_PATH='@t6g_mb_lib.t6g(sch_1):page210_i45@pure_quanta.q_res(chips)',
 PATH='I45',
 DRAWING='@T6G_MB_LIB.T6G(SCH_1):PAGE185',
 WATTAGE='1/16W',
 TOLERANCE='1%',
 MATERIAL='CHIP',
 PHYS_PAGE='210',
 XY='(-3875,5400)',
 ROT='0',
 VER='2',
 PACK_TYPE='0402LF',
 LOCATION='PR162',
 CDS_LIB='pure_quanta',
 CDS_PART_NAME='Q_RES_0402LF-49.9,1%,1/16W,CHIP,CS04992FB07',
 PART_NUMBER='CS04992FB07',
 VALUE='49.9',
 PRIM_FILE='./archive_libs/logical/q_res/chips/chips.prt';

PART_NAME
 PR163 'Q_RES_0402LF-49.9,1%,1/16W,CHIP,CS04992FB07':;

SECTION_NUMBER 1
 '@T6G_MB_LIB.T6G(SCH_1):PAGE185_I39@PURE_QUANTA.Q_RES(CHIPS)':
 C_PATH='@t6g_mb_lib.t6g(sch_1):page185_i39@pure_quanta.q_res(chips)',
 P_PATH='@t6g_mb_lib.t6g(sch_1):page210_i39@pure_quanta.q_res(chips)',
 PATH='I39',
 DRAWING='@T6G_MB_LIB.T6G(SCH_1):PAGE185',
 WATTAGE='1/16W',
 TOLERANCE='1%',
 MATERIAL='CHIP',
 PHYS_PAGE='210',
 XY='(-3875,4900)',
 ROT='0',
 VER='2',
 PACK_TYPE='0402LF',
 LOCATION='PR163',
 CDS_LIB='pure_quanta',
 CDS_PART_NAME='Q_RES_0402LF-49.9,1%,1/16W,CHIP,CS04992FB07',
 PART_NUMBER='CS04992FB07',
 VALUE='49.9',
 PRIM_FILE='./archive_libs/logical/q_res/chips/chips.prt';

PART_NAME
 PR164 'Q_RES_0402LF-49.9,1%,1/16W,CHIP,CS04992FB07':;

SECTION_NUMBER 1
 '@T6G_MB_LIB.T6G(SCH_1):PAGE185_I36@PURE_QUANTA.Q_RES(CHIPS)':
 C_PATH='@t6g_mb_lib.t6g(sch_1):page185_i36@pure_quanta.q_res(chips)',
 P_PATH='@t6g_mb_lib.t6g(sch_1):page210_i36@pure_quanta.q_res(chips)',
 PATH='I36',
 DRAWING='@T6G_MB_LIB.T6G(SCH_1):PAGE185',
 WATTAGE='1/16W',
 TOLERANCE='1%',
 MATERIAL='CHIP',
 PHYS_PAGE='210',
 XY='(-3875,4300)',
 ROT='0',
 VER='2',
 PACK_TYPE='0402LF',
 LOCATION='PR164',
 CDS_LIB='pure_quanta',
 CDS_PART_NAME='Q_RES_0402LF-49.9,1%,1/16W,CHIP,CS04992FB07',
 PART_NUMBER='CS04992FB07',
 VALUE='49.9',
 PRIM_FILE='./archive_libs/logical/q_res/chips/chips.prt';

PART_NAME
 PR169 'Q_RES_0402LF-0,5%,1/16W,CHIP,CS00002JB13':;

SECTION_NUMBER 1
 '@T6G_MB_LIB.T6G(SCH_1):PAGE54_I334@PURE_QUANTA.Q_RES(CHIPS)':
 C_PATH='@t6g_mb_lib.t6g(sch_1):page54_i334@pure_quanta.q_res(chips)',
 P_PATH='@t6g_mb_lib.t6g(sch_1):page54_i334@pure_quanta.q_res(chips)',
 PATH='I334',
 DRAWING='@T6G_MB_LIB.T6G(SCH_1):PAGE54',
 WATTAGE='1/16W',
 TOLERANCE='5%',
 MATERIAL='CHIP',
 PHYS_PAGE='54',
 XY='(-6775,5775)',
 ROT='0',
 VER='1',
 PACK_TYPE='0402LF',
 LOCATION='PR169',
 CDS_LIB='pure_quanta',
 CDS_PART_NAME='Q_RES_0402LF-0,5%,1/16W,CHIP,CS00002JB13',
 PART_NUMBER='CS00002JB13',
 VALUE='0',
 PRIM_FILE='./archive_libs/logical/q_res/chips/chips.prt';

PART_NAME
 PR170 'Q_RES_0402LF-0,5%,1/16W,CHIP,CS00002JB13':;

SECTION_NUMBER 1
 '@T6G_MB_LIB.T6G(SCH_1):PAGE54_I333@PURE_QUANTA.Q_RES(CHIPS)':
 C_PATH='@t6g_mb_lib.t6g(sch_1):page54_i333@pure_quanta.q_res(chips)',
 P_PATH='@t6g_mb_lib.t6g(sch_1):page54_i333@pure_quanta.q_res(chips)',
 PATH='I333',
 DRAWING='@T6G_MB_LIB.T6G(SCH_1):PAGE54',
 WATTAGE='1/16W',
 TOLERANCE='5%',
 MATERIAL='CHIP',
 PHYS_PAGE='54',
 XY='(-6775,5725)',
 ROT='0',
 VER='1',
 PACK_TYPE='0402LF',
 LOCATION='PR170',
 CDS_LIB='pure_quanta',
 CDS_PART_NAME='Q_RES_0402LF-0,5%,1/16W,CHIP,CS00002JB13',
 PART_NUMBER='CS00002JB13',
 VALUE='0',
 PRIM_FILE='./archive_libs/logical/q_res/chips/chips.prt';

PART_NAME
 PR172 'Q_RES_0402LF-0,5%,1/16W,CHIP,CS00002JB13':;

SECTION_NUMBER 1
 '@T6G_MB_LIB.T6G(SCH_1):PAGE185_I82@PURE_QUANTA.Q_RES(CHIPS)':
 C_PATH='@t6g_mb_lib.t6g(sch_1):page185_i82@pure_quanta.q_res(chips)',
 P_PATH='@t6g_mb_lib.t6g(sch_1):page210_i82@pure_quanta.q_res(chips)',
 PATH='I82',
 DRAWING='@T6G_MB_LIB.T6G(SCH_1):PAGE185',
 WATTAGE='1/16W',
 TOLERANCE='5%',
 MATERIAL='CHIP',
 PHYS_PAGE='210',
 XY='(-2800,6975)',
 ROT='0',
 VER='1',
 PACK_TYPE='0402LF',
 LOCATION='PR172',
 CDS_LIB='pure_quanta',
 CDS_PART_NAME='Q_RES_0402LF-0,5%,1/16W,CHIP,CS00002JB13',
 PART_NUMBER='CS00002JB13',
 VALUE='0',
 PRIM_FILE='./archive_libs/logical/q_res/chips/chips.prt';

PART_NAME
 PR173 'Q_RES_0402LF-0,5%,1/16W,CHIP,CS00002JB13':;

SECTION_NUMBER 1
 '@T6G_MB_LIB.T6G(SCH_1):PAGE185_I59@PURE_QUANTA.Q_RES(CHIPS)':
 C_PATH='@t6g_mb_lib.t6g(sch_1):page185_i59@pure_quanta.q_res(chips)',
 P_PATH='@t6g_mb_lib.t6g(sch_1):page210_i59@pure_quanta.q_res(chips)',
 PATH='I59',
 DRAWING='@T6G_MB_LIB.T6G(SCH_1):PAGE185',
 WATTAGE='1/16W',
 TOLERANCE='5%',
 MATERIAL='CHIP',
 PHYS_PAGE='210',
 XY='(-2800,5825)',
 ROT='0',
 VER='1',
 PACK_TYPE='0402LF',
 LOCATION='PR173',
 CDS_LIB='pure_quanta',
 CDS_PART_NAME='Q_RES_0402LF-0,5%,1/16W,CHIP,CS00002JB13',
 PART_NUMBER='CS00002JB13',
 VALUE='0',
 PRIM_FILE='./archive_libs/logical/q_res/chips/chips.prt';

PART_NAME
 PR174 'Q_RES_0402LF-0,5%,1/16W,CHIP,CS00002JB13':;

SECTION_NUMBER 1
 '@T6G_MB_LIB.T6G(SCH_1):PAGE185_I57@PURE_QUANTA.Q_RES(CHIPS)':
 C_PATH='@t6g_mb_lib.t6g(sch_1):page185_i57@pure_quanta.q_res(chips)',
 P_PATH='@t6g_mb_lib.t6g(sch_1):page210_i57@pure_quanta.q_res(chips)',
 PATH='I57',
 DRAWING='@T6G_MB_LIB.T6G(SCH_1):PAGE185',
 WATTAGE='1/16W',
 TOLERANCE='5%',
 MATERIAL='CHIP',
 PHYS_PAGE='210',
 XY='(-2725,4725)',
 ROT='0',
 VER='1',
 PACK_TYPE='0402LF',
 LOCATION='PR174',
 CDS_LIB='pure_quanta',
 CDS_PART_NAME='Q_RES_0402LF-0,5%,1/16W,CHIP,CS00002JB13',
 PART_NUMBER='CS00002JB13',
 VALUE='0',
 PRIM_FILE='./archive_libs/logical/q_res/chips/chips.prt';

PART_NAME
 PR181 'Q_RES_0402LF-0,5%,1/16W,CHIP,CS00002JB13':;

SECTION_NUMBER 1
 '@T6G_MB_LIB.T6G(SCH_1):PAGE185_I47@PURE_QUANTA.Q_RES(CHIPS)':
 C_PATH='@t6g_mb_lib.t6g(sch_1):page185_i47@pure_quanta.q_res(chips)',
 P_PATH='@t6g_mb_lib.t6g(sch_1):page210_i47@pure_quanta.q_res(chips)',
 PATH='I47',
 DRAWING='@T6G_MB_LIB.T6G(SCH_1):PAGE185',
 WATTAGE='1/16W',
 TOLERANCE='5%',
 MATERIAL='CHIP',
 PHYS_PAGE='210',
 XY='(-2725,2425)',
 ROT='0',
 VER='1',
 PACK_TYPE='0402LF',
 LOCATION='PR181',
 CDS_LIB='pure_quanta',
 CDS_PART_NAME='Q_RES_0402LF-0,5%,1/16W,CHIP,CS00002JB13',
 PART_NUMBER='CS00002JB13',
 VALUE='0',
 PRIM_FILE='./archive_libs/logical/q_res/chips/chips.prt';

PART_NAME
 PR183 'Q_RES_0402LF-1,1%,1/16W,CHIP,CS-1002FB04':;

SECTION_NUMBER 1
 '@T6G_MB_LIB.T6G(SCH_1):PAGE185_I129@PURE_QUANTA.Q_RES(CHIPS)':
 C_PATH='@t6g_mb_lib.t6g(sch_1):page185_i129@pure_quanta.q_res(chips)',
 P_PATH='@t6g_mb_lib.t6g(sch_1):page210_i129@pure_quanta.q_res(chips)',
 PATH='I129',
 DRAWING='@T6G_MB_LIB.T6G(SCH_1):PAGE185',
 WATTAGE='1/16W',
 TOLERANCE='1%',
 MATERIAL='CHIP',
 PHYS_PAGE='210',
 XY='(750,8050)',
 ROT='0',
 VER='1',
 PACK_TYPE='0402LF',
 LOCATION='PR183',
 CDS_LIB='pure_quanta',
 CDS_PART_NAME='Q_RES_0402LF-1,1%,1/16W,CHIP,CS-1002FB04',
 PART_NUMBER='CS-1002FB04',
 VALUE='1',
 PRIM_FILE='./archive_libs/logical/q_res/chips/chips.prt';

PART_NAME
 PR185 'Q_RES_0402LF-2.2,1%,1/16W,CHIP,CS-2202FB01':;

SECTION_NUMBER 1
 '@T6G_MB_LIB.T6G(SCH_1):PAGE186_I43@PURE_QUANTA.Q_RES(CHIPS)':
 C_PATH='@t6g_mb_lib.t6g(sch_1):page186_i43@pure_quanta.q_res(chips)',
 P_PATH='@t6g_mb_lib.t6g(sch_1):page211_i43@pure_quanta.q_res(chips)',
 PATH='I43',
 DRAWING='@T6G_MB_LIB.T6G(SCH_1):PAGE186',
 WATTAGE='1/16W',
 TOLERANCE='1%',
 MATERIAL='CHIP',
 PHYS_PAGE='211',
 XY='(-7600,5350)',
 ROT='0',
 VER='2',
 PACK_TYPE='0402LF',
 LOCATION='PR185',
 CDS_LIB='pure_quanta',
 CDS_PART_NAME='Q_RES_0402LF-2.2,1%,1/16W,CHIP,CS-2202FB01',
 PART_NUMBER='CS-2202FB01',
 VALUE='2.2',
 PRIM_FILE='./archive_libs/logical/q_res/chips/chips.prt';

PART_NAME
 PR186 'Q_RES_0402LF-2.2,1%,1/16W,CHIP,CS-2202FB01':;

SECTION_NUMBER 1
 '@T6G_MB_LIB.T6G(SCH_1):PAGE186_I11@PURE_QUANTA.Q_RES(CHIPS)':
 C_PATH='@t6g_mb_lib.t6g(sch_1):page186_i11@pure_quanta.q_res(chips)',
 P_PATH='@t6g_mb_lib.t6g(sch_1):page211_i11@pure_quanta.q_res(chips)',
 PATH='I11',
 DRAWING='@T6G_MB_LIB.T6G(SCH_1):PAGE186',
 WATTAGE='1/16W',
 TOLERANCE='1%',
 MATERIAL='CHIP',
 PHYS_PAGE='211',
 XY='(-7575,2600)',
 ROT='0',
 VER='2',
 PACK_TYPE='0402LF',
 LOCATION='PR186',
 CDS_LIB='pure_quanta',
 CDS_PART_NAME='Q_RES_0402LF-2.2,1%,1/16W,CHIP,CS-2202FB01',
 PART_NUMBER='CS-2202FB01',
 VALUE='2.2',
 PRIM_FILE='./archive_libs/logical/q_res/chips/chips.prt';

PART_NAME
 PR187 'Q_RES_0402LF-8.87K,1%,1/16W,EMPTY,CS28872FB01':;

SECTION_NUMBER 1
 '@T6G_MB_LIB.T6G(SCH_1):PAGE186_I37@PURE_QUANTA.Q_RES(CHIPS)':
 C_PATH='@t6g_mb_lib.t6g(sch_1):page186_i37@pure_quanta.q_res(chips)',
 P_PATH='@t6g_mb_lib.t6g(sch_1):page211_i37@pure_quanta.q_res(chips)',
 PATH='I37',
 DRAWING='@T6G_MB_LIB.T6G(SCH_1):PAGE186',
 WATTAGE='1/16W',
 TOLERANCE='1%',
 MATERIAL='EMPTY',
 PHYS_PAGE='211',
 XY='(-7300,4150)',
 ROT='0',
 VER='1',
 PACK_TYPE='0402LF',
 LOCATION='PR187',
 CDS_LIB='pure_quanta',
 CDS_PART_NAME='Q_RES_0402LF-8.87K,1%,1/16W,EMPTY,CS28872FB01',
 PART_NUMBER='CS28872FB01',
 VALUE='8.87K',
 PRIM_FILE='./archive_libs/logical/q_res/chips/chips.prt';

PART_NAME
 PR188 'Q_RES_0402LF-8.87K,1%,1/16W,EMPTY,CS28872FB01':;

SECTION_NUMBER 1
 '@T6G_MB_LIB.T6G(SCH_1):PAGE186_I80@PURE_QUANTA.Q_RES(CHIPS)':
 C_PATH='@t6g_mb_lib.t6g(sch_1):page186_i80@pure_quanta.q_res(chips)',
 P_PATH='@t6g_mb_lib.t6g(sch_1):page211_i80@pure_quanta.q_res(chips)',
 PATH='I80',
 DRAWING='@T6G_MB_LIB.T6G(SCH_1):PAGE186',
 WATTAGE='1/16W',
 TOLERANCE='1%',
 MATERIAL='EMPTY',
 PHYS_PAGE='211',
 XY='(-7275,1400)',
 ROT='0',
 VER='1',
 PACK_TYPE='0402LF',
 LOCATION='PR188',
 CDS_LIB='pure_quanta',
 CDS_PART_NAME='Q_RES_0402LF-8.87K,1%,1/16W,EMPTY,CS28872FB01',
 PART_NUMBER='CS28872FB01',
 VALUE='8.87K',
 PRIM_FILE='./archive_libs/logical/q_res/chips/chips.prt';

PART_NAME
 PR189 'Q_RES_0402LF-5.6,1%,1/16W,CHIP,CS-5602FB01':;

SECTION_NUMBER 1
 '@T6G_MB_LIB.T6G(SCH_1):PAGE186_I49@PURE_QUANTA.Q_RES(CHIPS)':
 C_PATH='@t6g_mb_lib.t6g(sch_1):page186_i49@pure_quanta.q_res(chips)',
 P_PATH='@t6g_mb_lib.t6g(sch_1):page211_i49@pure_quanta.q_res(chips)',
 PATH='I49',
 DRAWING='@T6G_MB_LIB.T6G(SCH_1):PAGE186',
 WATTAGE='1/16W',
 TOLERANCE='1%',
 MATERIAL='CHIP',
 PHYS_PAGE='211',
 XY='(-4875,4800)',
 ROT='0',
 VER='1',
 PACK_TYPE='0402LF',
 LOCATION='PR189',
 CDS_LIB='pure_quanta',
 CDS_PART_NAME='Q_RES_0402LF-5.6,1%,1/16W,CHIP,CS-5602FB01',
 PART_NUMBER='CS-5602FB01',
 VALUE='5.6',
 PRIM_FILE='./archive_libs/logical/q_res/chips/chips.prt';

PART_NAME
 PR190 'Q_RES_0402LF-5.6,1%,1/16W,CHIP,CS-5602FB01':;

SECTION_NUMBER 1
 '@T6G_MB_LIB.T6G(SCH_1):PAGE186_I83@PURE_QUANTA.Q_RES(CHIPS)':
 C_PATH='@t6g_mb_lib.t6g(sch_1):page186_i83@pure_quanta.q_res(chips)',
 P_PATH='@t6g_mb_lib.t6g(sch_1):page211_i83@pure_quanta.q_res(chips)',
 PATH='I83',
 DRAWING='@T6G_MB_LIB.T6G(SCH_1):PAGE186',
 WATTAGE='1/16W',
 TOLERANCE='1%',
 MATERIAL='CHIP',
 PHYS_PAGE='211',
 XY='(-4675,2050)',
 ROT='0',
 VER='1',
 PACK_TYPE='0402LF',
 LOCATION='PR190',
 CDS_LIB='pure_quanta',
 CDS_PART_NAME='Q_RES_0402LF-5.6,1%,1/16W,CHIP,CS-5602FB01',
 PART_NUMBER='CS-5602FB01',
 VALUE='5.6',
 PRIM_FILE='./archive_libs/logical/q_res/chips/chips.prt';

PART_NAME
 PR191 'Q_RES_0402LF-0,5%,1/16W,CHIP,CS00002JB13':;

SECTION_NUMBER 1
 '@T6G_MB_LIB.T6G(SCH_1):PAGE186_I35@PURE_QUANTA.Q_RES(CHIPS)':
 C_PATH='@t6g_mb_lib.t6g(sch_1):page186_i35@pure_quanta.q_res(chips)',
 P_PATH='@t6g_mb_lib.t6g(sch_1):page211_i35@pure_quanta.q_res(chips)',
 PATH='I35',
 DRAWING='@T6G_MB_LIB.T6G(SCH_1):PAGE186',
 WATTAGE='1/16W',
 TOLERANCE='5%',
 MATERIAL='CHIP',
 PHYS_PAGE='211',
 XY='(-4325,3475)',
 ROT='0',
 VER='1',
 PACK_TYPE='0402LF',
 LOCATION='PR191',
 CDS_LIB='pure_quanta',
 CDS_PART_NAME='Q_RES_0402LF-0,5%,1/16W,CHIP,CS00002JB13',
 PART_NUMBER='CS00002JB13',
 VALUE='0',
 PRIM_FILE='./archive_libs/logical/q_res/chips/chips.prt';

PART_NAME
 PR192 'Q_RES_0402LF-0,5%,1/16W,CHIP,CS00002JB13':;

SECTION_NUMBER 1
 '@T6G_MB_LIB.T6G(SCH_1):PAGE186_I23@PURE_QUANTA.Q_RES(CHIPS)':
 C_PATH='@t6g_mb_lib.t6g(sch_1):page186_i23@pure_quanta.q_res(chips)',
 P_PATH='@t6g_mb_lib.t6g(sch_1):page211_i23@pure_quanta.q_res(chips)',
 PATH='I23',
 DRAWING='@T6G_MB_LIB.T6G(SCH_1):PAGE186',
 WATTAGE='1/16W',
 TOLERANCE='5%',
 MATERIAL='CHIP',
 PHYS_PAGE='211',
 XY='(-4250,625)',
 ROT='0',
 VER='1',
 PACK_TYPE='0402LF',
 LOCATION='PR192',
 CDS_LIB='pure_quanta',
 CDS_PART_NAME='Q_RES_0402LF-0,5%,1/16W,CHIP,CS00002JB13',
 PART_NUMBER='CS00002JB13',
 VALUE='0',
 PRIM_FILE='./archive_libs/logical/q_res/chips/chips.prt';

PART_NAME
 PR193 'Q_RES_0402LF-2.2,1%,1/16W,CHIP,CS-2202FB01':;

SECTION_NUMBER 1
 '@T6G_MB_LIB.T6G(SCH_1):PAGE187_I38@PURE_QUANTA.Q_RES(CHIPS)':
 C_PATH='@t6g_mb_lib.t6g(sch_1):page187_i38@pure_quanta.q_res(chips)',
 P_PATH='@t6g_mb_lib.t6g(sch_1):page212_i38@pure_quanta.q_res(chips)',
 PATH='I38',
 DRAWING='@T6G_MB_LIB.T6G(SCH_1):PAGE187',
 WATTAGE='1/16W',
 TOLERANCE='1%',
 MATERIAL='CHIP',
 PHYS_PAGE='212',
 XY='(-7250,5775)',
 ROT='0',
 VER='2',
 PACK_TYPE='0402LF',
 LOCATION='PR193',
 CDS_LIB='pure_quanta',
 CDS_PART_NAME='Q_RES_0402LF-2.2,1%,1/16W,CHIP,CS-2202FB01',
 PART_NUMBER='CS-2202FB01',
 VALUE='2.2',
 PRIM_FILE='./archive_libs/logical/q_res/chips/chips.prt';

PART_NAME
 PR194 'Q_RES_0402LF-2.2,1%,1/16W,CHIP,CS-2202FB01':;

SECTION_NUMBER 1
 '@T6G_MB_LIB.T6G(SCH_1):PAGE187_I12@PURE_QUANTA.Q_RES(CHIPS)':
 C_PATH='@t6g_mb_lib.t6g(sch_1):page187_i12@pure_quanta.q_res(chips)',
 P_PATH='@t6g_mb_lib.t6g(sch_1):page212_i12@pure_quanta.q_res(chips)',
 PATH='I12',
 DRAWING='@T6G_MB_LIB.T6G(SCH_1):PAGE187',
 WATTAGE='1/16W',
 TOLERANCE='1%',
 MATERIAL='CHIP',
 PHYS_PAGE='212',
 XY='(-7150,2475)',
 ROT='0',
 VER='2',
 PACK_TYPE='0402LF',
 LOCATION='PR194',
 CDS_LIB='pure_quanta',
 CDS_PART_NAME='Q_RES_0402LF-2.2,1%,1/16W,CHIP,CS-2202FB01',
 PART_NUMBER='CS-2202FB01',
 VALUE='2.2',
 PRIM_FILE='./archive_libs/logical/q_res/chips/chips.prt';

PART_NAME
 PR195 'Q_RES_0402LF-8.87K,1%,1/16W,EMPTY,CS28872FB01':;

SECTION_NUMBER 1
 '@T6G_MB_LIB.T6G(SCH_1):PAGE187_I34@PURE_QUANTA.Q_RES(CHIPS)':
 C_PATH='@t6g_mb_lib.t6g(sch_1):page187_i34@pure_quanta.q_res(chips)',
 P_PATH='@t6g_mb_lib.t6g(sch_1):page212_i34@pure_quanta.q_res(chips)',
 PATH='I34',
 DRAWING='@T6G_MB_LIB.T6G(SCH_1):PAGE187',
 WATTAGE='1/16W',
 TOLERANCE='1%',
 MATERIAL='EMPTY',
 PHYS_PAGE='212',
 XY='(-6950,4575)',
 ROT='0',
 VER='1',
 PACK_TYPE='0402LF',
 LOCATION='PR195',
 CDS_LIB='pure_quanta',
 CDS_PART_NAME='Q_RES_0402LF-8.87K,1%,1/16W,EMPTY,CS28872FB01',
 PART_NUMBER='CS28872FB01',
 VALUE='8.87K',
 PRIM_FILE='./archive_libs/logical/q_res/chips/chips.prt';

PART_NAME
 PR196 'Q_RES_0402LF-8.87K,1%,1/16W,EMPTY,CS28872FB01':;

SECTION_NUMBER 1
 '@T6G_MB_LIB.T6G(SCH_1):PAGE187_I11@PURE_QUANTA.Q_RES(CHIPS)':
 C_PATH='@t6g_mb_lib.t6g(sch_1):page187_i11@pure_quanta.q_res(chips)',
 P_PATH='@t6g_mb_lib.t6g(sch_1):page212_i11@pure_quanta.q_res(chips)',
 PATH='I11',
 DRAWING='@T6G_MB_LIB.T6G(SCH_1):PAGE187',
 WATTAGE='1/16W',
 TOLERANCE='1%',
 MATERIAL='EMPTY',
 PHYS_PAGE='212',
 XY='(-6850,1275)',
 ROT='0',
 VER='1',
 PACK_TYPE='0402LF',
 LOCATION='PR196',
 CDS_LIB='pure_quanta',
 CDS_PART_NAME='Q_RES_0402LF-8.87K,1%,1/16W,EMPTY,CS28872FB01',
 PART_NUMBER='CS28872FB01',
 VALUE='8.87K',
 PRIM_FILE='./archive_libs/logical/q_res/chips/chips.prt';

PART_NAME
 PR197 'Q_RES_0402LF-5.6,1%,1/16W,CHIP,CS-5602FB01':;

SECTION_NUMBER 1
 '@T6G_MB_LIB.T6G(SCH_1):PAGE187_I47@PURE_QUANTA.Q_RES(CHIPS)':
 C_PATH='@t6g_mb_lib.t6g(sch_1):page187_i47@pure_quanta.q_res(chips)',
 P_PATH='@t6g_mb_lib.t6g(sch_1):page212_i47@pure_quanta.q_res(chips)',
 PATH='I47',
 DRAWING='@T6G_MB_LIB.T6G(SCH_1):PAGE187',
 WATTAGE='1/16W',
 TOLERANCE='1%',
 MATERIAL='CHIP',
 PHYS_PAGE='212',
 XY='(-4375,5225)',
 ROT='0',
 VER='1',
 PACK_TYPE='0402LF',
 LOCATION='PR197',
 CDS_LIB='pure_quanta',
 CDS_PART_NAME='Q_RES_0402LF-5.6,1%,1/16W,CHIP,CS-5602FB01',
 PART_NUMBER='CS-5602FB01',
 VALUE='5.6',
 PRIM_FILE='./archive_libs/logical/q_res/chips/chips.prt';

PART_NAME
 PR198 'Q_RES_0402LF-5.6,1%,1/16W,CHIP,CS-5602FB01':;

SECTION_NUMBER 1
 '@T6G_MB_LIB.T6G(SCH_1):PAGE187_I21@PURE_QUANTA.Q_RES(CHIPS)':
 C_PATH='@t6g_mb_lib.t6g(sch_1):page187_i21@pure_quanta.q_res(chips)',
 P_PATH='@t6g_mb_lib.t6g(sch_1):page212_i21@pure_quanta.q_res(chips)',
 PATH='I21',
 DRAWING='@T6G_MB_LIB.T6G(SCH_1):PAGE187',
 WATTAGE='1/16W',
 TOLERANCE='1%',
 MATERIAL='CHIP',
 PHYS_PAGE='212',
 XY='(-4300,1925)',
 ROT='0',
 VER='1',
 PACK_TYPE='0402LF',
 LOCATION='PR198',
 CDS_LIB='pure_quanta',
 CDS_PART_NAME='Q_RES_0402LF-5.6,1%,1/16W,CHIP,CS-5602FB01',
 PART_NUMBER='CS-5602FB01',
 VALUE='5.6',
 PRIM_FILE='./archive_libs/logical/q_res/chips/chips.prt';

PART_NAME
 PR199 'Q_RES_0402LF-0,5%,1/16W,CHIP,CS00002JB13':;

SECTION_NUMBER 1
 '@T6G_MB_LIB.T6G(SCH_1):PAGE187_I27@PURE_QUANTA.Q_RES(CHIPS)':
 C_PATH='@t6g_mb_lib.t6g(sch_1):page187_i27@pure_quanta.q_res(chips)',
 P_PATH='@t6g_mb_lib.t6g(sch_1):page212_i27@pure_quanta.q_res(chips)',
 PATH='I27',
 DRAWING='@T6G_MB_LIB.T6G(SCH_1):PAGE187',
 WATTAGE='1/16W',
 TOLERANCE='5%',
 MATERIAL='CHIP',
 PHYS_PAGE='212',
 XY='(-3975,3775)',
 ROT='0',
 VER='1',
 PACK_TYPE='0402LF',
 LOCATION='PR199',
 CDS_LIB='pure_quanta',
 CDS_PART_NAME='Q_RES_0402LF-0,5%,1/16W,CHIP,CS00002JB13',
 PART_NUMBER='CS00002JB13',
 VALUE='0',
 PRIM_FILE='./archive_libs/logical/q_res/chips/chips.prt';

PART_NAME
 PR200 'Q_RES_0402LF-0,5%,1/16W,CHIP,CS00002JB13':;

SECTION_NUMBER 1
 '@T6G_MB_LIB.T6G(SCH_1):PAGE187_I17@PURE_QUANTA.Q_RES(CHIPS)':
 C_PATH='@t6g_mb_lib.t6g(sch_1):page187_i17@pure_quanta.q_res(chips)',
 P_PATH='@t6g_mb_lib.t6g(sch_1):page212_i17@pure_quanta.q_res(chips)',
 PATH='I17',
 DRAWING='@T6G_MB_LIB.T6G(SCH_1):PAGE187',
 WATTAGE='1/16W',
 TOLERANCE='5%',
 MATERIAL='CHIP',
 PHYS_PAGE='212',
 XY='(-3925,475)',
 ROT='0',
 VER='1',
 PACK_TYPE='0402LF',
 LOCATION='PR200',
 CDS_LIB='pure_quanta',
 CDS_PART_NAME='Q_RES_0402LF-0,5%,1/16W,CHIP,CS00002JB13',
 PART_NUMBER='CS00002JB13',
 VALUE='0',
 PRIM_FILE='./archive_libs/logical/q_res/chips/chips.prt';

PART_NAME
 PR201 'Q_RES_0402LF-2.2,1%,1/16W,CHIP,CS-2202FB01':;

SECTION_NUMBER 1
 '@T6G_MB_LIB.T6G(SCH_1):PAGE188_I41@PURE_QUANTA.Q_RES(CHIPS)':
 C_PATH='@t6g_mb_lib.t6g(sch_1):page188_i41@pure_quanta.q_res(chips)',
 P_PATH='@t6g_mb_lib.t6g(sch_1):page213_i41@pure_quanta.q_res(chips)',
 PATH='I41',
 DRAWING='@T6G_MB_LIB.T6G(SCH_1):PAGE188',
 WATTAGE='1/16W',
 TOLERANCE='1%',
 MATERIAL='CHIP',
 PHYS_PAGE='213',
 XY='(-7200,5750)',
 ROT='0',
 VER='2',
 PACK_TYPE='0402LF',
 LOCATION='PR201',
 CDS_LIB='pure_quanta',
 CDS_PART_NAME='Q_RES_0402LF-2.2,1%,1/16W,CHIP,CS-2202FB01',
 PART_NUMBER='CS-2202FB01',
 VALUE='2.2',
 PRIM_FILE='./archive_libs/logical/q_res/chips/chips.prt';

PART_NAME
 PR202 'Q_RES_0402LF-8.87K,1%,1/16W,EMPTY,CS28872FB01':;

SECTION_NUMBER 1
 '@T6G_MB_LIB.T6G(SCH_1):PAGE188_I37@PURE_QUANTA.Q_RES(CHIPS)':
 C_PATH='@t6g_mb_lib.t6g(sch_1):page188_i37@pure_quanta.q_res(chips)',
 P_PATH='@t6g_mb_lib.t6g(sch_1):page213_i37@pure_quanta.q_res(chips)',
 PATH='I37',
 DRAWING='@T6G_MB_LIB.T6G(SCH_1):PAGE188',
 WATTAGE='1/16W',
 TOLERANCE='1%',
 MATERIAL='EMPTY',
 PHYS_PAGE='213',
 XY='(-6875,4550)',
 ROT='0',
 VER='1',
 PACK_TYPE='0402LF',
 LOCATION='PR202',
 CDS_LIB='pure_quanta',
 CDS_PART_NAME='Q_RES_0402LF-8.87K,1%,1/16W,EMPTY,CS28872FB01',
 PART_NUMBER='CS28872FB01',
 VALUE='8.87K',
 PRIM_FILE='./archive_libs/logical/q_res/chips/chips.prt';

PART_NAME
 PR203 'Q_RES_0402LF-5.6,1%,1/16W,CHIP,CS-5602FB01':;

SECTION_NUMBER 1
 '@T6G_MB_LIB.T6G(SCH_1):PAGE188_I47@PURE_QUANTA.Q_RES(CHIPS)':
 C_PATH='@t6g_mb_lib.t6g(sch_1):page188_i47@pure_quanta.q_res(chips)',
 P_PATH='@t6g_mb_lib.t6g(sch_1):page213_i47@pure_quanta.q_res(chips)',
 PATH='I47',
 DRAWING='@T6G_MB_LIB.T6G(SCH_1):PAGE188',
 WATTAGE='1/16W',
 TOLERANCE='1%',
 MATERIAL='CHIP',
 PHYS_PAGE='213',
 XY='(-4300,5200)',
 ROT='0',
 VER='1',
 PACK_TYPE='0402LF',
 LOCATION='PR203',
 CDS_LIB='pure_quanta',
 CDS_PART_NAME='Q_RES_0402LF-5.6,1%,1/16W,CHIP,CS-5602FB01',
 PART_NUMBER='CS-5602FB01',
 VALUE='5.6',
 PRIM_FILE='./archive_libs/logical/q_res/chips/chips.prt';

PART_NAME
 PR204 'Q_RES_0402LF-0,5%,1/16W,CHIP,CS00002JB13':;

SECTION_NUMBER 1
 '@T6G_MB_LIB.T6G(SCH_1):PAGE188_I33@PURE_QUANTA.Q_RES(CHIPS)':
 C_PATH='@t6g_mb_lib.t6g(sch_1):page188_i33@pure_quanta.q_res(chips)',
 P_PATH='@t6g_mb_lib.t6g(sch_1):page213_i33@pure_quanta.q_res(chips)',
 PATH='I33',
 DRAWING='@T6G_MB_LIB.T6G(SCH_1):PAGE188',
 WATTAGE='1/16W',
 TOLERANCE='5%',
 MATERIAL='CHIP',
 PHYS_PAGE='213',
 XY='(-3925,3750)',
 ROT='0',
 VER='1',
 PACK_TYPE='0402LF',
 LOCATION='PR204',
 CDS_LIB='pure_quanta',
 CDS_PART_NAME='Q_RES_0402LF-0,5%,1/16W,CHIP,CS00002JB13',
 PART_NUMBER='CS00002JB13',
 VALUE='0',
 PRIM_FILE='./archive_libs/logical/q_res/chips/chips.prt';

PART_NAME
 PR205 'Q_RES_0402LF-2.2,1%,1/16W,CHIP,CS-2202FB01':;

SECTION_NUMBER 1
 '@T6G_MB_LIB.T6G(SCH_1):PAGE190_I39@PURE_QUANTA.Q_RES(CHIPS)':
 C_PATH='@t6g_mb_lib.t6g(sch_1):page190_i39@pure_quanta.q_res(chips)',
 P_PATH='@t6g_mb_lib.t6g(sch_1):page215_i39@pure_quanta.q_res(chips)',
 PATH='I39',
 DRAWING='@T6G_MB_LIB.T6G(SCH_1):PAGE190',
 WATTAGE='1/16W',
 TOLERANCE='1%',
 MATERIAL='CHIP',
 PHYS_PAGE='215',
 XY='(-7550,5650)',
 ROT='0',
 VER='2',
 PACK_TYPE='0402LF',
 LOCATION='PR205',
 CDS_LIB='pure_quanta',
 CDS_PART_NAME='Q_RES_0402LF-2.2,1%,1/16W,CHIP,CS-2202FB01',
 PART_NUMBER='CS-2202FB01',
 VALUE='2.2',
 PRIM_FILE='./archive_libs/logical/q_res/chips/chips.prt';

PART_NAME
 PR206 'Q_RES_0402LF-2.2,1%,1/16W,CHIP,CS-2202FB01':;

SECTION_NUMBER 1
 '@T6G_MB_LIB.T6G(SCH_1):PAGE190_I12@PURE_QUANTA.Q_RES(CHIPS)':
 C_PATH='@t6g_mb_lib.t6g(sch_1):page190_i12@pure_quanta.q_res(chips)',
 P_PATH='@t6g_mb_lib.t6g(sch_1):page215_i12@pure_quanta.q_res(chips)',
 PATH='I12',
 DRAWING='@T6G_MB_LIB.T6G(SCH_1):PAGE190',
 WATTAGE='1/16W',
 TOLERANCE='1%',
 MATERIAL='CHIP',
 PHYS_PAGE='215',
 XY='(-7525,2875)',
 ROT='0',
 VER='2',
 PACK_TYPE='0402LF',
 LOCATION='PR206',
 CDS_LIB='pure_quanta',
 CDS_PART_NAME='Q_RES_0402LF-2.2,1%,1/16W,CHIP,CS-2202FB01',
 PART_NUMBER='CS-2202FB01',
 VALUE='2.2',
 PRIM_FILE='./archive_libs/logical/q_res/chips/chips.prt';

PART_NAME
 PR207 'Q_RES_0402LF-8.87K,1%,1/16W,EMPTY,CS28872FB01':;

SECTION_NUMBER 1
 '@T6G_MB_LIB.T6G(SCH_1):PAGE190_I35@PURE_QUANTA.Q_RES(CHIPS)':
 C_PATH='@t6g_mb_lib.t6g(sch_1):page190_i35@pure_quanta.q_res(chips)',
 P_PATH='@t6g_mb_lib.t6g(sch_1):page215_i35@pure_quanta.q_res(chips)',
 PATH='I35',
 DRAWING='@T6G_MB_LIB.T6G(SCH_1):PAGE190',
 WATTAGE='1/16W',
 TOLERANCE='1%',
 MATERIAL='EMPTY',
 PHYS_PAGE='215',
 XY='(-7200,4450)',
 ROT='0',
 VER='1',
 PACK_TYPE='0402LF',
 LOCATION='PR207',
 CDS_LIB='pure_quanta',
 CDS_PART_NAME='Q_RES_0402LF-8.87K,1%,1/16W,EMPTY,CS28872FB01',
 PART_NUMBER='CS28872FB01',
 VALUE='8.87K',
 PRIM_FILE='./archive_libs/logical/q_res/chips/chips.prt';

PART_NAME
 PR208 'Q_RES_0402LF-8.87K,1%,1/16W,EMPTY,CS28872FB01':;

SECTION_NUMBER 1
 '@T6G_MB_LIB.T6G(SCH_1):PAGE190_I8@PURE_QUANTA.Q_RES(CHIPS)':
 C_PATH='@t6g_mb_lib.t6g(sch_1):page190_i8@pure_quanta.q_res(chips)',
 P_PATH='@t6g_mb_lib.t6g(sch_1):page215_i8@pure_quanta.q_res(chips)',
 PATH='I8',
 DRAWING='@T6G_MB_LIB.T6G(SCH_1):PAGE190',
 WATTAGE='1/16W',
 TOLERANCE='1%',
 MATERIAL='EMPTY',
 PHYS_PAGE='215',
 XY='(-7175,1675)',
 ROT='0',
 VER='1',
 PACK_TYPE='0402LF',
 LOCATION='PR208',
 CDS_LIB='pure_quanta',
 CDS_PART_NAME='Q_RES_0402LF-8.87K,1%,1/16W,EMPTY,CS28872FB01',
 PART_NUMBER='CS28872FB01',
 VALUE='8.87K',
 PRIM_FILE='./archive_libs/logical/q_res/chips/chips.prt';

PART_NAME
 PR209 'Q_RES_0402LF-5.6,1%,1/16W,CHIP,CS-5602FB01':;

SECTION_NUMBER 1
 '@T6G_MB_LIB.T6G(SCH_1):PAGE190_I46@PURE_QUANTA.Q_RES(CHIPS)':
 C_PATH='@t6g_mb_lib.t6g(sch_1):page190_i46@pure_quanta.q_res(chips)',
 P_PATH='@t6g_mb_lib.t6g(sch_1):page215_i46@pure_quanta.q_res(chips)',
 PATH='I46',
 DRAWING='@T6G_MB_LIB.T6G(SCH_1):PAGE190',
 WATTAGE='1/16W',
 TOLERANCE='1%',
 MATERIAL='CHIP',
 PHYS_PAGE='215',
 XY='(-4800,5100)',
 ROT='0',
 VER='1',
 PACK_TYPE='0402LF',
 LOCATION='PR209',
 CDS_LIB='pure_quanta',
 CDS_PART_NAME='Q_RES_0402LF-5.6,1%,1/16W,CHIP,CS-5602FB01',
 PART_NUMBER='CS-5602FB01',
 VALUE='5.6',
 PRIM_FILE='./archive_libs/logical/q_res/chips/chips.prt';

PART_NAME
 PR210 'Q_RES_0402LF-5.6,1%,1/16W,CHIP,CS-5602FB01':;

SECTION_NUMBER 1
 '@T6G_MB_LIB.T6G(SCH_1):PAGE190_I24@PURE_QUANTA.Q_RES(CHIPS)':
 C_PATH='@t6g_mb_lib.t6g(sch_1):page190_i24@pure_quanta.q_res(chips)',
 P_PATH='@t6g_mb_lib.t6g(sch_1):page215_i24@pure_quanta.q_res(chips)',
 PATH='I24',
 DRAWING='@T6G_MB_LIB.T6G(SCH_1):PAGE190',
 WATTAGE='1/16W',
 TOLERANCE='1%',
 MATERIAL='CHIP',
 PHYS_PAGE='215',
 XY='(-4700,2325)',
 ROT='0',
 VER='1',
 PACK_TYPE='0402LF',
 LOCATION='PR210',
 CDS_LIB='pure_quanta',
 CDS_PART_NAME='Q_RES_0402LF-5.6,1%,1/16W,CHIP,CS-5602FB01',
 PART_NUMBER='CS-5602FB01',
 VALUE='5.6',
 PRIM_FILE='./archive_libs/logical/q_res/chips/chips.prt';

PART_NAME
 PR211 'Q_RES_0402LF-0,5%,1/16W,CHIP,CS00002JB13':;

SECTION_NUMBER 1
 '@T6G_MB_LIB.T6G(SCH_1):PAGE190_I30@PURE_QUANTA.Q_RES(CHIPS)':
 C_PATH='@t6g_mb_lib.t6g(sch_1):page190_i30@pure_quanta.q_res(chips)',
 P_PATH='@t6g_mb_lib.t6g(sch_1):page215_i30@pure_quanta.q_res(chips)',
 PATH='I30',
 DRAWING='@T6G_MB_LIB.T6G(SCH_1):PAGE190',
 WATTAGE='1/16W',
 TOLERANCE='5%',
 MATERIAL='CHIP',
 PHYS_PAGE='215',
 XY='(-4225,3725)',
 ROT='0',
 VER='1',
 PACK_TYPE='0402LF',
 LOCATION='PR211',
 CDS_LIB='pure_quanta',
 CDS_PART_NAME='Q_RES_0402LF-0,5%,1/16W,CHIP,CS00002JB13',
 PART_NUMBER='CS00002JB13',
 VALUE='0',
 PRIM_FILE='./archive_libs/logical/q_res/chips/chips.prt';

PART_NAME
 PR212 'Q_RES_0402LF-0,5%,1/16W,CHIP,CS00002JB13':;

SECTION_NUMBER 1
 '@T6G_MB_LIB.T6G(SCH_1):PAGE190_I85@PURE_QUANTA.Q_RES(CHIPS)':
 C_PATH='@t6g_mb_lib.t6g(sch_1):page190_i85@pure_quanta.q_res(chips)',
 P_PATH='@t6g_mb_lib.t6g(sch_1):page215_i85@pure_quanta.q_res(chips)',
 PATH='I85',
 DRAWING='@T6G_MB_LIB.T6G(SCH_1):PAGE190',
 WATTAGE='1/16W',
 TOLERANCE='5%',
 MATERIAL='CHIP',
 PHYS_PAGE='215',
 XY='(-4275,800)',
 ROT='0',
 VER='1',
 PACK_TYPE='0402LF',
 LOCATION='PR212',
 CDS_LIB='pure_quanta',
 CDS_PART_NAME='Q_RES_0402LF-0,5%,1/16W,CHIP,CS00002JB13',
 PART_NUMBER='CS00002JB13',
 VALUE='0',
 PRIM_FILE='./archive_libs/logical/q_res/chips/chips.prt';

PART_NAME
 PR213 'Q_RES_0402LF-2.2,1%,1/16W,CHIP,CS-2202FB01':;

SECTION_NUMBER 1
 '@T6G_MB_LIB.T6G(SCH_1):PAGE191_I14@PURE_QUANTA.Q_RES(CHIPS)':
 C_PATH='@t6g_mb_lib.t6g(sch_1):page191_i14@pure_quanta.q_res(chips)',
 P_PATH='@t6g_mb_lib.t6g(sch_1):page216_i14@pure_quanta.q_res(chips)',
 PATH='I14',
 DRAWING='@T6G_MB_LIB.T6G(SCH_1):PAGE191',
 WATTAGE='1/16W',
 TOLERANCE='1%',
 MATERIAL='CHIP',
 PHYS_PAGE='216',
 XY='(-7350,5400)',
 ROT='0',
 VER='2',
 PACK_TYPE='0402LF',
 LOCATION='PR213',
 CDS_LIB='pure_quanta',
 CDS_PART_NAME='Q_RES_0402LF-2.2,1%,1/16W,CHIP,CS-2202FB01',
 PART_NUMBER='CS-2202FB01',
 VALUE='2.2',
 PRIM_FILE='./archive_libs/logical/q_res/chips/chips.prt';

PART_NAME
 PR214 'Q_RES_0402LF-8.87K,1%,1/16W,EMPTY,CS28872FB01':;

SECTION_NUMBER 1
 '@T6G_MB_LIB.T6G(SCH_1):PAGE191_I7@PURE_QUANTA.Q_RES(CHIPS)':
 C_PATH='@t6g_mb_lib.t6g(sch_1):page191_i7@pure_quanta.q_res(chips)',
 P_PATH='@t6g_mb_lib.t6g(sch_1):page216_i7@pure_quanta.q_res(chips)',
 PATH='I7',
 DRAWING='@T6G_MB_LIB.T6G(SCH_1):PAGE191',
 WATTAGE='1/16W',
 TOLERANCE='1%',
 MATERIAL='EMPTY',
 PHYS_PAGE='216',
 XY='(-7000,4200)',
 ROT='0',
 VER='1',
 PACK_TYPE='0402LF',
 LOCATION='PR214',
 CDS_LIB='pure_quanta',
 CDS_PART_NAME='Q_RES_0402LF-8.87K,1%,1/16W,EMPTY,CS28872FB01',
 PART_NUMBER='CS28872FB01',
 VALUE='8.87K',
 PRIM_FILE='./archive_libs/logical/q_res/chips/chips.prt';

PART_NAME
 PR215 'Q_RES_0402LF-5.6,1%,1/16W,CHIP,CS-5602FB01':;

SECTION_NUMBER 1
 '@T6G_MB_LIB.T6G(SCH_1):PAGE191_I21@PURE_QUANTA.Q_RES(CHIPS)':
 C_PATH='@t6g_mb_lib.t6g(sch_1):page191_i21@pure_quanta.q_res(chips)',
 P_PATH='@t6g_mb_lib.t6g(sch_1):page216_i21@pure_quanta.q_res(chips)',
 PATH='I21',
 DRAWING='@T6G_MB_LIB.T6G(SCH_1):PAGE191',
 WATTAGE='1/16W',
 TOLERANCE='1%',
 MATERIAL='CHIP',
 PHYS_PAGE='216',
 XY='(-4475,4850)',
 ROT='0',
 VER='1',
 PACK_TYPE='0402LF',
 LOCATION='PR215',
 CDS_LIB='pure_quanta',
 CDS_PART_NAME='Q_RES_0402LF-5.6,1%,1/16W,CHIP,CS-5602FB01',
 PART_NUMBER='CS-5602FB01',
 VALUE='5.6',
 PRIM_FILE='./archive_libs/logical/q_res/chips/chips.prt';

PART_NAME
 PR216 'Q_RES_0402LF-0,5%,1/16W,CHIP,CS00002JB13':;

SECTION_NUMBER 1
 '@T6G_MB_LIB.T6G(SCH_1):PAGE191_I23@PURE_QUANTA.Q_RES(CHIPS)':
 C_PATH='@t6g_mb_lib.t6g(sch_1):page191_i23@pure_quanta.q_res(chips)',
 P_PATH='@t6g_mb_lib.t6g(sch_1):page216_i23@pure_quanta.q_res(chips)',
 PATH='I23',
 DRAWING='@T6G_MB_LIB.T6G(SCH_1):PAGE191',
 WATTAGE='1/16W',
 TOLERANCE='5%',
 MATERIAL='CHIP',
 PHYS_PAGE='216',
 XY='(-4000,3300)',
 ROT='0',
 VER='1',
 PACK_TYPE='0402LF',
 LOCATION='PR216',
 CDS_LIB='pure_quanta',
 CDS_PART_NAME='Q_RES_0402LF-0,5%,1/16W,CHIP,CS00002JB13',
 PART_NUMBER='CS00002JB13',
 VALUE='0',
 PRIM_FILE='./archive_libs/logical/q_res/chips/chips.prt';

PART_NAME
 PR217 'Q_RES_0402LF-0,5%,1/16W,CHIP,CS00002JB13':;

SECTION_NUMBER 1
 '@T6G_MB_LIB.T6G(SCH_1):PAGE192_I29@PURE_QUANTA.Q_RES(CHIPS)':
 C_PATH='@t6g_mb_lib.t6g(sch_1):page192_i29@pure_quanta.q_res(chips)',
 P_PATH='@t6g_mb_lib.t6g(sch_1):page217_i29@pure_quanta.q_res(chips)',
 PATH='I29',
 DRAWING='@T6G_MB_LIB.T6G(SCH_1):PAGE192',
 WATTAGE='1/16W',
 TOLERANCE='5%',
 MATERIAL='CHIP',
 PHYS_PAGE='217',
 XY='(-5000,6125)',
 ROT='0',
 VER='2',
 PACK_TYPE='0402LF',
 LOCATION='PR217',
 CDS_LIB='pure_quanta',
 CDS_PART_NAME='Q_RES_0402LF-0,5%,1/16W,CHIP,CS00002JB13',
 PART_NUMBER='CS00002JB13',
 VALUE='0',
 PRIM_FILE='./archive_libs/logical/q_res/chips/chips.prt';

PART_NAME
 PR218 'Q_RES_0402LF-1K,1%,1/16W,EMPTY,CS21002FB06':;

SECTION_NUMBER 1
 '@T6G_MB_LIB.T6G(SCH_1):PAGE192_I38@PURE_QUANTA.Q_RES(CHIPS)':
 C_PATH='@t6g_mb_lib.t6g(sch_1):page192_i38@pure_quanta.q_res(chips)',
 P_PATH='@t6g_mb_lib.t6g(sch_1):page217_i38@pure_quanta.q_res(chips)',
 PATH='I38',
 DRAWING='@T6G_MB_LIB.T6G(SCH_1):PAGE192',
 WATTAGE='1/16W',
 TOLERANCE='1%',
 MATERIAL='EMPTY',
 PHYS_PAGE='217',
 XY='(-4950,7100)',
 ROT='0',
 VER='2',
 PACK_TYPE='0402LF',
 LOCATION='PR218',
 CDS_LIB='pure_quanta',
 CDS_PART_NAME='Q_RES_0402LF-1K,1%,1/16W,EMPTY,CS21002FB06',
 PART_NUMBER='CS21002FB06',
 VALUE='1K',
 PRIM_FILE='./archive_libs/logical/q_res/chips/chips.prt';

PART_NAME
 PR221 'Q_RES_0402LF-1.5,1%,1/8W,EMPTY,CS-1504FB00':;

SECTION_NUMBER 1
 '@T6G_MB_LIB.T6G(SCH_1):PAGE180_I60@PURE_QUANTA.Q_RES(CHIPS)':
 C_PATH='@t6g_mb_lib.t6g(sch_1):page180_i60@pure_quanta.q_res(chips)',
 P_PATH='@t6g_mb_lib.t6g(sch_1):page205_i60@pure_quanta.q_res(chips)',
 PATH='I60',
 DRAWING='@T6G_MB_LIB.T6G(SCH_1):PAGE180',
 WATTAGE='1/8W',
 TOLERANCE='1%',
 MATERIAL='EMPTY',
 PHYS_PAGE='205',
 XY='(4325,4225)',
 ROT='0',
 VER='2',
 PACK_TYPE='0402LF',
 LOCATION='PR221',
 CDS_LIB='pure_quanta',
 CDS_PART_NAME='Q_RES_0402LF-1.5,1%,1/8W,EMPTY,CS-1504FB00',
 PART_NUMBER='CS-1504FB00',
 VALUE='1.5',
 PRIM_FILE='./archive_libs/logical/q_res/chips/chips.prt';

PART_NAME
 PR223 'Q_RES_0402LF-1.5,1%,1/8W,EMPTY,CS-1504FB00':;

SECTION_NUMBER 1
 '@T6G_MB_LIB.T6G(SCH_1):PAGE180_I36@PURE_QUANTA.Q_RES(CHIPS)':
 C_PATH='@t6g_mb_lib.t6g(sch_1):page180_i36@pure_quanta.q_res(chips)',
 P_PATH='@t6g_mb_lib.t6g(sch_1):page205_i36@pure_quanta.q_res(chips)',
 PATH='I36',
 DRAWING='@T6G_MB_LIB.T6G(SCH_1):PAGE180',
 WATTAGE='1/8W',
 TOLERANCE='1%',
 MATERIAL='EMPTY',
 PHYS_PAGE='205',
 XY='(4325,1475)',
 ROT='0',
 VER='2',
 PACK_TYPE='0402LF',
 LOCATION='PR223',
 CDS_LIB='pure_quanta',
 CDS_PART_NAME='Q_RES_0402LF-1.5,1%,1/8W,EMPTY,CS-1504FB00',
 PART_NUMBER='CS-1504FB00',
 VALUE='1.5',
 PRIM_FILE='./archive_libs/logical/q_res/chips/chips.prt';

PART_NAME
 PR226 'Q_RES_0402LF-49.9,1%,1/16W,CHIP,CS04992FB07':;

SECTION_NUMBER 1
 '@T6G_MB_LIB.T6G(SCH_1):PAGE192_I23@PURE_QUANTA.Q_RES(CHIPS)':
 C_PATH='@t6g_mb_lib.t6g(sch_1):page192_i23@pure_quanta.q_res(chips)',
 P_PATH='@t6g_mb_lib.t6g(sch_1):page217_i23@pure_quanta.q_res(chips)',
 PATH='I23',
 DRAWING='@T6G_MB_LIB.T6G(SCH_1):PAGE192',
 WATTAGE='1/16W',
 TOLERANCE='1%',
 MATERIAL='CHIP',
 PHYS_PAGE='217',
 XY='(-3400,4700)',
 ROT='0',
 VER='1',
 PACK_TYPE='0402LF',
 LOCATION='PR226',
 CDS_LIB='pure_quanta',
 CDS_PART_NAME='Q_RES_0402LF-49.9,1%,1/16W,CHIP,CS04992FB07',
 PART_NUMBER='CS04992FB07',
 VALUE='49.9',
 PRIM_FILE='./archive_libs/logical/q_res/chips/chips.prt';

PART_NAME
 PR227 'Q_RES_0402LF-49.9,1%,1/16W,CHIP,CS04992FB07':;

SECTION_NUMBER 1
 '@T6G_MB_LIB.T6G(SCH_1):PAGE192_I22@PURE_QUANTA.Q_RES(CHIPS)':
 C_PATH='@t6g_mb_lib.t6g(sch_1):page192_i22@pure_quanta.q_res(chips)',
 P_PATH='@t6g_mb_lib.t6g(sch_1):page217_i22@pure_quanta.q_res(chips)',
 PATH='I22',
 DRAWING='@T6G_MB_LIB.T6G(SCH_1):PAGE192',
 WATTAGE='1/16W',
 TOLERANCE='1%',
 MATERIAL='CHIP',
 PHYS_PAGE='217',
 XY='(-3400,4275)',
 ROT='0',
 VER='1',
 PACK_TYPE='0402LF',
 LOCATION='PR227',
 CDS_LIB='pure_quanta',
 CDS_PART_NAME='Q_RES_0402LF-49.9,1%,1/16W,CHIP,CS04992FB07',
 PART_NUMBER='CS04992FB07',
 VALUE='49.9',
 PRIM_FILE='./archive_libs/logical/q_res/chips/chips.prt';

PART_NAME
 PR228 'Q_RES_0402LF-49.9,1%,1/16W,CHIP,CS04992FB07':;

SECTION_NUMBER 1
 '@T6G_MB_LIB.T6G(SCH_1):PAGE192_I34@PURE_QUANTA.Q_RES(CHIPS)':
 C_PATH='@t6g_mb_lib.t6g(sch_1):page192_i34@pure_quanta.q_res(chips)',
 P_PATH='@t6g_mb_lib.t6g(sch_1):page217_i34@pure_quanta.q_res(chips)',
 PATH='I34',
 DRAWING='@T6G_MB_LIB.T6G(SCH_1):PAGE192',
 WATTAGE='1/16W',
 TOLERANCE='1%',
 MATERIAL='CHIP',
 PHYS_PAGE='217',
 XY='(-3350,5375)',
 ROT='0',
 VER='1',
 PACK_TYPE='0402LF',
 LOCATION='PR228',
 CDS_LIB='pure_quanta',
 CDS_PART_NAME='Q_RES_0402LF-49.9,1%,1/16W,CHIP,CS04992FB07',
 PART_NUMBER='CS04992FB07',
 VALUE='49.9',
 PRIM_FILE='./archive_libs/logical/q_res/chips/chips.prt';

PART_NAME
 PR229 'Q_RES_0402LF-49.9,1%,1/16W,CHIP,CS04992FB07':;

SECTION_NUMBER 1
 '@T6G_MB_LIB.T6G(SCH_1):PAGE199_I29@PURE_QUANTA.Q_RES(CHIPS)':
 C_PATH='@t6g_mb_lib.t6g(sch_1):page199_i29@pure_quanta.q_res(chips)',
 P_PATH='@t6g_mb_lib.t6g(sch_1):page224_i29@pure_quanta.q_res(chips)',
 PATH='I29',
 DRAWING='@T6G_MB_LIB.T6G(SCH_1):PAGE199',
 WATTAGE='1/16W',
 TOLERANCE='1%',
 MATERIAL='CHIP',
 PHYS_PAGE='224',
 XY='(-6750,4250)',
 ROT='0',
 VER='2',
 PACK_TYPE='0402LF',
 LOCATION='PR229',
 CDS_LIB='pure_quanta',
 CDS_PART_NAME='Q_RES_0402LF-49.9,1%,1/16W,CHIP,CS04992FB07',
 PART_NUMBER='CS04992FB07',
 VALUE='49.9',
 PRIM_FILE='./archive_libs/logical/q_res/chips/chips.prt';

PART_NAME
 PR230 'Q_RES_0402LF-40.2K,1%,1/16W,CHIP,CS34022FB04':;

SECTION_NUMBER 1
 '@T6G_MB_LIB.T6G(SCH_1):PAGE192_I9@PURE_QUANTA.Q_RES(CHIPS)':
 C_PATH='@t6g_mb_lib.t6g(sch_1):page192_i9@pure_quanta.q_res(chips)',
 P_PATH='@t6g_mb_lib.t6g(sch_1):page217_i9@pure_quanta.q_res(chips)',
 PATH='I9',
 DRAWING='@T6G_MB_LIB.T6G(SCH_1):PAGE192',
 WATTAGE='1/16W',
 TOLERANCE='1%',
 MATERIAL='CHIP',
 PHYS_PAGE='217',
 XY='(-3400,1875)',
 ROT='0',
 VER='1',
 PACK_TYPE='0402LF',
 LOCATION='PR230',
 CDS_LIB='pure_quanta',
 CDS_PART_NAME='Q_RES_0402LF-40.2K,1%,1/16W,CHIP,CS34022FB04',
 PART_NUMBER='CS34022FB04',
 VALUE='40.2K',
 PRIM_FILE='./archive_libs/logical/q_res/chips/chips.prt';

PART_NAME
 PR231 'Q_RES_0402LF-10K,1%,1/16W,CHIP,CS31002FB08':;

SECTION_NUMBER 1
 '@T6G_MB_LIB.T6G(SCH_1):PAGE192_I8@PURE_QUANTA.Q_RES(CHIPS)':
 C_PATH='@t6g_mb_lib.t6g(sch_1):page192_i8@pure_quanta.q_res(chips)',
 P_PATH='@t6g_mb_lib.t6g(sch_1):page217_i8@pure_quanta.q_res(chips)',
 PATH='I8',
 DRAWING='@T6G_MB_LIB.T6G(SCH_1):PAGE192',
 WATTAGE='1/16W',
 TOLERANCE='1%',
 MATERIAL='CHIP',
 PHYS_PAGE='217',
 XY='(-3050,1700)',
 ROT='0',
 VER='2',
 PACK_TYPE='0402LF',
 LOCATION='PR231',
 CDS_LIB='pure_quanta',
 CDS_PART_NAME='Q_RES_0402LF-10K,1%,1/16W,CHIP,CS31002FB08',
 PART_NUMBER='CS31002FB08',
 VALUE='10K',
 PRIM_FILE='./archive_libs/logical/q_res/chips/chips.prt';

PART_NAME
 PR232 'Q_RES_0402LF-1K,1%,1/16W,CHIP,CS21002FB06':;

SECTION_NUMBER 1
 '@T6G_MB_LIB.T6G(SCH_1):PAGE192_I17@PURE_QUANTA.Q_RES(CHIPS)':
 C_PATH='@t6g_mb_lib.t6g(sch_1):page192_i17@pure_quanta.q_res(chips)',
 P_PATH='@t6g_mb_lib.t6g(sch_1):page217_i17@pure_quanta.q_res(chips)',
 PATH='I17',
 DRAWING='@T6G_MB_LIB.T6G(SCH_1):PAGE192',
 WATTAGE='1/16W',
 TOLERANCE='1%',
 MATERIAL='CHIP',
 PHYS_PAGE='217',
 XY='(-4000,3250)',
 ROT='0',
 VER='2',
 PACK_TYPE='0402LF',
 LOCATION='PR232',
 CDS_LIB='pure_quanta',
 CDS_PART_NAME='Q_RES_0402LF-1K,1%,1/16W,CHIP,CS21002FB06',
 PART_NUMBER='CS21002FB06',
 VALUE='1K',
 PRIM_FILE='./archive_libs/logical/q_res/chips/chips.prt';

PART_NAME
 PR236 'Q_RES_0402LF-0,5%,1/16W,CHIP,CS00002JB13':;

SECTION_NUMBER 1
 '@T6G_MB_LIB.T6G(SCH_1):PAGE54_I338@PURE_QUANTA.Q_RES(CHIPS)':
 C_PATH='@t6g_mb_lib.t6g(sch_1):page54_i338@pure_quanta.q_res(chips)',
 P_PATH='@t6g_mb_lib.t6g(sch_1):page54_i338@pure_quanta.q_res(chips)',
 PATH='I338',
 DRAWING='@T6G_MB_LIB.T6G(SCH_1):PAGE54',
 WATTAGE='1/16W',
 TOLERANCE='5%',
 MATERIAL='CHIP',
 PHYS_PAGE='54',
 XY='(-6775,5575)',
 ROT='0',
 VER='1',
 PACK_TYPE='0402LF',
 LOCATION='PR236',
 CDS_LIB='pure_quanta',
 CDS_PART_NAME='Q_RES_0402LF-0,5%,1/16W,CHIP,CS00002JB13',
 PART_NUMBER='CS00002JB13',
 VALUE='0',
 PRIM_FILE='./archive_libs/logical/q_res/chips/chips.prt';

PART_NAME
 PR237 'Q_RES_0402LF-0,5%,1/16W,CHIP,CS00002JB13':;

SECTION_NUMBER 1
 '@T6G_MB_LIB.T6G(SCH_1):PAGE54_I337@PURE_QUANTA.Q_RES(CHIPS)':
 C_PATH='@t6g_mb_lib.t6g(sch_1):page54_i337@pure_quanta.q_res(chips)',
 P_PATH='@t6g_mb_lib.t6g(sch_1):page54_i337@pure_quanta.q_res(chips)',
 PATH='I337',
 DRAWING='@T6G_MB_LIB.T6G(SCH_1):PAGE54',
 WATTAGE='1/16W',
 TOLERANCE='5%',
 MATERIAL='CHIP',
 PHYS_PAGE='54',
 XY='(-6775,5525)',
 ROT='0',
 VER='1',
 PACK_TYPE='0402LF',
 LOCATION='PR237',
 CDS_LIB='pure_quanta',
 CDS_PART_NAME='Q_RES_0402LF-0,5%,1/16W,CHIP,CS00002JB13',
 PART_NUMBER='CS00002JB13',
 VALUE='0',
 PRIM_FILE='./archive_libs/logical/q_res/chips/chips.prt';

PART_NAME
 PR239 'Q_RES_0402LF-0,5%,1/16W,CHIP,CS00002JB13':;

SECTION_NUMBER 1
 '@T6G_MB_LIB.T6G(SCH_1):PAGE192_I83@PURE_QUANTA.Q_RES(CHIPS)':
 C_PATH='@t6g_mb_lib.t6g(sch_1):page192_i83@pure_quanta.q_res(chips)',
 P_PATH='@t6g_mb_lib.t6g(sch_1):page217_i83@pure_quanta.q_res(chips)',
 PATH='I83',
 DRAWING='@T6G_MB_LIB.T6G(SCH_1):PAGE192',
 WATTAGE='1/16W',
 TOLERANCE='5%',
 MATERIAL='CHIP',
 PHYS_PAGE='217',
 XY='(-2875,6325)',
 ROT='0',
 VER='1',
 PACK_TYPE='0402LF',
 LOCATION='PR239',
 CDS_LIB='pure_quanta',
 CDS_PART_NAME='Q_RES_0402LF-0,5%,1/16W,CHIP,CS00002JB13',
 PART_NUMBER='CS00002JB13',
 VALUE='0',
 PRIM_FILE='./archive_libs/logical/q_res/chips/chips.prt';

PART_NAME
 PR244 'Q_RES_0402LF-9.53K,1%,1/16W,CHIP,CS29532FB06':;

SECTION_NUMBER 1
 '@T6G_MB_LIB.T6G(SCH_1):PAGE192_I12@PURE_QUANTA.Q_RES(CHIPS)':
 C_PATH='@t6g_mb_lib.t6g(sch_1):page192_i12@pure_quanta.q_res(chips)',
 P_PATH='@t6g_mb_lib.t6g(sch_1):page217_i12@pure_quanta.q_res(chips)',
 PATH='I12',
 DRAWING='@T6G_MB_LIB.T6G(SCH_1):PAGE192',
 WATTAGE='1/16W',
 TOLERANCE='1%',
 MATERIAL='CHIP',
 PHYS_PAGE='217',
 XY='(-3300,2525)',
 ROT='0',
 VER='2',
 PACK_TYPE='0402LF',
 LOCATION='PR244',
 CDS_LIB='pure_quanta',
 CDS_PART_NAME='Q_RES_0402LF-9.53K,1%,1/16W,CHIP,CS29532FB06',
 PART_NUMBER='CS29532FB06',
 VALUE='9.53K',
 PRIM_FILE='./archive_libs/logical/q_res/chips/chips.prt';

PART_NAME
 PR245 'Q_RES_0402LF-0,5%,1/16W,CHIP,CS00002JB13':;

SECTION_NUMBER 1
 '@T6G_MB_LIB.T6G(SCH_1):PAGE192_I77@PURE_QUANTA.Q_RES(CHIPS)':
 C_PATH='@t6g_mb_lib.t6g(sch_1):page192_i77@pure_quanta.q_res(chips)',
 P_PATH='@t6g_mb_lib.t6g(sch_1):page217_i77@pure_quanta.q_res(chips)',
 PATH='I77',
 DRAWING='@T6G_MB_LIB.T6G(SCH_1):PAGE192',
 WATTAGE='1/16W',
 TOLERANCE='5%',
 MATERIAL='CHIP',
 PHYS_PAGE='217',
 XY='(-2525,5225)',
 ROT='0',
 VER='1',
 PACK_TYPE='0402LF',
 LOCATION='PR245',
 CDS_LIB='pure_quanta',
 CDS_PART_NAME='Q_RES_0402LF-0,5%,1/16W,CHIP,CS00002JB13',
 PART_NUMBER='CS00002JB13',
 VALUE='0',
 PRIM_FILE='./archive_libs/logical/q_res/chips/chips.prt';

PART_NAME
 PR246 'Q_RES_0402LF-0,5%,1/16W,CHIP,CS00002JB13':;

SECTION_NUMBER 1
 '@T6G_MB_LIB.T6G(SCH_1):PAGE192_I69@PURE_QUANTA.Q_RES(CHIPS)':
 C_PATH='@t6g_mb_lib.t6g(sch_1):page192_i69@pure_quanta.q_res(chips)',
 P_PATH='@t6g_mb_lib.t6g(sch_1):page217_i69@pure_quanta.q_res(chips)',
 PATH='I69',
 DRAWING='@T6G_MB_LIB.T6G(SCH_1):PAGE192',
 WATTAGE='1/16W',
 TOLERANCE='5%',
 MATERIAL='CHIP',
 PHYS_PAGE='217',
 XY='(-2475,4125)',
 ROT='0',
 VER='1',
 PACK_TYPE='0402LF',
 LOCATION='PR246',
 CDS_LIB='pure_quanta',
 CDS_PART_NAME='Q_RES_0402LF-0,5%,1/16W,CHIP,CS00002JB13',
 PART_NUMBER='CS00002JB13',
 VALUE='0',
 PRIM_FILE='./archive_libs/logical/q_res/chips/chips.prt';

PART_NAME
 PR251 'Q_RES_0402LF-0,5%,1/16W,CHIP,CS00002JB13':;

SECTION_NUMBER 1
 '@T6G_MB_LIB.T6G(SCH_1):PAGE192_I49@PURE_QUANTA.Q_RES(CHIPS)':
 C_PATH='@t6g_mb_lib.t6g(sch_1):page192_i49@pure_quanta.q_res(chips)',
 P_PATH='@t6g_mb_lib.t6g(sch_1):page217_i49@pure_quanta.q_res(chips)',
 PATH='I49',
 DRAWING='@T6G_MB_LIB.T6G(SCH_1):PAGE192',
 WATTAGE='1/16W',
 TOLERANCE='5%',
 MATERIAL='CHIP',
 PHYS_PAGE='217',
 XY='(-2075,1700)',
 ROT='0',
 VER='1',
 PACK_TYPE='0402LF',
 LOCATION='PR251',
 CDS_LIB='pure_quanta',
 CDS_PART_NAME='Q_RES_0402LF-0,5%,1/16W,CHIP,CS00002JB13',
 PART_NUMBER='CS00002JB13',
 VALUE='0',
 PRIM_FILE='./archive_libs/logical/q_res/chips/chips.prt';

PART_NAME
 PR253 'Q_RES_0402LF-1,1%,1/16W,CHIP,CS-1002FB04':;

SECTION_NUMBER 1
 '@T6G_MB_LIB.T6G(SCH_1):PAGE192_I124@PURE_QUANTA.Q_RES(CHIPS)':
 C_PATH='@t6g_mb_lib.t6g(sch_1):page192_i124@pure_quanta.q_res(chips)',
 P_PATH='@t6g_mb_lib.t6g(sch_1):page217_i124@pure_quanta.q_res(chips)',
 PATH='I124',
 DRAWING='@T6G_MB_LIB.T6G(SCH_1):PAGE192',
 WATTAGE='1/16W',
 TOLERANCE='1%',
 MATERIAL='CHIP',
 PHYS_PAGE='217',
 XY='(1300,7225)',
 ROT='0',
 VER='1',
 PACK_TYPE='0402LF',
 LOCATION='PR253',
 CDS_LIB='pure_quanta',
 CDS_PART_NAME='Q_RES_0402LF-1,1%,1/16W,CHIP,CS-1002FB04',
 PART_NUMBER='CS-1002FB04',
 VALUE='1',
 PRIM_FILE='./archive_libs/logical/q_res/chips/chips.prt';

PART_NAME
 PR254 'Q_RES_0402LF-8.87K,1%,1/16W,EMPTY,CS28872FB01':;

SECTION_NUMBER 1
 '@T6G_MB_LIB.T6G(SCH_1):PAGE193_I4@PURE_QUANTA.Q_RES(CHIPS)':
 C_PATH='@t6g_mb_lib.t6g(sch_1):page193_i4@pure_quanta.q_res(chips)',
 P_PATH='@t6g_mb_lib.t6g(sch_1):page218_i4@pure_quanta.q_res(chips)',
 PATH='I4',
 DRAWING='@T6G_MB_LIB.T6G(SCH_1):PAGE193',
 WATTAGE='1/16W',
 TOLERANCE='1%',
 MATERIAL='EMPTY',
 PHYS_PAGE='218',
 XY='(-8750,1475)',
 ROT='2',
 VER='2',
 PACK_TYPE='0402LF',
 LOCATION='PR254',
 CDS_LIB='pure_quanta',
 CDS_PART_NAME='Q_RES_0402LF-8.87K,1%,1/16W,EMPTY,CS28872FB01',
 PART_NUMBER='CS28872FB01',
 VALUE='8.87K',
 PRIM_FILE='./archive_libs/logical/q_res/chips/chips.prt';

PART_NAME
 PR255 'Q_RES_0402LF-8.87K,1%,1/16W,EMPTY,CS28872FB01':;

SECTION_NUMBER 1
 '@T6G_MB_LIB.T6G(SCH_1):PAGE193_I17@PURE_QUANTA.Q_RES(CHIPS)':
 C_PATH='@t6g_mb_lib.t6g(sch_1):page193_i17@pure_quanta.q_res(chips)',
 P_PATH='@t6g_mb_lib.t6g(sch_1):page218_i17@pure_quanta.q_res(chips)',
 PATH='I17',
 DRAWING='@T6G_MB_LIB.T6G(SCH_1):PAGE193',
 WATTAGE='1/16W',
 TOLERANCE='1%',
 MATERIAL='EMPTY',
 PHYS_PAGE='218',
 XY='(-8725,4100)',
 ROT='2',
 VER='2',
 PACK_TYPE='0402LF',
 LOCATION='PR255',
 CDS_LIB='pure_quanta',
 CDS_PART_NAME='Q_RES_0402LF-8.87K,1%,1/16W,EMPTY,CS28872FB01',
 PART_NUMBER='CS28872FB01',
 VALUE='8.87K',
 PRIM_FILE='./archive_libs/logical/q_res/chips/chips.prt';

PART_NAME
 PR256 'Q_RES_0402LF-2.2,1%,1/16W,CHIP,CS-2202FB01':;

SECTION_NUMBER 1
 '@T6G_MB_LIB.T6G(SCH_1):PAGE193_I27@PURE_QUANTA.Q_RES(CHIPS)':
 C_PATH='@t6g_mb_lib.t6g(sch_1):page193_i27@pure_quanta.q_res(chips)',
 P_PATH='@t6g_mb_lib.t6g(sch_1):page218_i27@pure_quanta.q_res(chips)',
 PATH='I27',
 DRAWING='@T6G_MB_LIB.T6G(SCH_1):PAGE193',
 WATTAGE='1/16W',
 TOLERANCE='1%',
 MATERIAL='CHIP',
 PHYS_PAGE='218',
 XY='(-8575,5600)',
 ROT='0',
 VER='2',
 PACK_TYPE='0402LF',
 LOCATION='PR256',
 CDS_LIB='pure_quanta',
 CDS_PART_NAME='Q_RES_0402LF-2.2,1%,1/16W,CHIP,CS-2202FB01',
 PART_NUMBER='CS-2202FB01',
 VALUE='2.2',
 PRIM_FILE='./archive_libs/logical/q_res/chips/chips.prt';

PART_NAME
 PR257 'Q_RES_0402LF-2.2,1%,1/16W,CHIP,CS-2202FB01':;

SECTION_NUMBER 1
 '@T6G_MB_LIB.T6G(SCH_1):PAGE193_I14@PURE_QUANTA.Q_RES(CHIPS)':
 C_PATH='@t6g_mb_lib.t6g(sch_1):page193_i14@pure_quanta.q_res(chips)',
 P_PATH='@t6g_mb_lib.t6g(sch_1):page218_i14@pure_quanta.q_res(chips)',
 PATH='I14',
 DRAWING='@T6G_MB_LIB.T6G(SCH_1):PAGE193',
 WATTAGE='1/16W',
 TOLERANCE='1%',
 MATERIAL='CHIP',
 PHYS_PAGE='218',
 XY='(-8475,2950)',
 ROT='0',
 VER='2',
 PACK_TYPE='0402LF',
 LOCATION='PR257',
 CDS_LIB='pure_quanta',
 CDS_PART_NAME='Q_RES_0402LF-2.2,1%,1/16W,CHIP,CS-2202FB01',
 PART_NUMBER='CS-2202FB01',
 VALUE='2.2',
 PRIM_FILE='./archive_libs/logical/q_res/chips/chips.prt';

PART_NAME
 PR258 'Q_RES_0402LF-5.6,1%,1/16W,CHIP,CS-5602FB01':;

SECTION_NUMBER 1
 '@T6G_MB_LIB.T6G(SCH_1):PAGE193_I51@PURE_QUANTA.Q_RES(CHIPS)':
 C_PATH='@t6g_mb_lib.t6g(sch_1):page193_i51@pure_quanta.q_res(chips)',
 P_PATH='@t6g_mb_lib.t6g(sch_1):page218_i51@pure_quanta.q_res(chips)',
 PATH='I51',
 DRAWING='@T6G_MB_LIB.T6G(SCH_1):PAGE193',
 WATTAGE='1/16W',
 TOLERANCE='1%',
 MATERIAL='CHIP',
 PHYS_PAGE='218',
 XY='(-5550,4950)',
 ROT='0',
 VER='1',
 PACK_TYPE='0402LF',
 LOCATION='PR258',
 CDS_LIB='pure_quanta',
 CDS_PART_NAME='Q_RES_0402LF-5.6,1%,1/16W,CHIP,CS-5602FB01',
 PART_NUMBER='CS-5602FB01',
 VALUE='5.6',
 PRIM_FILE='./archive_libs/logical/q_res/chips/chips.prt';

PART_NAME
 PR259 'Q_RES_0402LF-5.6,1%,1/16W,CHIP,CS-5602FB01':;

SECTION_NUMBER 1
 '@T6G_MB_LIB.T6G(SCH_1):PAGE193_I41@PURE_QUANTA.Q_RES(CHIPS)':
 C_PATH='@t6g_mb_lib.t6g(sch_1):page193_i41@pure_quanta.q_res(chips)',
 P_PATH='@t6g_mb_lib.t6g(sch_1):page218_i41@pure_quanta.q_res(chips)',
 PATH='I41',
 DRAWING='@T6G_MB_LIB.T6G(SCH_1):PAGE193',
 WATTAGE='1/16W',
 TOLERANCE='1%',
 MATERIAL='CHIP',
 PHYS_PAGE='218',
 XY='(-5500,2325)',
 ROT='0',
 VER='1',
 PACK_TYPE='0402LF',
 LOCATION='PR259',
 CDS_LIB='pure_quanta',
 CDS_PART_NAME='Q_RES_0402LF-5.6,1%,1/16W,CHIP,CS-5602FB01',
 PART_NUMBER='CS-5602FB01',
 VALUE='5.6',
 PRIM_FILE='./archive_libs/logical/q_res/chips/chips.prt';

PART_NAME
 PR260 'Q_RES_0402LF-0,5%,1/16W,CHIP,CS00002JB13':;

SECTION_NUMBER 1
 '@T6G_MB_LIB.T6G(SCH_1):PAGE193_I38@PURE_QUANTA.Q_RES(CHIPS)':
 C_PATH='@t6g_mb_lib.t6g(sch_1):page193_i38@pure_quanta.q_res(chips)',
 P_PATH='@t6g_mb_lib.t6g(sch_1):page218_i38@pure_quanta.q_res(chips)',
 PATH='I38',
 DRAWING='@T6G_MB_LIB.T6G(SCH_1):PAGE193',
 WATTAGE='1/16W',
 TOLERANCE='5%',
 MATERIAL='CHIP',
 PHYS_PAGE='218',
 XY='(-4500,750)',
 ROT='0',
 VER='1',
 PACK_TYPE='0402LF',
 LOCATION='PR260',
 CDS_LIB='pure_quanta',
 CDS_PART_NAME='Q_RES_0402LF-0,5%,1/16W,CHIP,CS00002JB13',
 PART_NUMBER='CS00002JB13',
 VALUE='0',
 PRIM_FILE='./archive_libs/logical/q_res/chips/chips.prt';

PART_NAME
 PR261 'Q_RES_0402LF-0,5%,1/16W,CHIP,CS00002JB13':;

SECTION_NUMBER 1
 '@T6G_MB_LIB.T6G(SCH_1):PAGE193_I64@PURE_QUANTA.Q_RES(CHIPS)':
 C_PATH='@t6g_mb_lib.t6g(sch_1):page193_i64@pure_quanta.q_res(chips)',
 P_PATH='@t6g_mb_lib.t6g(sch_1):page218_i64@pure_quanta.q_res(chips)',
 PATH='I64',
 DRAWING='@T6G_MB_LIB.T6G(SCH_1):PAGE193',
 WATTAGE='1/16W',
 TOLERANCE='5%',
 MATERIAL='CHIP',
 PHYS_PAGE='218',
 XY='(-3775,3575)',
 ROT='0',
 VER='1',
 PACK_TYPE='0402LF',
 LOCATION='PR261',
 CDS_LIB='pure_quanta',
 CDS_PART_NAME='Q_RES_0402LF-0,5%,1/16W,CHIP,CS00002JB13',
 PART_NUMBER='CS00002JB13',
 VALUE='0',
 PRIM_FILE='./archive_libs/logical/q_res/chips/chips.prt';

PART_NAME
 PR262 'Q_RES_0402LF-8.87K,1%,1/16W,EMPTY,CS28872FB01':;

SECTION_NUMBER 1
 '@T6G_MB_LIB.T6G(SCH_1):PAGE194_I4@PURE_QUANTA.Q_RES(CHIPS)':
 C_PATH='@t6g_mb_lib.t6g(sch_1):page194_i4@pure_quanta.q_res(chips)',
 P_PATH='@t6g_mb_lib.t6g(sch_1):page219_i4@pure_quanta.q_res(chips)',
 PATH='I4',
 DRAWING='@T6G_MB_LIB.T6G(SCH_1):PAGE194',
 WATTAGE='1/16W',
 TOLERANCE='1%',
 MATERIAL='EMPTY',
 PHYS_PAGE='219',
 XY='(1350,975)',
 ROT='2',
 VER='2',
 PACK_TYPE='0402LF',
 LOCATION='PR262',
 CDS_LIB='pure_quanta',
 CDS_PART_NAME='Q_RES_0402LF-8.87K,1%,1/16W,EMPTY,CS28872FB01',
 PART_NUMBER='CS28872FB01',
 VALUE='8.87K',
 PRIM_FILE='./archive_libs/logical/q_res/chips/chips.prt';

PART_NAME
 PR263 'Q_RES_0402LF-8.87K,1%,1/16W,EMPTY,CS28872FB01':;

SECTION_NUMBER 1
 '@T6G_MB_LIB.T6G(SCH_1):PAGE194_I18@PURE_QUANTA.Q_RES(CHIPS)':
 C_PATH='@t6g_mb_lib.t6g(sch_1):page194_i18@pure_quanta.q_res(chips)',
 P_PATH='@t6g_mb_lib.t6g(sch_1):page219_i18@pure_quanta.q_res(chips)',
 PATH='I18',
 DRAWING='@T6G_MB_LIB.T6G(SCH_1):PAGE194',
 WATTAGE='1/16W',
 TOLERANCE='1%',
 MATERIAL='EMPTY',
 PHYS_PAGE='219',
 XY='(1375,3800)',
 ROT='2',
 VER='2',
 PACK_TYPE='0402LF',
 LOCATION='PR263',
 CDS_LIB='pure_quanta',
 CDS_PART_NAME='Q_RES_0402LF-8.87K,1%,1/16W,EMPTY,CS28872FB01',
 PART_NUMBER='CS28872FB01',
 VALUE='8.87K',
 PRIM_FILE='./archive_libs/logical/q_res/chips/chips.prt';

PART_NAME
 PR264 'Q_RES_0402LF-2.2,1%,1/16W,CHIP,CS-2202FB01':;

SECTION_NUMBER 1
 '@T6G_MB_LIB.T6G(SCH_1):PAGE194_I13@PURE_QUANTA.Q_RES(CHIPS)':
 C_PATH='@t6g_mb_lib.t6g(sch_1):page194_i13@pure_quanta.q_res(chips)',
 P_PATH='@t6g_mb_lib.t6g(sch_1):page219_i13@pure_quanta.q_res(chips)',
 PATH='I13',
 DRAWING='@T6G_MB_LIB.T6G(SCH_1):PAGE194',
 WATTAGE='1/16W',
 TOLERANCE='1%',
 MATERIAL='CHIP',
 PHYS_PAGE='219',
 XY='(1500,2475)',
 ROT='0',
 VER='2',
 PACK_TYPE='0402LF',
 LOCATION='PR264',
 CDS_LIB='pure_quanta',
 CDS_PART_NAME='Q_RES_0402LF-2.2,1%,1/16W,CHIP,CS-2202FB01',
 PART_NUMBER='CS-2202FB01',
 VALUE='2.2',
 PRIM_FILE='./archive_libs/logical/q_res/chips/chips.prt';

PART_NAME
 PR265 'Q_RES_0402LF-2.2,1%,1/16W,CHIP,CS-2202FB01':;

SECTION_NUMBER 1
 '@T6G_MB_LIB.T6G(SCH_1):PAGE194_I29@PURE_QUANTA.Q_RES(CHIPS)':
 C_PATH='@t6g_mb_lib.t6g(sch_1):page194_i29@pure_quanta.q_res(chips)',
 P_PATH='@t6g_mb_lib.t6g(sch_1):page219_i29@pure_quanta.q_res(chips)',
 PATH='I29',
 DRAWING='@T6G_MB_LIB.T6G(SCH_1):PAGE194',
 WATTAGE='1/16W',
 TOLERANCE='1%',
 MATERIAL='CHIP',
 PHYS_PAGE='219',
 XY='(1675,5300)',
 ROT='0',
 VER='2',
 PACK_TYPE='0402LF',
 LOCATION='PR265',
 CDS_LIB='pure_quanta',
 CDS_PART_NAME='Q_RES_0402LF-2.2,1%,1/16W,CHIP,CS-2202FB01',
 PART_NUMBER='CS-2202FB01',
 VALUE='2.2',
 PRIM_FILE='./archive_libs/logical/q_res/chips/chips.prt';

PART_NAME
 PR266 'Q_RES_0402LF-5.6,1%,1/16W,CHIP,CS-5602FB01':;

SECTION_NUMBER 1
 '@T6G_MB_LIB.T6G(SCH_1):PAGE194_I36@PURE_QUANTA.Q_RES(CHIPS)':
 C_PATH='@t6g_mb_lib.t6g(sch_1):page194_i36@pure_quanta.q_res(chips)',
 P_PATH='@t6g_mb_lib.t6g(sch_1):page219_i36@pure_quanta.q_res(chips)',
 PATH='I36',
 DRAWING='@T6G_MB_LIB.T6G(SCH_1):PAGE194',
 WATTAGE='1/16W',
 TOLERANCE='1%',
 MATERIAL='CHIP',
 PHYS_PAGE='219',
 XY='(4600,1825)',
 ROT='0',
 VER='1',
 PACK_TYPE='0402LF',
 LOCATION='PR266',
 CDS_LIB='pure_quanta',
 CDS_PART_NAME='Q_RES_0402LF-5.6,1%,1/16W,CHIP,CS-5602FB01',
 PART_NUMBER='CS-5602FB01',
 VALUE='5.6',
 PRIM_FILE='./archive_libs/logical/q_res/chips/chips.prt';

PART_NAME
 PR267 'Q_RES_0402LF-5.6,1%,1/16W,CHIP,CS-5602FB01':;

SECTION_NUMBER 1
 '@T6G_MB_LIB.T6G(SCH_1):PAGE194_I52@PURE_QUANTA.Q_RES(CHIPS)':
 C_PATH='@t6g_mb_lib.t6g(sch_1):page194_i52@pure_quanta.q_res(chips)',
 P_PATH='@t6g_mb_lib.t6g(sch_1):page219_i52@pure_quanta.q_res(chips)',
 PATH='I52',
 DRAWING='@T6G_MB_LIB.T6G(SCH_1):PAGE194',
 WATTAGE='1/16W',
 TOLERANCE='1%',
 MATERIAL='CHIP',
 PHYS_PAGE='219',
 XY='(4675,4650)',
 ROT='0',
 VER='1',
 PACK_TYPE='0402LF',
 LOCATION='PR267',
 CDS_LIB='pure_quanta',
 CDS_PART_NAME='Q_RES_0402LF-5.6,1%,1/16W,CHIP,CS-5602FB01',
 PART_NUMBER='CS-5602FB01',
 VALUE='5.6',
 PRIM_FILE='./archive_libs/logical/q_res/chips/chips.prt';

PART_NAME
 PR268 'Q_RES_0402LF-0,5%,1/16W,CHIP,CS00002JB13':;

SECTION_NUMBER 1
 '@T6G_MB_LIB.T6G(SCH_1):PAGE194_I38@PURE_QUANTA.Q_RES(CHIPS)':
 C_PATH='@t6g_mb_lib.t6g(sch_1):page194_i38@pure_quanta.q_res(chips)',
 P_PATH='@t6g_mb_lib.t6g(sch_1):page219_i38@pure_quanta.q_res(chips)',
 PATH='I38',
 DRAWING='@T6G_MB_LIB.T6G(SCH_1):PAGE194',
 WATTAGE='1/16W',
 TOLERANCE='5%',
 MATERIAL='CHIP',
 PHYS_PAGE='219',
 XY='(5975,475)',
 ROT='0',
 VER='1',
 PACK_TYPE='0402LF',
 LOCATION='PR268',
 CDS_LIB='pure_quanta',
 CDS_PART_NAME='Q_RES_0402LF-0,5%,1/16W,CHIP,CS00002JB13',
 PART_NUMBER='CS00002JB13',
 VALUE='0',
 PRIM_FILE='./archive_libs/logical/q_res/chips/chips.prt';

PART_NAME
 PR269 'Q_RES_0402LF-0,5%,1/16W,CHIP,CS00002JB13':;

SECTION_NUMBER 1
 '@T6G_MB_LIB.T6G(SCH_1):PAGE194_I49@PURE_QUANTA.Q_RES(CHIPS)':
 C_PATH='@t6g_mb_lib.t6g(sch_1):page194_i49@pure_quanta.q_res(chips)',
 P_PATH='@t6g_mb_lib.t6g(sch_1):page219_i49@pure_quanta.q_res(chips)',
 PATH='I49',
 DRAWING='@T6G_MB_LIB.T6G(SCH_1):PAGE194',
 WATTAGE='1/16W',
 TOLERANCE='5%',
 MATERIAL='CHIP',
 PHYS_PAGE='219',
 XY='(5900,3125)',
 ROT='0',
 VER='1',
 PACK_TYPE='0402LF',
 LOCATION='PR269',
 CDS_LIB='pure_quanta',
 CDS_PART_NAME='Q_RES_0402LF-0,5%,1/16W,CHIP,CS00002JB13',
 PART_NUMBER='CS00002JB13',
 VALUE='0',
 PRIM_FILE='./archive_libs/logical/q_res/chips/chips.prt';

PART_NAME
 PR270 'Q_RES_0402LF-8.87K,1%,1/16W,EMPTY,CS28872FB01':;

SECTION_NUMBER 1
 '@T6G_MB_LIB.T6G(SCH_1):PAGE195_I15@PURE_QUANTA.Q_RES(CHIPS)':
 C_PATH='@t6g_mb_lib.t6g(sch_1):page195_i15@pure_quanta.q_res(chips)',
 P_PATH='@t6g_mb_lib.t6g(sch_1):page220_i15@pure_quanta.q_res(chips)',
 PATH='I15',
 DRAWING='@T6G_MB_LIB.T6G(SCH_1):PAGE195',
 WATTAGE='1/16W',
 TOLERANCE='1%',
 MATERIAL='EMPTY',
 PHYS_PAGE='220',
 XY='(1225,4350)',
 ROT='2',
 VER='2',
 PACK_TYPE='0402LF',
 LOCATION='PR270',
 CDS_LIB='pure_quanta',
 CDS_PART_NAME='Q_RES_0402LF-8.87K,1%,1/16W,EMPTY,CS28872FB01',
 PART_NUMBER='CS28872FB01',
 VALUE='8.87K',
 PRIM_FILE='./archive_libs/logical/q_res/chips/chips.prt';

PART_NAME
 PR271 'Q_RES_0402LF-2.2,1%,1/16W,CHIP,CS-2202FB01':;

SECTION_NUMBER 1
 '@T6G_MB_LIB.T6G(SCH_1):PAGE195_I28@PURE_QUANTA.Q_RES(CHIPS)':
 C_PATH='@t6g_mb_lib.t6g(sch_1):page195_i28@pure_quanta.q_res(chips)',
 P_PATH='@t6g_mb_lib.t6g(sch_1):page220_i28@pure_quanta.q_res(chips)',
 PATH='I28',
 DRAWING='@T6G_MB_LIB.T6G(SCH_1):PAGE195',
 WATTAGE='1/16W',
 TOLERANCE='1%',
 MATERIAL='CHIP',
 PHYS_PAGE='220',
 XY='(1675,5825)',
 ROT='0',
 VER='2',
 PACK_TYPE='0402LF',
 LOCATION='PR271',
 CDS_LIB='pure_quanta',
 CDS_PART_NAME='Q_RES_0402LF-2.2,1%,1/16W,CHIP,CS-2202FB01',
 PART_NUMBER='CS-2202FB01',
 VALUE='2.2',
 PRIM_FILE='./archive_libs/logical/q_res/chips/chips.prt';

PART_NAME
 PR272 'Q_RES_0402LF-5.6,1%,1/16W,CHIP,CS-5602FB01':;

SECTION_NUMBER 1
 '@T6G_MB_LIB.T6G(SCH_1):PAGE195_I52@PURE_QUANTA.Q_RES(CHIPS)':
 C_PATH='@t6g_mb_lib.t6g(sch_1):page195_i52@pure_quanta.q_res(chips)',
 P_PATH='@t6g_mb_lib.t6g(sch_1):page220_i52@pure_quanta.q_res(chips)',
 PATH='I52',
 DRAWING='@T6G_MB_LIB.T6G(SCH_1):PAGE195',
 WATTAGE='1/16W',
 TOLERANCE='1%',
 MATERIAL='CHIP',
 PHYS_PAGE='220',
 XY='(4500,5200)',
 ROT='0',
 VER='1',
 PACK_TYPE='0402LF',
 LOCATION='PR272',
 CDS_LIB='pure_quanta',
 CDS_PART_NAME='Q_RES_0402LF-5.6,1%,1/16W,CHIP,CS-5602FB01',
 PART_NUMBER='CS-5602FB01',
 VALUE='5.6',
 PRIM_FILE='./archive_libs/logical/q_res/chips/chips.prt';

PART_NAME
 PR273 'Q_RES_0402LF-0,5%,1/16W,CHIP,CS00002JB13':;

SECTION_NUMBER 1
 '@T6G_MB_LIB.T6G(SCH_1):PAGE195_I49@PURE_QUANTA.Q_RES(CHIPS)':
 C_PATH='@t6g_mb_lib.t6g(sch_1):page195_i49@pure_quanta.q_res(chips)',
 P_PATH='@t6g_mb_lib.t6g(sch_1):page220_i49@pure_quanta.q_res(chips)',
 PATH='I49',
 DRAWING='@T6G_MB_LIB.T6G(SCH_1):PAGE195',
 WATTAGE='1/16W',
 TOLERANCE='5%',
 MATERIAL='CHIP',
 PHYS_PAGE='220',
 XY='(5575,3800)',
 ROT='0',
 VER='1',
 PACK_TYPE='0402LF',
 LOCATION='PR273',
 CDS_LIB='pure_quanta',
 CDS_PART_NAME='Q_RES_0402LF-0,5%,1/16W,CHIP,CS00002JB13',
 PART_NUMBER='CS00002JB13',
 VALUE='0',
 PRIM_FILE='./archive_libs/logical/q_res/chips/chips.prt';

PART_NAME
 PR274 'Q_RES_0402LF-8.87K,1%,1/16W,EMPTY,CS28872FB01':;

SECTION_NUMBER 1
 '@T6G_MB_LIB.T6G(SCH_1):PAGE197_I6@PURE_QUANTA.Q_RES(CHIPS)':
 C_PATH='@t6g_mb_lib.t6g(sch_1):page197_i6@pure_quanta.q_res(chips)',
 P_PATH='@t6g_mb_lib.t6g(sch_1):page222_i6@pure_quanta.q_res(chips)',
 PATH='I6',
 DRAWING='@T6G_MB_LIB.T6G(SCH_1):PAGE197',
 WATTAGE='1/16W',
 TOLERANCE='1%',
 MATERIAL='EMPTY',
 PHYS_PAGE='222',
 XY='(625,1750)',
 ROT='2',
 VER='2',
 PACK_TYPE='0402LF',
 LOCATION='PR274',
 CDS_LIB='pure_quanta',
 CDS_PART_NAME='Q_RES_0402LF-8.87K,1%,1/16W,EMPTY,CS28872FB01',
 PART_NUMBER='CS28872FB01',
 VALUE='8.87K',
 PRIM_FILE='./archive_libs/logical/q_res/chips/chips.prt';

PART_NAME
 PR275 'Q_RES_0402LF-8.87K,1%,1/16W,EMPTY,CS28872FB01':;

SECTION_NUMBER 1
 '@T6G_MB_LIB.T6G(SCH_1):PAGE197_I28@PURE_QUANTA.Q_RES(CHIPS)':
 C_PATH='@t6g_mb_lib.t6g(sch_1):page197_i28@pure_quanta.q_res(chips)',
 P_PATH='@t6g_mb_lib.t6g(sch_1):page222_i28@pure_quanta.q_res(chips)',
 PATH='I28',
 DRAWING='@T6G_MB_LIB.T6G(SCH_1):PAGE197',
 WATTAGE='1/16W',
 TOLERANCE='1%',
 MATERIAL='EMPTY',
 PHYS_PAGE='222',
 XY='(650,4550)',
 ROT='2',
 VER='2',
 PACK_TYPE='0402LF',
 LOCATION='PR275',
 CDS_LIB='pure_quanta',
 CDS_PART_NAME='Q_RES_0402LF-8.87K,1%,1/16W,EMPTY,CS28872FB01',
 PART_NUMBER='CS28872FB01',
 VALUE='8.87K',
 PRIM_FILE='./archive_libs/logical/q_res/chips/chips.prt';

PART_NAME
 PR276 'Q_RES_0402LF-2.2,1%,1/16W,CHIP,CS-2202FB01':;

SECTION_NUMBER 1
 '@T6G_MB_LIB.T6G(SCH_1):PAGE197_I13@PURE_QUANTA.Q_RES(CHIPS)':
 C_PATH='@t6g_mb_lib.t6g(sch_1):page197_i13@pure_quanta.q_res(chips)',
 P_PATH='@t6g_mb_lib.t6g(sch_1):page222_i13@pure_quanta.q_res(chips)',
 PATH='I13',
 DRAWING='@T6G_MB_LIB.T6G(SCH_1):PAGE197',
 WATTAGE='1/16W',
 TOLERANCE='1%',
 MATERIAL='CHIP',
 PHYS_PAGE='222',
 XY='(975,3200)',
 ROT='0',
 VER='2',
 PACK_TYPE='0402LF',
 LOCATION='PR276',
 CDS_LIB='pure_quanta',
 CDS_PART_NAME='Q_RES_0402LF-2.2,1%,1/16W,CHIP,CS-2202FB01',
 PART_NUMBER='CS-2202FB01',
 VALUE='2.2',
 PRIM_FILE='./archive_libs/logical/q_res/chips/chips.prt';

PART_NAME
 PR277 'Q_RES_0402LF-2.2,1%,1/16W,CHIP,CS-2202FB01':;

SECTION_NUMBER 1
 '@T6G_MB_LIB.T6G(SCH_1):PAGE197_I35@PURE_QUANTA.Q_RES(CHIPS)':
 C_PATH='@t6g_mb_lib.t6g(sch_1):page197_i35@pure_quanta.q_res(chips)',
 P_PATH='@t6g_mb_lib.t6g(sch_1):page222_i35@pure_quanta.q_res(chips)',
 PATH='I35',
 DRAWING='@T6G_MB_LIB.T6G(SCH_1):PAGE197',
 WATTAGE='1/16W',
 TOLERANCE='1%',
 MATERIAL='CHIP',
 PHYS_PAGE='222',
 XY='(1075,5825)',
 ROT='0',
 VER='2',
 PACK_TYPE='0402LF',
 LOCATION='PR277',
 CDS_LIB='pure_quanta',
 CDS_PART_NAME='Q_RES_0402LF-2.2,1%,1/16W,CHIP,CS-2202FB01',
 PART_NUMBER='CS-2202FB01',
 VALUE='2.2',
 PRIM_FILE='./archive_libs/logical/q_res/chips/chips.prt';

PART_NAME
 PR278 'Q_RES_0402LF-5.6,1%,1/16W,CHIP,CS-5602FB01':;

SECTION_NUMBER 1
 '@T6G_MB_LIB.T6G(SCH_1):PAGE197_I22@PURE_QUANTA.Q_RES(CHIPS)':
 C_PATH='@t6g_mb_lib.t6g(sch_1):page197_i22@pure_quanta.q_res(chips)',
 P_PATH='@t6g_mb_lib.t6g(sch_1):page222_i22@pure_quanta.q_res(chips)',
 PATH='I22',
 DRAWING='@T6G_MB_LIB.T6G(SCH_1):PAGE197',
 WATTAGE='1/16W',
 TOLERANCE='1%',
 MATERIAL='CHIP',
 PHYS_PAGE='222',
 XY='(3925,2600)',
 ROT='0',
 VER='1',
 PACK_TYPE='0402LF',
 LOCATION='PR278',
 CDS_LIB='pure_quanta',
 CDS_PART_NAME='Q_RES_0402LF-5.6,1%,1/16W,CHIP,CS-5602FB01',
 PART_NUMBER='CS-5602FB01',
 VALUE='5.6',
 PRIM_FILE='./archive_libs/logical/q_res/chips/chips.prt';

PART_NAME
 PR279 'Q_RES_0402LF-5.6,1%,1/16W,CHIP,CS-5602FB01':;

SECTION_NUMBER 1
 '@T6G_MB_LIB.T6G(SCH_1):PAGE197_I43@PURE_QUANTA.Q_RES(CHIPS)':
 C_PATH='@t6g_mb_lib.t6g(sch_1):page197_i43@pure_quanta.q_res(chips)',
 P_PATH='@t6g_mb_lib.t6g(sch_1):page222_i43@pure_quanta.q_res(chips)',
 PATH='I43',
 DRAWING='@T6G_MB_LIB.T6G(SCH_1):PAGE197',
 WATTAGE='1/16W',
 TOLERANCE='1%',
 MATERIAL='CHIP',
 PHYS_PAGE='222',
 XY='(3975,5350)',
 ROT='0',
 VER='1',
 PACK_TYPE='0402LF',
 LOCATION='PR279',
 CDS_LIB='pure_quanta',
 CDS_PART_NAME='Q_RES_0402LF-5.6,1%,1/16W,CHIP,CS-5602FB01',
 PART_NUMBER='CS-5602FB01',
 VALUE='5.6',
 PRIM_FILE='./archive_libs/logical/q_res/chips/chips.prt';

PART_NAME
 PR280 'Q_RES_0402LF-0,5%,1/16W,CHIP,CS00002JB13':;

SECTION_NUMBER 1
 '@T6G_MB_LIB.T6G(SCH_1):PAGE197_I50@PURE_QUANTA.Q_RES(CHIPS)':
 C_PATH='@t6g_mb_lib.t6g(sch_1):page197_i50@pure_quanta.q_res(chips)',
 P_PATH='@t6g_mb_lib.t6g(sch_1):page222_i50@pure_quanta.q_res(chips)',
 PATH='I50',
 DRAWING='@T6G_MB_LIB.T6G(SCH_1):PAGE197',
 WATTAGE='1/16W',
 TOLERANCE='5%',
 MATERIAL='CHIP',
 PHYS_PAGE='222',
 XY='(5175,4000)',
 ROT='0',
 VER='1',
 PACK_TYPE='0402LF',
 LOCATION='PR280',
 CDS_LIB='pure_quanta',
 CDS_PART_NAME='Q_RES_0402LF-0,5%,1/16W,CHIP,CS00002JB13',
 PART_NUMBER='CS00002JB13',
 VALUE='0',
 PRIM_FILE='./archive_libs/logical/q_res/chips/chips.prt';

PART_NAME
 PR281 'Q_RES_0402LF-0,5%,1/16W,CHIP,CS00002JB13':;

SECTION_NUMBER 1
 '@T6G_MB_LIB.T6G(SCH_1):PAGE197_I45@PURE_QUANTA.Q_RES(CHIPS)':
 C_PATH='@t6g_mb_lib.t6g(sch_1):page197_i45@pure_quanta.q_res(chips)',
 P_PATH='@t6g_mb_lib.t6g(sch_1):page222_i45@pure_quanta.q_res(chips)',
 PATH='I45',
 DRAWING='@T6G_MB_LIB.T6G(SCH_1):PAGE197',
 WATTAGE='1/16W',
 TOLERANCE='5%',
 MATERIAL='CHIP',
 PHYS_PAGE='222',
 XY='(5000,1225)',
 ROT='0',
 VER='1',
 PACK_TYPE='0402LF',
 LOCATION='PR281',
 CDS_LIB='pure_quanta',
 CDS_PART_NAME='Q_RES_0402LF-0,5%,1/16W,CHIP,CS00002JB13',
 PART_NUMBER='CS00002JB13',
 VALUE='0',
 PRIM_FILE='./archive_libs/logical/q_res/chips/chips.prt';

PART_NAME
 PR283 'Q_RES_0402LF-0,5%,1/16W,CHIP,CS00002JB13':;

SECTION_NUMBER 1
 '@T6G_MB_LIB.T6G(SCH_1):PAGE168_I4@PURE_QUANTA.Q_RES(CHIPS)':
 C_PATH='@t6g_mb_lib.t6g(sch_1):page168_i4@pure_quanta.q_res(chips)',
 P_PATH='@t6g_mb_lib.t6g(sch_1):page193_i4@pure_quanta.q_res(chips)',
 PATH='I4',
 DRAWING='@T6G_MB_LIB.T6G(SCH_1):PAGE168',
 WATTAGE='1/16W',
 TOLERANCE='5%',
 MATERIAL='CHIP',
 PHYS_PAGE='193',
 XY='(-8100,5425)',
 ROT='0',
 VER='2',
 PACK_TYPE='0402LF',
 LOCATION='PR283',
 CDS_LIB='pure_quanta',
 CDS_PART_NAME='Q_RES_0402LF-0,5%,1/16W,CHIP,CS00002JB13',
 PART_NUMBER='CS00002JB13',
 VALUE='0',
 PRIM_FILE='./archive_libs/logical/q_res/chips/chips.prt';

PART_NAME
 PR284 'Q_RES_0402LF-1K,1%,1/16W,EMPTY,CS21002FB06':;

SECTION_NUMBER 1
 '@T6G_MB_LIB.T6G(SCH_1):PAGE168_I10@PURE_QUANTA.Q_RES(CHIPS)':
 C_PATH='@t6g_mb_lib.t6g(sch_1):page168_i10@pure_quanta.q_res(chips)',
 P_PATH='@t6g_mb_lib.t6g(sch_1):page193_i10@pure_quanta.q_res(chips)',
 PATH='I10',
 DRAWING='@T6G_MB_LIB.T6G(SCH_1):PAGE168',
 WATTAGE='1/16W',
 TOLERANCE='1%',
 MATERIAL='EMPTY',
 PHYS_PAGE='193',
 XY='(-7900,6375)',
 ROT='0',
 VER='2',
 PACK_TYPE='0402LF',
 LOCATION='PR284',
 CDS_LIB='pure_quanta',
 CDS_PART_NAME='Q_RES_0402LF-1K,1%,1/16W,EMPTY,CS21002FB06',
 PART_NUMBER='CS21002FB06',
 VALUE='1K',
 PRIM_FILE='./archive_libs/logical/q_res/chips/chips.prt';

PART_NAME
 PR285 'Q_RES_0402LF-1K,1%,1/16W,CHIP,CS21002FB06':;

SECTION_NUMBER 1
 '@T6G_MB_LIB.T6G(SCH_1):PAGE168_I18@PURE_QUANTA.Q_RES(CHIPS)':
 C_PATH='@t6g_mb_lib.t6g(sch_1):page168_i18@pure_quanta.q_res(chips)',
 P_PATH='@t6g_mb_lib.t6g(sch_1):page193_i18@pure_quanta.q_res(chips)',
 PATH='I18',
 DRAWING='@T6G_MB_LIB.T6G(SCH_1):PAGE168',
 WATTAGE='1/16W',
 TOLERANCE='1%',
 MATERIAL='CHIP',
 PHYS_PAGE='193',
 XY='(-7350,2425)',
 ROT='0',
 VER='2',
 PACK_TYPE='0402LF',
 LOCATION='PR285',
 CDS_LIB='pure_quanta',
 CDS_PART_NAME='Q_RES_0402LF-1K,1%,1/16W,CHIP,CS21002FB06',
 PART_NUMBER='CS21002FB06',
 VALUE='1K',
 PRIM_FILE='./archive_libs/logical/q_res/chips/chips.prt';

PART_NAME
 PR288 'Q_RES_0402LF-49.9,1%,1/16W,CHIP,CS04992FB07':;

SECTION_NUMBER 1
 '@T6G_MB_LIB.T6G(SCH_1):PAGE199_I15@PURE_QUANTA.Q_RES(CHIPS)':
 C_PATH='@t6g_mb_lib.t6g(sch_1):page199_i15@pure_quanta.q_res(chips)',
 P_PATH='@t6g_mb_lib.t6g(sch_1):page224_i15@pure_quanta.q_res(chips)',
 PATH='I15',
 DRAWING='@T6G_MB_LIB.T6G(SCH_1):PAGE199',
 WATTAGE='1/16W',
 TOLERANCE='1%',
 MATERIAL='CHIP',
 PHYS_PAGE='224',
 XY='(-6750,3675)',
 ROT='0',
 VER='2',
 PACK_TYPE='0402LF',
 LOCATION='PR288',
 CDS_LIB='pure_quanta',
 CDS_PART_NAME='Q_RES_0402LF-49.9,1%,1/16W,CHIP,CS04992FB07',
 PART_NUMBER='CS04992FB07',
 VALUE='49.9',
 PRIM_FILE='./archive_libs/logical/q_res/chips/chips.prt';

PART_NAME
 PR290 'Q_RES_0402LF-40.2K,1%,1/16W,CHIP,CS34022FB04':;

SECTION_NUMBER 1
 '@T6G_MB_LIB.T6G(SCH_1):PAGE168_I15@PURE_QUANTA.Q_RES(CHIPS)':
 C_PATH='@t6g_mb_lib.t6g(sch_1):page168_i15@pure_quanta.q_res(chips)',
 P_PATH='@t6g_mb_lib.t6g(sch_1):page193_i15@pure_quanta.q_res(chips)',
 PATH='I15',
 DRAWING='@T6G_MB_LIB.T6G(SCH_1):PAGE168',
 WATTAGE='1/16W',
 TOLERANCE='1%',
 MATERIAL='CHIP',
 PHYS_PAGE='193',
 XY='(-6825,1225)',
 ROT='0',
 VER='1',
 PACK_TYPE='0402LF',
 LOCATION='PR290',
 CDS_LIB='pure_quanta',
 CDS_PART_NAME='Q_RES_0402LF-40.2K,1%,1/16W,CHIP,CS34022FB04',
 PART_NUMBER='CS34022FB04',
 VALUE='40.2K',
 PRIM_FILE='./archive_libs/logical/q_res/chips/chips.prt';

PART_NAME
 PR291 'Q_RES_0402LF-1.5,1%,1/8W,EMPTY,CS-1504FB00':;

SECTION_NUMBER 1
 '@T6G_MB_LIB.T6G(SCH_1):PAGE181_I38@PURE_QUANTA.Q_RES(CHIPS)':
 C_PATH='@t6g_mb_lib.t6g(sch_1):page181_i38@pure_quanta.q_res(chips)',
 P_PATH='@t6g_mb_lib.t6g(sch_1):page206_i38@pure_quanta.q_res(chips)',
 PATH='I38',
 DRAWING='@T6G_MB_LIB.T6G(SCH_1):PAGE181',
 WATTAGE='1/8W',
 TOLERANCE='1%',
 MATERIAL='EMPTY',
 PHYS_PAGE='206',
 XY='(-7950,1900)',
 ROT='0',
 VER='2',
 PACK_TYPE='0402LF',
 LOCATION='PR291',
 CDS_LIB='pure_quanta',
 CDS_PART_NAME='Q_RES_0402LF-1.5,1%,1/8W,EMPTY,CS-1504FB00',
 PART_NUMBER='CS-1504FB00',
 VALUE='1.5',
 PRIM_FILE='./archive_libs/logical/q_res/chips/chips.prt';

PART_NAME
 PR292 'Q_RES_0402LF-681,1%,1/16W,CHIP,CS16812FB02':;

SECTION_NUMBER 1
 '@T6G_MB_LIB.T6G(SCH_1):PAGE168_I27@PURE_QUANTA.Q_RES(CHIPS)':
 C_PATH='@t6g_mb_lib.t6g(sch_1):page168_i27@pure_quanta.q_res(chips)',
 P_PATH='@t6g_mb_lib.t6g(sch_1):page193_i27@pure_quanta.q_res(chips)',
 PATH='I27',
 DRAWING='@T6G_MB_LIB.T6G(SCH_1):PAGE168',
 WATTAGE='1/16W',
 TOLERANCE='1%',
 MATERIAL='CHIP',
 PHYS_PAGE='193',
 XY='(-6675,1775)',
 ROT='0',
 VER='2',
 PACK_TYPE='0402LF',
 LOCATION='PR292',
 CDS_LIB='pure_quanta',
 CDS_PART_NAME='Q_RES_0402LF-681,1%,1/16W,CHIP,CS16812FB02',
 PART_NUMBER='CS16812FB02',
 VALUE='681',
 PRIM_FILE='./archive_libs/logical/q_res/chips/chips.prt';

PART_NAME
 PR294 'Q_RES_0402LF-49.9,1%,1/16W,CHIP,CS04992FB07':;

SECTION_NUMBER 1
 '@T6G_MB_LIB.T6G(SCH_1):PAGE168_I72@PURE_QUANTA.Q_RES(CHIPS)':
 C_PATH='@t6g_mb_lib.t6g(sch_1):page168_i72@pure_quanta.q_res(chips)',
 P_PATH='@t6g_mb_lib.t6g(sch_1):page193_i72@pure_quanta.q_res(chips)',
 PATH='I72',
 DRAWING='@T6G_MB_LIB.T6G(SCH_1):PAGE168',
 WATTAGE='1/16W',
 TOLERANCE='1%',
 MATERIAL='CHIP',
 PHYS_PAGE='193',
 XY='(-6625,4650)',
 ROT='0',
 VER='2',
 PACK_TYPE='0402LF',
 LOCATION='PR294',
 CDS_LIB='pure_quanta',
 CDS_PART_NAME='Q_RES_0402LF-49.9,1%,1/16W,CHIP,CS04992FB07',
 PART_NUMBER='CS04992FB07',
 VALUE='49.9',
 PRIM_FILE='./archive_libs/logical/q_res/chips/chips.prt';

PART_NAME
 PR295 'Q_RES_0402LF-49.9,1%,1/16W,CHIP,CS04992FB07':;

SECTION_NUMBER 1
 '@T6G_MB_LIB.T6G(SCH_1):PAGE168_I44@PURE_QUANTA.Q_RES(CHIPS)':
 C_PATH='@t6g_mb_lib.t6g(sch_1):page168_i44@pure_quanta.q_res(chips)',
 P_PATH='@t6g_mb_lib.t6g(sch_1):page193_i44@pure_quanta.q_res(chips)',
 PATH='I44',
 DRAWING='@T6G_MB_LIB.T6G(SCH_1):PAGE168',
 WATTAGE='1/16W',
 TOLERANCE='1%',
 MATERIAL='CHIP',
 PHYS_PAGE='193',
 XY='(-6625,4025)',
 ROT='0',
 VER='2',
 PACK_TYPE='0402LF',
 LOCATION='PR295',
 CDS_LIB='pure_quanta',
 CDS_PART_NAME='Q_RES_0402LF-49.9,1%,1/16W,CHIP,CS04992FB07',
 PART_NUMBER='CS04992FB07',
 VALUE='49.9',
 PRIM_FILE='./archive_libs/logical/q_res/chips/chips.prt';

PART_NAME
 PR296 'Q_RES_0402LF-49.9,1%,1/16W,CHIP,CS04992FB07':;

SECTION_NUMBER 1
 '@T6G_MB_LIB.T6G(SCH_1):PAGE168_I40@PURE_QUANTA.Q_RES(CHIPS)':
 C_PATH='@t6g_mb_lib.t6g(sch_1):page168_i40@pure_quanta.q_res(chips)',
 P_PATH='@t6g_mb_lib.t6g(sch_1):page193_i40@pure_quanta.q_res(chips)',
 PATH='I40',
 DRAWING='@T6G_MB_LIB.T6G(SCH_1):PAGE168',
 WATTAGE='1/16W',
 TOLERANCE='1%',
 MATERIAL='CHIP',
 PHYS_PAGE='193',
 XY='(-6625,3525)',
 ROT='0',
 VER='2',
 PACK_TYPE='0402LF',
 LOCATION='PR296',
 CDS_LIB='pure_quanta',
 CDS_PART_NAME='Q_RES_0402LF-49.9,1%,1/16W,CHIP,CS04992FB07',
 PART_NUMBER='CS04992FB07',
 VALUE='49.9',
 PRIM_FILE='./archive_libs/logical/q_res/chips/chips.prt';

PART_NAME
 PR297 'Q_RES_0402LF-49.9,1%,1/16W,CHIP,CS04992FB07':;

SECTION_NUMBER 1
 '@T6G_MB_LIB.T6G(SCH_1):PAGE168_I36@PURE_QUANTA.Q_RES(CHIPS)':
 C_PATH='@t6g_mb_lib.t6g(sch_1):page168_i36@pure_quanta.q_res(chips)',
 P_PATH='@t6g_mb_lib.t6g(sch_1):page193_i36@pure_quanta.q_res(chips)',
 PATH='I36',
 DRAWING='@T6G_MB_LIB.T6G(SCH_1):PAGE168',
 WATTAGE='1/16W',
 TOLERANCE='1%',
 MATERIAL='CHIP',
 PHYS_PAGE='193',
 XY='(-6625,2925)',
 ROT='0',
 VER='2',
 PACK_TYPE='0402LF',
 LOCATION='PR297',
 CDS_LIB='pure_quanta',
 CDS_PART_NAME='Q_RES_0402LF-49.9,1%,1/16W,CHIP,CS04992FB07',
 PART_NUMBER='CS04992FB07',
 VALUE='49.9',
 PRIM_FILE='./archive_libs/logical/q_res/chips/chips.prt';

PART_NAME
 PR302 'Q_RES_0402LF-0,5%,1/16W,CHIP,CS00002JB13':;

SECTION_NUMBER 1
 '@T6G_MB_LIB.T6G(SCH_1):PAGE27_I323@PURE_QUANTA.Q_RES(CHIPS)':
 C_PATH='@t6g_mb_lib.t6g(sch_1):page27_i323@pure_quanta.q_res(chips)',
 P_PATH='@t6g_mb_lib.t6g(sch_1):page27_i323@pure_quanta.q_res(chips)',
 PATH='I323',
 DRAWING='@T6G_MB_LIB.T6G(SCH_1):PAGE27',
 WATTAGE='1/16W',
 TOLERANCE='5%',
 MATERIAL='CHIP',
 PHYS_PAGE='27',
 XY='(-6350,5525)',
 ROT='0',
 VER='1',
 PACK_TYPE='0402LF',
 LOCATION='PR302',
 CDS_LIB='pure_quanta',
 CDS_PART_NAME='Q_RES_0402LF-0,5%,1/16W,CHIP,CS00002JB13',
 PART_NUMBER='CS00002JB13',
 VALUE='0',
 PRIM_FILE='./archive_libs/logical/q_res/chips/chips.prt';

PART_NAME
 PR303 'Q_RES_0402LF-0,5%,1/16W,CHIP,CS00002JB13':;

SECTION_NUMBER 1
 '@T6G_MB_LIB.T6G(SCH_1):PAGE27_I322@PURE_QUANTA.Q_RES(CHIPS)':
 C_PATH='@t6g_mb_lib.t6g(sch_1):page27_i322@pure_quanta.q_res(chips)',
 P_PATH='@t6g_mb_lib.t6g(sch_1):page27_i322@pure_quanta.q_res(chips)',
 PATH='I322',
 DRAWING='@T6G_MB_LIB.T6G(SCH_1):PAGE27',
 WATTAGE='1/16W',
 TOLERANCE='5%',
 MATERIAL='CHIP',
 PHYS_PAGE='27',
 XY='(-6350,5475)',
 ROT='0',
 VER='1',
 PACK_TYPE='0402LF',
 LOCATION='PR303',
 CDS_LIB='pure_quanta',
 CDS_PART_NAME='Q_RES_0402LF-0,5%,1/16W,CHIP,CS00002JB13',
 PART_NUMBER='CS00002JB13',
 VALUE='0',
 PRIM_FILE='./archive_libs/logical/q_res/chips/chips.prt';

PART_NAME
 PR305 'Q_RES_0402LF-0,5%,1/16W,CHIP,CS00002JB13':;

SECTION_NUMBER 1
 '@T6G_MB_LIB.T6G(SCH_1):PAGE168_I86@PURE_QUANTA.Q_RES(CHIPS)':
 C_PATH='@t6g_mb_lib.t6g(sch_1):page168_i86@pure_quanta.q_res(chips)',
 P_PATH='@t6g_mb_lib.t6g(sch_1):page193_i86@pure_quanta.q_res(chips)',
 PATH='I86',
 DRAWING='@T6G_MB_LIB.T6G(SCH_1):PAGE168',
 WATTAGE='1/16W',
 TOLERANCE='5%',
 MATERIAL='CHIP',
 PHYS_PAGE='193',
 XY='(-5600,5600)',
 ROT='0',
 VER='1',
 PACK_TYPE='0402LF',
 LOCATION='PR305',
 CDS_LIB='pure_quanta',
 CDS_PART_NAME='Q_RES_0402LF-0,5%,1/16W,CHIP,CS00002JB13',
 PART_NUMBER='CS00002JB13',
 VALUE='0',
 PRIM_FILE='./archive_libs/logical/q_res/chips/chips.prt';

PART_NAME
 PR306 'Q_RES_0402LF-0,5%,1/16W,CHIP,CS00002JB13':;

SECTION_NUMBER 1
 '@T6G_MB_LIB.T6G(SCH_1):PAGE168_I61@PURE_QUANTA.Q_RES(CHIPS)':
 C_PATH='@t6g_mb_lib.t6g(sch_1):page168_i61@pure_quanta.q_res(chips)',
 P_PATH='@t6g_mb_lib.t6g(sch_1):page193_i61@pure_quanta.q_res(chips)',
 PATH='I61',
 DRAWING='@T6G_MB_LIB.T6G(SCH_1):PAGE168',
 WATTAGE='1/16W',
 TOLERANCE='5%',
 MATERIAL='CHIP',
 PHYS_PAGE='193',
 XY='(-5600,4450)',
 ROT='0',
 VER='1',
 PACK_TYPE='0402LF',
 LOCATION='PR306',
 CDS_LIB='pure_quanta',
 CDS_PART_NAME='Q_RES_0402LF-0,5%,1/16W,CHIP,CS00002JB13',
 PART_NUMBER='CS00002JB13',
 VALUE='0',
 PRIM_FILE='./archive_libs/logical/q_res/chips/chips.prt';

PART_NAME
 PR307 'Q_RES_0402LF-0,5%,1/16W,CHIP,CS00002JB13':;

SECTION_NUMBER 1
 '@T6G_MB_LIB.T6G(SCH_1):PAGE168_I59@PURE_QUANTA.Q_RES(CHIPS)':
 C_PATH='@t6g_mb_lib.t6g(sch_1):page168_i59@pure_quanta.q_res(chips)',
 P_PATH='@t6g_mb_lib.t6g(sch_1):page193_i59@pure_quanta.q_res(chips)',
 PATH='I59',
 DRAWING='@T6G_MB_LIB.T6G(SCH_1):PAGE168',
 WATTAGE='1/16W',
 TOLERANCE='5%',
 MATERIAL='CHIP',
 PHYS_PAGE='193',
 XY='(-5525,3350)',
 ROT='0',
 VER='1',
 PACK_TYPE='0402LF',
 LOCATION='PR307',
 CDS_LIB='pure_quanta',
 CDS_PART_NAME='Q_RES_0402LF-0,5%,1/16W,CHIP,CS00002JB13',
 PART_NUMBER='CS00002JB13',
 VALUE='0',
 PRIM_FILE='./archive_libs/logical/q_res/chips/chips.prt';

PART_NAME
 PR314 'Q_RES_0402LF-0,5%,1/16W,CHIP,CS00002JB13':;

SECTION_NUMBER 1
 '@T6G_MB_LIB.T6G(SCH_1):PAGE168_I48@PURE_QUANTA.Q_RES(CHIPS)':
 C_PATH='@t6g_mb_lib.t6g(sch_1):page168_i48@pure_quanta.q_res(chips)',
 P_PATH='@t6g_mb_lib.t6g(sch_1):page193_i48@pure_quanta.q_res(chips)',
 PATH='I48',
 DRAWING='@T6G_MB_LIB.T6G(SCH_1):PAGE168',
 WATTAGE='1/16W',
 TOLERANCE='5%',
 MATERIAL='CHIP',
 PHYS_PAGE='193',
 XY='(-5550,1050)',
 ROT='0',
 VER='1',
 PACK_TYPE='0402LF',
 LOCATION='PR314',
 CDS_LIB='pure_quanta',
 CDS_PART_NAME='Q_RES_0402LF-0,5%,1/16W,CHIP,CS00002JB13',
 PART_NUMBER='CS00002JB13',
 VALUE='0',
 PRIM_FILE='./archive_libs/logical/q_res/chips/chips.prt';

PART_NAME
 PR316 'Q_RES_0402LF-1,1%,1/16W,CHIP,CS-1002FB04':;

SECTION_NUMBER 1
 '@T6G_MB_LIB.T6G(SCH_1):PAGE168_I133@PURE_QUANTA.Q_RES(CHIPS)':
 C_PATH='@t6g_mb_lib.t6g(sch_1):page168_i133@pure_quanta.q_res(chips)',
 P_PATH='@t6g_mb_lib.t6g(sch_1):page193_i133@pure_quanta.q_res(chips)',
 PATH='I133',
 DRAWING='@T6G_MB_LIB.T6G(SCH_1):PAGE168',
 WATTAGE='1/16W',
 TOLERANCE='1%',
 MATERIAL='CHIP',
 PHYS_PAGE='193',
 XY='(-2050,6675)',
 ROT='0',
 VER='1',
 PACK_TYPE='0402LF',
 LOCATION='PR316',
 CDS_LIB='pure_quanta',
 CDS_PART_NAME='Q_RES_0402LF-1,1%,1/16W,CHIP,CS-1002FB04',
 PART_NUMBER='CS-1002FB04',
 VALUE='1',
 PRIM_FILE='./archive_libs/logical/q_res/chips/chips.prt';

PART_NAME
 PR318 'Q_RES_0402LF-2.2,1%,1/16W,CHIP,CS-2202FB01':;

SECTION_NUMBER 1
 '@T6G_MB_LIB.T6G(SCH_1):PAGE169_I49@PURE_QUANTA.Q_RES(CHIPS)':
 C_PATH='@t6g_mb_lib.t6g(sch_1):page169_i49@pure_quanta.q_res(chips)',
 P_PATH='@t6g_mb_lib.t6g(sch_1):page194_i49@pure_quanta.q_res(chips)',
 PATH='I49',
 DRAWING='@T6G_MB_LIB.T6G(SCH_1):PAGE169',
 WATTAGE='1/16W',
 TOLERANCE='1%',
 MATERIAL='CHIP',
 PHYS_PAGE='194',
 XY='(-7975,5200)',
 ROT='0',
 VER='2',
 PACK_TYPE='0402LF',
 LOCATION='PR318',
 CDS_LIB='pure_quanta',
 CDS_PART_NAME='Q_RES_0402LF-2.2,1%,1/16W,CHIP,CS-2202FB01',
 PART_NUMBER='CS-2202FB01',
 VALUE='2.2',
 PRIM_FILE='./archive_libs/logical/q_res/chips/chips.prt';

PART_NAME
 PR319 'Q_RES_0402LF-2.2,1%,1/16W,CHIP,CS-2202FB01':;

SECTION_NUMBER 1
 '@T6G_MB_LIB.T6G(SCH_1):PAGE169_I17@PURE_QUANTA.Q_RES(CHIPS)':
 C_PATH='@t6g_mb_lib.t6g(sch_1):page169_i17@pure_quanta.q_res(chips)',
 P_PATH='@t6g_mb_lib.t6g(sch_1):page194_i17@pure_quanta.q_res(chips)',
 PATH='I17',
 DRAWING='@T6G_MB_LIB.T6G(SCH_1):PAGE169',
 WATTAGE='1/16W',
 TOLERANCE='1%',
 MATERIAL='CHIP',
 PHYS_PAGE='194',
 XY='(-7650,2450)',
 ROT='0',
 VER='2',
 PACK_TYPE='0402LF',
 LOCATION='PR319',
 CDS_LIB='pure_quanta',
 CDS_PART_NAME='Q_RES_0402LF-2.2,1%,1/16W,CHIP,CS-2202FB01',
 PART_NUMBER='CS-2202FB01',
 VALUE='2.2',
 PRIM_FILE='./archive_libs/logical/q_res/chips/chips.prt';

PART_NAME
 PR320 'Q_RES_0402LF-8.87K,1%,1/16W,EMPTY,CS28872FB01':;

SECTION_NUMBER 1
 '@T6G_MB_LIB.T6G(SCH_1):PAGE169_I46@PURE_QUANTA.Q_RES(CHIPS)':
 C_PATH='@t6g_mb_lib.t6g(sch_1):page169_i46@pure_quanta.q_res(chips)',
 P_PATH='@t6g_mb_lib.t6g(sch_1):page194_i46@pure_quanta.q_res(chips)',
 PATH='I46',
 DRAWING='@T6G_MB_LIB.T6G(SCH_1):PAGE169',
 WATTAGE='1/16W',
 TOLERANCE='1%',
 MATERIAL='EMPTY',
 PHYS_PAGE='194',
 XY='(-7350,4050)',
 ROT='0',
 VER='1',
 PACK_TYPE='0402LF',
 LOCATION='PR320',
 CDS_LIB='pure_quanta',
 CDS_PART_NAME='Q_RES_0402LF-8.87K,1%,1/16W,EMPTY,CS28872FB01',
 PART_NUMBER='CS28872FB01',
 VALUE='8.87K',
 PRIM_FILE='./archive_libs/logical/q_res/chips/chips.prt';

PART_NAME
 PR321 'Q_RES_0402LF-8.87K,1%,1/16W,EMPTY,CS28872FB01':;

SECTION_NUMBER 1
 '@T6G_MB_LIB.T6G(SCH_1):PAGE169_I10@PURE_QUANTA.Q_RES(CHIPS)':
 C_PATH='@t6g_mb_lib.t6g(sch_1):page169_i10@pure_quanta.q_res(chips)',
 P_PATH='@t6g_mb_lib.t6g(sch_1):page194_i10@pure_quanta.q_res(chips)',
 PATH='I10',
 DRAWING='@T6G_MB_LIB.T6G(SCH_1):PAGE169',
 WATTAGE='1/16W',
 TOLERANCE='1%',
 MATERIAL='EMPTY',
 PHYS_PAGE='194',
 XY='(-7350,1300)',
 ROT='0',
 VER='1',
 PACK_TYPE='0402LF',
 LOCATION='PR321',
 CDS_LIB='pure_quanta',
 CDS_PART_NAME='Q_RES_0402LF-8.87K,1%,1/16W,EMPTY,CS28872FB01',
 PART_NUMBER='CS28872FB01',
 VALUE='8.87K',
 PRIM_FILE='./archive_libs/logical/q_res/chips/chips.prt';

PART_NAME
 PR322 'Q_RES_0402LF-5.6,1%,1/16W,CHIP,CS-5602FB01':;

SECTION_NUMBER 1
 '@T6G_MB_LIB.T6G(SCH_1):PAGE169_I55@PURE_QUANTA.Q_RES(CHIPS)':
 C_PATH='@t6g_mb_lib.t6g(sch_1):page169_i55@pure_quanta.q_res(chips)',
 P_PATH='@t6g_mb_lib.t6g(sch_1):page194_i55@pure_quanta.q_res(chips)',
 PATH='I55',
 DRAWING='@T6G_MB_LIB.T6G(SCH_1):PAGE169',
 WATTAGE='1/16W',
 TOLERANCE='1%',
 MATERIAL='CHIP',
 PHYS_PAGE='194',
 XY='(-4850,4700)',
 ROT='0',
 VER='1',
 PACK_TYPE='0402LF',
 LOCATION='PR322',
 CDS_LIB='pure_quanta',
 CDS_PART_NAME='Q_RES_0402LF-5.6,1%,1/16W,CHIP,CS-5602FB01',
 PART_NUMBER='CS-5602FB01',
 VALUE='5.6',
 PRIM_FILE='./archive_libs/logical/q_res/chips/chips.prt';

PART_NAME
 PR323 'Q_RES_0402LF-5.6,1%,1/16W,CHIP,CS-5602FB01':;

SECTION_NUMBER 1
 '@T6G_MB_LIB.T6G(SCH_1):PAGE169_I32@PURE_QUANTA.Q_RES(CHIPS)':
 C_PATH='@t6g_mb_lib.t6g(sch_1):page169_i32@pure_quanta.q_res(chips)',
 P_PATH='@t6g_mb_lib.t6g(sch_1):page194_i32@pure_quanta.q_res(chips)',
 PATH='I32',
 DRAWING='@T6G_MB_LIB.T6G(SCH_1):PAGE169',
 WATTAGE='1/16W',
 TOLERANCE='1%',
 MATERIAL='CHIP',
 PHYS_PAGE='194',
 XY='(-4725,1950)',
 ROT='0',
 VER='1',
 PACK_TYPE='0402LF',
 LOCATION='PR323',
 CDS_LIB='pure_quanta',
 CDS_PART_NAME='Q_RES_0402LF-5.6,1%,1/16W,CHIP,CS-5602FB01',
 PART_NUMBER='CS-5602FB01',
 VALUE='5.6',
 PRIM_FILE='./archive_libs/logical/q_res/chips/chips.prt';

PART_NAME
 PR324 'Q_RES_0402LF-0,5%,1/16W,CHIP,CS00002JB13':;

SECTION_NUMBER 1
 '@T6G_MB_LIB.T6G(SCH_1):PAGE169_I43@PURE_QUANTA.Q_RES(CHIPS)':
 C_PATH='@t6g_mb_lib.t6g(sch_1):page169_i43@pure_quanta.q_res(chips)',
 P_PATH='@t6g_mb_lib.t6g(sch_1):page194_i43@pure_quanta.q_res(chips)',
 PATH='I43',
 DRAWING='@T6G_MB_LIB.T6G(SCH_1):PAGE169',
 WATTAGE='1/16W',
 TOLERANCE='5%',
 MATERIAL='CHIP',
 PHYS_PAGE='194',
 XY='(-4375,3400)',
 ROT='0',
 VER='1',
 PACK_TYPE='0402LF',
 LOCATION='PR324',
 CDS_LIB='pure_quanta',
 CDS_PART_NAME='Q_RES_0402LF-0,5%,1/16W,CHIP,CS00002JB13',
 PART_NUMBER='CS00002JB13',
 VALUE='0',
 PRIM_FILE='./archive_libs/logical/q_res/chips/chips.prt';

PART_NAME
 PR325 'Q_RES_0402LF-0,5%,1/16W,CHIP,CS00002JB13':;

SECTION_NUMBER 1
 '@T6G_MB_LIB.T6G(SCH_1):PAGE169_I30@PURE_QUANTA.Q_RES(CHIPS)':
 C_PATH='@t6g_mb_lib.t6g(sch_1):page169_i30@pure_quanta.q_res(chips)',
 P_PATH='@t6g_mb_lib.t6g(sch_1):page194_i30@pure_quanta.q_res(chips)',
 PATH='I30',
 DRAWING='@T6G_MB_LIB.T6G(SCH_1):PAGE169',
 WATTAGE='1/16W',
 TOLERANCE='5%',
 MATERIAL='CHIP',
 PHYS_PAGE='194',
 XY='(-4250,675)',
 ROT='0',
 VER='1',
 PACK_TYPE='0402LF',
 LOCATION='PR325',
 CDS_LIB='pure_quanta',
 CDS_PART_NAME='Q_RES_0402LF-0,5%,1/16W,CHIP,CS00002JB13',
 PART_NUMBER='CS00002JB13',
 VALUE='0',
 PRIM_FILE='./archive_libs/logical/q_res/chips/chips.prt';

PART_NAME
 PR326 'Q_RES_0402LF-2.2,1%,1/16W,CHIP,CS-2202FB01':;

SECTION_NUMBER 1
 '@T6G_MB_LIB.T6G(SCH_1):PAGE200_I40@PURE_QUANTA.Q_RES(CHIPS)':
 C_PATH='@t6g_mb_lib.t6g(sch_1):page200_i40@pure_quanta.q_res(chips)',
 P_PATH='@t6g_mb_lib.t6g(sch_1):page225_i40@pure_quanta.q_res(chips)',
 PATH='I40',
 DRAWING='@T6G_MB_LIB.T6G(SCH_1):PAGE200',
 WATTAGE='1/16W',
 TOLERANCE='1%',
 MATERIAL='CHIP',
 PHYS_PAGE='225',
 XY='(-7775,5500)',
 ROT='0',
 VER='2',
 PACK_TYPE='0402LF',
 LOCATION='PR326',
 CDS_LIB='pure_quanta',
 CDS_PART_NAME='Q_RES_0402LF-2.2,1%,1/16W,CHIP,CS-2202FB01',
 PART_NUMBER='CS-2202FB01',
 VALUE='2.2',
 PRIM_FILE='./archive_libs/logical/q_res/chips/chips.prt';

PART_NAME
 PR327 'Q_RES_0402LF-2.2,1%,1/16W,CHIP,CS-2202FB01':;

SECTION_NUMBER 1
 '@T6G_MB_LIB.T6G(SCH_1):PAGE200_I14@PURE_QUANTA.Q_RES(CHIPS)':
 C_PATH='@t6g_mb_lib.t6g(sch_1):page200_i14@pure_quanta.q_res(chips)',
 P_PATH='@t6g_mb_lib.t6g(sch_1):page225_i14@pure_quanta.q_res(chips)',
 PATH='I14',
 DRAWING='@T6G_MB_LIB.T6G(SCH_1):PAGE200',
 WATTAGE='1/16W',
 TOLERANCE='1%',
 MATERIAL='CHIP',
 PHYS_PAGE='225',
 XY='(-7775,2575)',
 ROT='0',
 VER='2',
 PACK_TYPE='0402LF',
 LOCATION='PR327',
 CDS_LIB='pure_quanta',
 CDS_PART_NAME='Q_RES_0402LF-2.2,1%,1/16W,CHIP,CS-2202FB01',
 PART_NUMBER='CS-2202FB01',
 VALUE='2.2',
 PRIM_FILE='./archive_libs/logical/q_res/chips/chips.prt';

PART_NAME
 PR328 'Q_RES_0402LF-4.87K,1%,1/16W,EMPTY,CS24872FB07':;

SECTION_NUMBER 1
 '@T6G_MB_LIB.T6G(SCH_1):PAGE200_I37@PURE_QUANTA.Q_RES(CHIPS)':
 C_PATH='@t6g_mb_lib.t6g(sch_1):page200_i37@pure_quanta.q_res(chips)',
 P_PATH='@t6g_mb_lib.t6g(sch_1):page225_i37@pure_quanta.q_res(chips)',
 PATH='I37',
 DRAWING='@T6G_MB_LIB.T6G(SCH_1):PAGE200',
 WATTAGE='1/16W',
 TOLERANCE='1%',
 MATERIAL='EMPTY',
 PHYS_PAGE='225',
 XY='(-7200,4325)',
 ROT='0',
 VER='1',
 PACK_TYPE='0402LF',
 LOCATION='PR328',
 CDS_LIB='pure_quanta',
 CDS_PART_NAME='Q_RES_0402LF-4.87K,1%,1/16W,EMPTY,CS24872FB07',
 PART_NUMBER='CS24872FB07',
 VALUE='4.87K',
 PRIM_FILE='./archive_libs/logical/q_res/chips/chips.prt';

PART_NAME
 PR329 'Q_RES_0402LF-4.87K,1%,1/16W,EMPTY,CS24872FB07':;

SECTION_NUMBER 1
 '@T6G_MB_LIB.T6G(SCH_1):PAGE200_I12@PURE_QUANTA.Q_RES(CHIPS)':
 C_PATH='@t6g_mb_lib.t6g(sch_1):page200_i12@pure_quanta.q_res(chips)',
 P_PATH='@t6g_mb_lib.t6g(sch_1):page225_i12@pure_quanta.q_res(chips)',
 PATH='I12',
 DRAWING='@T6G_MB_LIB.T6G(SCH_1):PAGE200',
 WATTAGE='1/16W',
 TOLERANCE='1%',
 MATERIAL='EMPTY',
 PHYS_PAGE='225',
 XY='(-7175,1400)',
 ROT='0',
 VER='1',
 PACK_TYPE='0402LF',
 LOCATION='PR329',
 CDS_LIB='pure_quanta',
 CDS_PART_NAME='Q_RES_0402LF-4.87K,1%,1/16W,EMPTY,CS24872FB07',
 PART_NUMBER='CS24872FB07',
 VALUE='4.87K',
 PRIM_FILE='./archive_libs/logical/q_res/chips/chips.prt';

PART_NAME
 PR330 'Q_RES_0402LF-5.6,1%,1/16W,CHIP,CS-5602FB01':;

SECTION_NUMBER 1
 '@T6G_MB_LIB.T6G(SCH_1):PAGE200_I47@PURE_QUANTA.Q_RES(CHIPS)':
 C_PATH='@t6g_mb_lib.t6g(sch_1):page200_i47@pure_quanta.q_res(chips)',
 P_PATH='@t6g_mb_lib.t6g(sch_1):page225_i47@pure_quanta.q_res(chips)',
 PATH='I47',
 DRAWING='@T6G_MB_LIB.T6G(SCH_1):PAGE200',
 WATTAGE='1/16W',
 TOLERANCE='1%',
 MATERIAL='CHIP',
 PHYS_PAGE='225',
 XY='(-4775,4975)',
 ROT='0',
 VER='1',
 PACK_TYPE='0402LF',
 LOCATION='PR330',
 CDS_LIB='pure_quanta',
 CDS_PART_NAME='Q_RES_0402LF-5.6,1%,1/16W,CHIP,CS-5602FB01',
 PART_NUMBER='CS-5602FB01',
 VALUE='5.6',
 PRIM_FILE='./archive_libs/logical/q_res/chips/chips.prt';

PART_NAME
 PR331 'Q_RES_0402LF-5.6,1%,1/16W,CHIP,CS-5602FB01':;

SECTION_NUMBER 1
 '@T6G_MB_LIB.T6G(SCH_1):PAGE200_I26@PURE_QUANTA.Q_RES(CHIPS)':
 C_PATH='@t6g_mb_lib.t6g(sch_1):page200_i26@pure_quanta.q_res(chips)',
 P_PATH='@t6g_mb_lib.t6g(sch_1):page225_i26@pure_quanta.q_res(chips)',
 PATH='I26',
 DRAWING='@T6G_MB_LIB.T6G(SCH_1):PAGE200',
 WATTAGE='1/16W',
 TOLERANCE='1%',
 MATERIAL='CHIP',
 PHYS_PAGE='225',
 XY='(-4650,2050)',
 ROT='0',
 VER='1',
 PACK_TYPE='0402LF',
 LOCATION='PR331',
 CDS_LIB='pure_quanta',
 CDS_PART_NAME='Q_RES_0402LF-5.6,1%,1/16W,CHIP,CS-5602FB01',
 PART_NUMBER='CS-5602FB01',
 VALUE='5.6',
 PRIM_FILE='./archive_libs/logical/q_res/chips/chips.prt';

PART_NAME
 PR332 'Q_RES_0402LF-0,5%,1/16W,CHIP,CS00002JB13':;

SECTION_NUMBER 1
 '@T6G_MB_LIB.T6G(SCH_1):PAGE200_I60@PURE_QUANTA.Q_RES(CHIPS)':
 C_PATH='@t6g_mb_lib.t6g(sch_1):page200_i60@pure_quanta.q_res(chips)',
 P_PATH='@t6g_mb_lib.t6g(sch_1):page225_i60@pure_quanta.q_res(chips)',
 PATH='I60',
 DRAWING='@T6G_MB_LIB.T6G(SCH_1):PAGE200',
 WATTAGE='1/16W',
 TOLERANCE='5%',
 MATERIAL='CHIP',
 PHYS_PAGE='225',
 XY='(-3575,3500)',
 ROT='0',
 VER='1',
 PACK_TYPE='0402LF',
 LOCATION='PR332',
 CDS_LIB='pure_quanta',
 CDS_PART_NAME='Q_RES_0402LF-0,5%,1/16W,CHIP,CS00002JB13',
 PART_NUMBER='CS00002JB13',
 VALUE='0',
 PRIM_FILE='./archive_libs/logical/q_res/chips/chips.prt';

PART_NAME
 PR333 'Q_RES_0402LF-0,5%,1/16W,CHIP,CS00002JB13':;

SECTION_NUMBER 1
 '@T6G_MB_LIB.T6G(SCH_1):PAGE200_I53@PURE_QUANTA.Q_RES(CHIPS)':
 C_PATH='@t6g_mb_lib.t6g(sch_1):page200_i53@pure_quanta.q_res(chips)',
 P_PATH='@t6g_mb_lib.t6g(sch_1):page225_i53@pure_quanta.q_res(chips)',
 PATH='I53',
 DRAWING='@T6G_MB_LIB.T6G(SCH_1):PAGE200',
 WATTAGE='1/16W',
 TOLERANCE='5%',
 MATERIAL='CHIP',
 PHYS_PAGE='225',
 XY='(-3500,700)',
 ROT='0',
 VER='1',
 PACK_TYPE='0402LF',
 LOCATION='PR333',
 CDS_LIB='pure_quanta',
 CDS_PART_NAME='Q_RES_0402LF-0,5%,1/16W,CHIP,CS00002JB13',
 PART_NUMBER='CS00002JB13',
 VALUE='0',
 PRIM_FILE='./archive_libs/logical/q_res/chips/chips.prt';

PART_NAME
 PR334 'Q_RES_0402LF-1K,1%,1/16W,CHIP,CS21002FB06':;

SECTION_NUMBER 1
 '@T6G_MB_LIB.T6G(SCH_1):PAGE173_I82@PURE_QUANTA.Q_RES(CHIPS)':
 C_PATH='@t6g_mb_lib.t6g(sch_1):page173_i82@pure_quanta.q_res(chips)',
 P_PATH='@t6g_mb_lib.t6g(sch_1):page198_i82@pure_quanta.q_res(chips)',
 PATH='I82',
 DRAWING='@T6G_MB_LIB.T6G(SCH_1):PAGE173',
 WATTAGE='1/16W',
 TOLERANCE='1%',
 MATERIAL='CHIP',
 PHYS_PAGE='198',
 XY='(-350,4875)',
 ROT='0',
 VER='2',
 PACK_TYPE='0402LF',
 LOCATION='PR334',
 CDS_LIB='pure_quanta',
 CDS_PART_NAME='Q_RES_0402LF-1K,1%,1/16W,CHIP,CS21002FB06',
 PART_NUMBER='CS21002FB06',
 VALUE='1K',
 PRIM_FILE='./archive_libs/logical/q_res/chips/chips.prt';

PART_NAME
 PR335 'Q_RES_0402LF-0,5%,1/16W,CHIP,CS00002JB13':;

SECTION_NUMBER 1
 '@T6G_MB_LIB.T6G(SCH_1):PAGE186_I3@PURE_QUANTA.Q_RES(CHIPS)':
 C_PATH='@t6g_mb_lib.t6g(sch_1):page186_i3@pure_quanta.q_res(chips)',
 P_PATH='@t6g_mb_lib.t6g(sch_1):page211_i3@pure_quanta.q_res(chips)',
 PATH='I3',
 DRAWING='@T6G_MB_LIB.T6G(SCH_1):PAGE186',
 WATTAGE='1/16W',
 TOLERANCE='5%',
 MATERIAL='CHIP',
 PHYS_PAGE='211',
 XY='(-8250,5750)',
 ROT='1',
 VER='1',
 PACK_TYPE='0402LF',
 LOCATION='PR335',
 CDS_LIB='pure_quanta',
 CDS_PART_NAME='Q_RES_0402LF-0,5%,1/16W,CHIP,CS00002JB13',
 PART_NUMBER='CS00002JB13',
 VALUE='0',
 PRIM_FILE='./archive_libs/logical/q_res/chips/chips.prt';

PART_NAME
 PR336 'Q_RES_0402LF-0,5%,1/16W,EMPTY,CS00002JB13':;

SECTION_NUMBER 1
 '@T6G_MB_LIB.T6G(SCH_1):PAGE186_I41@PURE_QUANTA.Q_RES(CHIPS)':
 C_PATH='@t6g_mb_lib.t6g(sch_1):page186_i41@pure_quanta.q_res(chips)',
 P_PATH='@t6g_mb_lib.t6g(sch_1):page211_i41@pure_quanta.q_res(chips)',
 PATH='I41',
 DRAWING='@T6G_MB_LIB.T6G(SCH_1):PAGE186',
 WATTAGE='1/16W',
 TOLERANCE='5%',
 MATERIAL='EMPTY',
 PHYS_PAGE='211',
 XY='(-7900,5750)',
 ROT='1',
 VER='1',
 PACK_TYPE='0402LF',
 LOCATION='PR336',
 CDS_LIB='pure_quanta',
 CDS_PART_NAME='Q_RES_0402LF-0,5%,1/16W,EMPTY,CS00002JB13',
 PART_NUMBER='CS00002JB13',
 VALUE='0',
 PRIM_FILE='./archive_libs/logical/q_res/chips/chips.prt';

PART_NAME
 PR337 'Q_RES_0402LF-1K,1%,1/16W,CHIP,CS21002FB06':;

SECTION_NUMBER 1
 '@T6G_MB_LIB.T6G(SCH_1):PAGE186_I78@PURE_QUANTA.Q_RES(CHIPS)':
 C_PATH='@t6g_mb_lib.t6g(sch_1):page186_i78@pure_quanta.q_res(chips)',
 P_PATH='@t6g_mb_lib.t6g(sch_1):page211_i78@pure_quanta.q_res(chips)',
 PATH='I78',
 DRAWING='@T6G_MB_LIB.T6G(SCH_1):PAGE186',
 WATTAGE='1/16W',
 TOLERANCE='1%',
 MATERIAL='CHIP',
 PHYS_PAGE='211',
 XY='(-925,4275)',
 ROT='0',
 VER='2',
 PACK_TYPE='0402LF',
 LOCATION='PR337',
 CDS_LIB='pure_quanta',
 CDS_PART_NAME='Q_RES_0402LF-1K,1%,1/16W,CHIP,CS21002FB06',
 PART_NUMBER='CS21002FB06',
 VALUE='1K',
 PRIM_FILE='./archive_libs/logical/q_res/chips/chips.prt';

PART_NAME
 PR339 'Q_RES_0402LF-1K,1%,1/16W,CHIP,CS21002FB06':;

SECTION_NUMBER 1
 '@T6G_MB_LIB.T6G(SCH_1):PAGE190_I83@PURE_QUANTA.Q_RES(CHIPS)':
 C_PATH='@t6g_mb_lib.t6g(sch_1):page190_i83@pure_quanta.q_res(chips)',
 P_PATH='@t6g_mb_lib.t6g(sch_1):page215_i83@pure_quanta.q_res(chips)',
 PATH='I83',
 DRAWING='@T6G_MB_LIB.T6G(SCH_1):PAGE190',
 WATTAGE='1/16W',
 TOLERANCE='1%',
 MATERIAL='CHIP',
 PHYS_PAGE='215',
 XY='(-875,4550)',
 ROT='0',
 VER='2',
 PACK_TYPE='0402LF',
 LOCATION='PR339',
 CDS_LIB='pure_quanta',
 CDS_PART_NAME='Q_RES_0402LF-1K,1%,1/16W,CHIP,CS21002FB06',
 PART_NUMBER='CS21002FB06',
 VALUE='1K',
 PRIM_FILE='./archive_libs/logical/q_res/chips/chips.prt';

PART_NAME
 PR340 'Q_RES_0402LF-0,5%,1/16W,CHIP,CS00002JB13':;

SECTION_NUMBER 1
 '@T6G_MB_LIB.T6G(SCH_1):PAGE193_I89@PURE_QUANTA.Q_RES(CHIPS)':
 C_PATH='@t6g_mb_lib.t6g(sch_1):page193_i89@pure_quanta.q_res(chips)',
 P_PATH='@t6g_mb_lib.t6g(sch_1):page218_i89@pure_quanta.q_res(chips)',
 PATH='I89',
 DRAWING='@T6G_MB_LIB.T6G(SCH_1):PAGE193',
 WATTAGE='1/16W',
 TOLERANCE='5%',
 MATERIAL='CHIP',
 PHYS_PAGE='218',
 XY='(-9225,6000)',
 ROT='1',
 VER='1',
 PACK_TYPE='0402LF',
 LOCATION='PR340',
 CDS_LIB='pure_quanta',
 CDS_PART_NAME='Q_RES_0402LF-0,5%,1/16W,CHIP,CS00002JB13',
 PART_NUMBER='CS00002JB13',
 VALUE='0',
 PRIM_FILE='./archive_libs/logical/q_res/chips/chips.prt';

PART_NAME
 PR341 'Q_RES_0402LF-0,5%,1/16W,EMPTY,CS00002JB13':;

SECTION_NUMBER 1
 '@T6G_MB_LIB.T6G(SCH_1):PAGE193_I90@PURE_QUANTA.Q_RES(CHIPS)':
 C_PATH='@t6g_mb_lib.t6g(sch_1):page193_i90@pure_quanta.q_res(chips)',
 P_PATH='@t6g_mb_lib.t6g(sch_1):page218_i90@pure_quanta.q_res(chips)',
 PATH='I90',
 DRAWING='@T6G_MB_LIB.T6G(SCH_1):PAGE193',
 WATTAGE='1/16W',
 TOLERANCE='5%',
 MATERIAL='EMPTY',
 PHYS_PAGE='218',
 XY='(-8875,6000)',
 ROT='1',
 VER='1',
 PACK_TYPE='0402LF',
 LOCATION='PR341',
 CDS_LIB='pure_quanta',
 CDS_PART_NAME='Q_RES_0402LF-0,5%,1/16W,EMPTY,CS00002JB13',
 PART_NUMBER='CS00002JB13',
 VALUE='0',
 PRIM_FILE='./archive_libs/logical/q_res/chips/chips.prt';

PART_NAME
 PR342 'Q_RES_0402LF-1K,1%,1/16W,CHIP,CS21002FB06':;

SECTION_NUMBER 1
 '@T6G_MB_LIB.T6G(SCH_1):PAGE193_I87@PURE_QUANTA.Q_RES(CHIPS)':
 C_PATH='@t6g_mb_lib.t6g(sch_1):page193_i87@pure_quanta.q_res(chips)',
 P_PATH='@t6g_mb_lib.t6g(sch_1):page218_i87@pure_quanta.q_res(chips)',
 PATH='I87',
 DRAWING='@T6G_MB_LIB.T6G(SCH_1):PAGE193',
 WATTAGE='1/16W',
 TOLERANCE='1%',
 MATERIAL='CHIP',
 PHYS_PAGE='218',
 XY='(-900,4400)',
 ROT='0',
 VER='2',
 PACK_TYPE='0402LF',
 LOCATION='PR342',
 CDS_LIB='pure_quanta',
 CDS_PART_NAME='Q_RES_0402LF-1K,1%,1/16W,CHIP,CS21002FB06',
 PART_NUMBER='CS21002FB06',
 VALUE='1K',
 PRIM_FILE='./archive_libs/logical/q_res/chips/chips.prt';

PART_NAME
 PR344 'Q_RES_0402LF-2.2,1%,1/16W,CHIP,CS-2202FB01':;

SECTION_NUMBER 1
 '@T6G_MB_LIB.T6G(SCH_1):PAGE170_I37@PURE_QUANTA.Q_RES(CHIPS)':
 C_PATH='@t6g_mb_lib.t6g(sch_1):page170_i37@pure_quanta.q_res(chips)',
 P_PATH='@t6g_mb_lib.t6g(sch_1):page195_i37@pure_quanta.q_res(chips)',
 PATH='I37',
 DRAWING='@T6G_MB_LIB.T6G(SCH_1):PAGE170',
 WATTAGE='1/16W',
 TOLERANCE='1%',
 MATERIAL='CHIP',
 PHYS_PAGE='195',
 XY='(-7350,5650)',
 ROT='0',
 VER='2',
 PACK_TYPE='0402LF',
 LOCATION='PR344',
 CDS_LIB='pure_quanta',
 CDS_PART_NAME='Q_RES_0402LF-2.2,1%,1/16W,CHIP,CS-2202FB01',
 PART_NUMBER='CS-2202FB01',
 VALUE='2.2',
 PRIM_FILE='./archive_libs/logical/q_res/chips/chips.prt';

PART_NAME
 PR345 'Q_RES_0402LF-2.2,1%,1/16W,CHIP,CS-2202FB01':;

SECTION_NUMBER 1
 '@T6G_MB_LIB.T6G(SCH_1):PAGE170_I12@PURE_QUANTA.Q_RES(CHIPS)':
 C_PATH='@t6g_mb_lib.t6g(sch_1):page170_i12@pure_quanta.q_res(chips)',
 P_PATH='@t6g_mb_lib.t6g(sch_1):page195_i12@pure_quanta.q_res(chips)',
 PATH='I12',
 DRAWING='@T6G_MB_LIB.T6G(SCH_1):PAGE170',
 WATTAGE='1/16W',
 TOLERANCE='1%',
 MATERIAL='CHIP',
 PHYS_PAGE='195',
 XY='(-7250,2400)',
 ROT='0',
 VER='2',
 PACK_TYPE='0402LF',
 LOCATION='PR345',
 CDS_LIB='pure_quanta',
 CDS_PART_NAME='Q_RES_0402LF-2.2,1%,1/16W,CHIP,CS-2202FB01',
 PART_NUMBER='CS-2202FB01',
 VALUE='2.2',
 PRIM_FILE='./archive_libs/logical/q_res/chips/chips.prt';

PART_NAME
 PR346 'Q_RES_0402LF-8.87K,1%,1/16W,EMPTY,CS28872FB01':;

SECTION_NUMBER 1
 '@T6G_MB_LIB.T6G(SCH_1):PAGE170_I33@PURE_QUANTA.Q_RES(CHIPS)':
 C_PATH='@t6g_mb_lib.t6g(sch_1):page170_i33@pure_quanta.q_res(chips)',
 P_PATH='@t6g_mb_lib.t6g(sch_1):page195_i33@pure_quanta.q_res(chips)',
 PATH='I33',
 DRAWING='@T6G_MB_LIB.T6G(SCH_1):PAGE170',
 WATTAGE='1/16W',
 TOLERANCE='1%',
 MATERIAL='EMPTY',
 PHYS_PAGE='195',
 XY='(-7025,4500)',
 ROT='0',
 VER='1',
 PACK_TYPE='0402LF',
 LOCATION='PR346',
 CDS_LIB='pure_quanta',
 CDS_PART_NAME='Q_RES_0402LF-8.87K,1%,1/16W,EMPTY,CS28872FB01',
 PART_NUMBER='CS28872FB01',
 VALUE='8.87K',
 PRIM_FILE='./archive_libs/logical/q_res/chips/chips.prt';

PART_NAME
 PR347 'Q_RES_0402LF-8.87K,1%,1/16W,EMPTY,CS28872FB01':;

SECTION_NUMBER 1
 '@T6G_MB_LIB.T6G(SCH_1):PAGE170_I11@PURE_QUANTA.Q_RES(CHIPS)':
 C_PATH='@t6g_mb_lib.t6g(sch_1):page170_i11@pure_quanta.q_res(chips)',
 P_PATH='@t6g_mb_lib.t6g(sch_1):page195_i11@pure_quanta.q_res(chips)',
 PATH='I11',
 DRAWING='@T6G_MB_LIB.T6G(SCH_1):PAGE170',
 WATTAGE='1/16W',
 TOLERANCE='1%',
 MATERIAL='EMPTY',
 PHYS_PAGE='195',
 XY='(-6950,1200)',
 ROT='0',
 VER='1',
 PACK_TYPE='0402LF',
 LOCATION='PR347',
 CDS_LIB='pure_quanta',
 CDS_PART_NAME='Q_RES_0402LF-8.87K,1%,1/16W,EMPTY,CS28872FB01',
 PART_NUMBER='CS28872FB01',
 VALUE='8.87K',
 PRIM_FILE='./archive_libs/logical/q_res/chips/chips.prt';

PART_NAME
 PR348 'Q_RES_0402LF-5.6,1%,1/16W,CHIP,CS-5602FB01':;

SECTION_NUMBER 1
 '@T6G_MB_LIB.T6G(SCH_1):PAGE170_I46@PURE_QUANTA.Q_RES(CHIPS)':
 C_PATH='@t6g_mb_lib.t6g(sch_1):page170_i46@pure_quanta.q_res(chips)',
 P_PATH='@t6g_mb_lib.t6g(sch_1):page195_i46@pure_quanta.q_res(chips)',
 PATH='I46',
 DRAWING='@T6G_MB_LIB.T6G(SCH_1):PAGE170',
 WATTAGE='1/16W',
 TOLERANCE='1%',
 MATERIAL='CHIP',
 PHYS_PAGE='195',
 XY='(-4450,5150)',
 ROT='0',
 VER='1',
 PACK_TYPE='0402LF',
 LOCATION='PR348',
 CDS_LIB='pure_quanta',
 CDS_PART_NAME='Q_RES_0402LF-5.6,1%,1/16W,CHIP,CS-5602FB01',
 PART_NUMBER='CS-5602FB01',
 VALUE='5.6',
 PRIM_FILE='./archive_libs/logical/q_res/chips/chips.prt';

PART_NAME
 PR349 'Q_RES_0402LF-5.6,1%,1/16W,CHIP,CS-5602FB01':;

SECTION_NUMBER 1
 '@T6G_MB_LIB.T6G(SCH_1):PAGE170_I20@PURE_QUANTA.Q_RES(CHIPS)':
 C_PATH='@t6g_mb_lib.t6g(sch_1):page170_i20@pure_quanta.q_res(chips)',
 P_PATH='@t6g_mb_lib.t6g(sch_1):page195_i20@pure_quanta.q_res(chips)',
 PATH='I20',
 DRAWING='@T6G_MB_LIB.T6G(SCH_1):PAGE170',
 WATTAGE='1/16W',
 TOLERANCE='1%',
 MATERIAL='CHIP',
 PHYS_PAGE='195',
 XY='(-4375,1850)',
 ROT='0',
 VER='1',
 PACK_TYPE='0402LF',
 LOCATION='PR349',
 CDS_LIB='pure_quanta',
 CDS_PART_NAME='Q_RES_0402LF-5.6,1%,1/16W,CHIP,CS-5602FB01',
 PART_NUMBER='CS-5602FB01',
 VALUE='5.6',
 PRIM_FILE='./archive_libs/logical/q_res/chips/chips.prt';

PART_NAME
 PR350 'Q_RES_0402LF-0,5%,1/16W,CHIP,CS00002JB13':;

SECTION_NUMBER 1
 '@T6G_MB_LIB.T6G(SCH_1):PAGE170_I26@PURE_QUANTA.Q_RES(CHIPS)':
 C_PATH='@t6g_mb_lib.t6g(sch_1):page170_i26@pure_quanta.q_res(chips)',
 P_PATH='@t6g_mb_lib.t6g(sch_1):page195_i26@pure_quanta.q_res(chips)',
 PATH='I26',
 DRAWING='@T6G_MB_LIB.T6G(SCH_1):PAGE170',
 WATTAGE='1/16W',
 TOLERANCE='5%',
 MATERIAL='CHIP',
 PHYS_PAGE='195',
 XY='(-4050,3850)',
 ROT='0',
 VER='1',
 PACK_TYPE='0402LF',
 LOCATION='PR350',
 CDS_LIB='pure_quanta',
 CDS_PART_NAME='Q_RES_0402LF-0,5%,1/16W,CHIP,CS00002JB13',
 PART_NUMBER='CS00002JB13',
 VALUE='0',
 PRIM_FILE='./archive_libs/logical/q_res/chips/chips.prt';

PART_NAME
 PR351 'Q_RES_0402LF-0,5%,1/16W,CHIP,CS00002JB13':;

SECTION_NUMBER 1
 '@T6G_MB_LIB.T6G(SCH_1):PAGE170_I50@PURE_QUANTA.Q_RES(CHIPS)':
 C_PATH='@t6g_mb_lib.t6g(sch_1):page170_i50@pure_quanta.q_res(chips)',
 P_PATH='@t6g_mb_lib.t6g(sch_1):page195_i50@pure_quanta.q_res(chips)',
 PATH='I50',
 DRAWING='@T6G_MB_LIB.T6G(SCH_1):PAGE170',
 WATTAGE='1/16W',
 TOLERANCE='5%',
 MATERIAL='CHIP',
 PHYS_PAGE='195',
 XY='(-3875,600)',
 ROT='0',
 VER='1',
 PACK_TYPE='0402LF',
 LOCATION='PR351',
 CDS_LIB='pure_quanta',
 CDS_PART_NAME='Q_RES_0402LF-0,5%,1/16W,CHIP,CS00002JB13',
 PART_NUMBER='CS00002JB13',
 VALUE='0',
 PRIM_FILE='./archive_libs/logical/q_res/chips/chips.prt';

PART_NAME
 PR352 'Q_RES_0402LF-2.2,1%,1/16W,CHIP,CS-2202FB01':;

SECTION_NUMBER 1
 '@T6G_MB_LIB.T6G(SCH_1):PAGE171_I40@PURE_QUANTA.Q_RES(CHIPS)':
 C_PATH='@t6g_mb_lib.t6g(sch_1):page171_i40@pure_quanta.q_res(chips)',
 P_PATH='@t6g_mb_lib.t6g(sch_1):page196_i40@pure_quanta.q_res(chips)',
 PATH='I40',
 DRAWING='@T6G_MB_LIB.T6G(SCH_1):PAGE171',
 WATTAGE='1/16W',
 TOLERANCE='1%',
 MATERIAL='CHIP',
 PHYS_PAGE='196',
 XY='(-7200,5425)',
 ROT='0',
 VER='2',
 PACK_TYPE='0402LF',
 LOCATION='PR352',
 CDS_LIB='pure_quanta',
 CDS_PART_NAME='Q_RES_0402LF-2.2,1%,1/16W,CHIP,CS-2202FB01',
 PART_NUMBER='CS-2202FB01',
 VALUE='2.2',
 PRIM_FILE='./archive_libs/logical/q_res/chips/chips.prt';

PART_NAME
 PR353 'Q_RES_0402LF-8.87K,1%,1/16W,EMPTY,CS28872FB01':;

SECTION_NUMBER 1
 '@T6G_MB_LIB.T6G(SCH_1):PAGE171_I36@PURE_QUANTA.Q_RES(CHIPS)':
 C_PATH='@t6g_mb_lib.t6g(sch_1):page171_i36@pure_quanta.q_res(chips)',
 P_PATH='@t6g_mb_lib.t6g(sch_1):page196_i36@pure_quanta.q_res(chips)',
 PATH='I36',
 DRAWING='@T6G_MB_LIB.T6G(SCH_1):PAGE171',
 WATTAGE='1/16W',
 TOLERANCE='1%',
 MATERIAL='EMPTY',
 PHYS_PAGE='196',
 XY='(-6875,4275)',
 ROT='0',
 VER='1',
 PACK_TYPE='0402LF',
 LOCATION='PR353',
 CDS_LIB='pure_quanta',
 CDS_PART_NAME='Q_RES_0402LF-8.87K,1%,1/16W,EMPTY,CS28872FB01',
 PART_NUMBER='CS28872FB01',
 VALUE='8.87K',
 PRIM_FILE='./archive_libs/logical/q_res/chips/chips.prt';

PART_NAME
 PR354 'Q_RES_0402LF-5.6,1%,1/16W,CHIP,CS-5602FB01':;

SECTION_NUMBER 1
 '@T6G_MB_LIB.T6G(SCH_1):PAGE171_I45@PURE_QUANTA.Q_RES(CHIPS)':
 C_PATH='@t6g_mb_lib.t6g(sch_1):page171_i45@pure_quanta.q_res(chips)',
 P_PATH='@t6g_mb_lib.t6g(sch_1):page196_i45@pure_quanta.q_res(chips)',
 PATH='I45',
 DRAWING='@T6G_MB_LIB.T6G(SCH_1):PAGE171',
 WATTAGE='1/16W',
 TOLERANCE='1%',
 MATERIAL='CHIP',
 PHYS_PAGE='196',
 XY='(-4275,4925)',
 ROT='0',
 VER='1',
 PACK_TYPE='0402LF',
 LOCATION='PR354',
 CDS_LIB='pure_quanta',
 CDS_PART_NAME='Q_RES_0402LF-5.6,1%,1/16W,CHIP,CS-5602FB01',
 PART_NUMBER='CS-5602FB01',
 VALUE='5.6',
 PRIM_FILE='./archive_libs/logical/q_res/chips/chips.prt';

PART_NAME
 PR355 'Q_RES_0402LF-0,5%,1/16W,CHIP,CS00002JB13':;

SECTION_NUMBER 1
 '@T6G_MB_LIB.T6G(SCH_1):PAGE171_I32@PURE_QUANTA.Q_RES(CHIPS)':
 C_PATH='@t6g_mb_lib.t6g(sch_1):page171_i32@pure_quanta.q_res(chips)',
 P_PATH='@t6g_mb_lib.t6g(sch_1):page196_i32@pure_quanta.q_res(chips)',
 PATH='I32',
 DRAWING='@T6G_MB_LIB.T6G(SCH_1):PAGE171',
 WATTAGE='1/16W',
 TOLERANCE='5%',
 MATERIAL='CHIP',
 PHYS_PAGE='196',
 XY='(-3625,3625)',
 ROT='0',
 VER='1',
 PACK_TYPE='0402LF',
 LOCATION='PR355',
 CDS_LIB='pure_quanta',
 CDS_PART_NAME='Q_RES_0402LF-0,5%,1/16W,CHIP,CS00002JB13',
 PART_NUMBER='CS00002JB13',
 VALUE='0',
 PRIM_FILE='./archive_libs/logical/q_res/chips/chips.prt';

PART_NAME
 PR356 'Q_RES_0402LF-2.2,1%,1/16W,CHIP,CS-2202FB01':;

SECTION_NUMBER 1
 '@T6G_MB_LIB.T6G(SCH_1):PAGE173_I38@PURE_QUANTA.Q_RES(CHIPS)':
 C_PATH='@t6g_mb_lib.t6g(sch_1):page173_i38@pure_quanta.q_res(chips)',
 P_PATH='@t6g_mb_lib.t6g(sch_1):page198_i38@pure_quanta.q_res(chips)',
 PATH='I38',
 DRAWING='@T6G_MB_LIB.T6G(SCH_1):PAGE173',
 WATTAGE='1/16W',
 TOLERANCE='1%',
 MATERIAL='CHIP',
 PHYS_PAGE='198',
 XY='(-7325,5925)',
 ROT='0',
 VER='2',
 PACK_TYPE='0402LF',
 LOCATION='PR356',
 CDS_LIB='pure_quanta',
 CDS_PART_NAME='Q_RES_0402LF-2.2,1%,1/16W,CHIP,CS-2202FB01',
 PART_NUMBER='CS-2202FB01',
 VALUE='2.2',
 PRIM_FILE='./archive_libs/logical/q_res/chips/chips.prt';

PART_NAME
 PR357 'Q_RES_0402LF-2.2,1%,1/16W,CHIP,CS-2202FB01':;

SECTION_NUMBER 1
 '@T6G_MB_LIB.T6G(SCH_1):PAGE173_I12@PURE_QUANTA.Q_RES(CHIPS)':
 C_PATH='@t6g_mb_lib.t6g(sch_1):page173_i12@pure_quanta.q_res(chips)',
 P_PATH='@t6g_mb_lib.t6g(sch_1):page198_i12@pure_quanta.q_res(chips)',
 PATH='I12',
 DRAWING='@T6G_MB_LIB.T6G(SCH_1):PAGE173',
 WATTAGE='1/16W',
 TOLERANCE='1%',
 MATERIAL='CHIP',
 PHYS_PAGE='198',
 XY='(-7300,2850)',
 ROT='0',
 VER='2',
 PACK_TYPE='0402LF',
 LOCATION='PR357',
 CDS_LIB='pure_quanta',
 CDS_PART_NAME='Q_RES_0402LF-2.2,1%,1/16W,CHIP,CS-2202FB01',
 PART_NUMBER='CS-2202FB01',
 VALUE='2.2',
 PRIM_FILE='./archive_libs/logical/q_res/chips/chips.prt';

PART_NAME
 PR358 'Q_RES_0402LF-8.87K,1%,1/16W,EMPTY,CS28872FB01':;

SECTION_NUMBER 1
 '@T6G_MB_LIB.T6G(SCH_1):PAGE173_I32@PURE_QUANTA.Q_RES(CHIPS)':
 C_PATH='@t6g_mb_lib.t6g(sch_1):page173_i32@pure_quanta.q_res(chips)',
 P_PATH='@t6g_mb_lib.t6g(sch_1):page198_i32@pure_quanta.q_res(chips)',
 PATH='I32',
 DRAWING='@T6G_MB_LIB.T6G(SCH_1):PAGE173',
 WATTAGE='1/16W',
 TOLERANCE='1%',
 MATERIAL='EMPTY',
 PHYS_PAGE='198',
 XY='(-7000,4775)',
 ROT='0',
 VER='1',
 PACK_TYPE='0402LF',
 LOCATION='PR358',
 CDS_LIB='pure_quanta',
 CDS_PART_NAME='Q_RES_0402LF-8.87K,1%,1/16W,EMPTY,CS28872FB01',
 PART_NUMBER='CS28872FB01',
 VALUE='8.87K',
 PRIM_FILE='./archive_libs/logical/q_res/chips/chips.prt';

PART_NAME
 PR359 'Q_RES_0402LF-8.87K,1%,1/16W,EMPTY,CS28872FB01':;

SECTION_NUMBER 1
 '@T6G_MB_LIB.T6G(SCH_1):PAGE173_I8@PURE_QUANTA.Q_RES(CHIPS)':
 C_PATH='@t6g_mb_lib.t6g(sch_1):page173_i8@pure_quanta.q_res(chips)',
 P_PATH='@t6g_mb_lib.t6g(sch_1):page198_i8@pure_quanta.q_res(chips)',
 PATH='I8',
 DRAWING='@T6G_MB_LIB.T6G(SCH_1):PAGE173',
 WATTAGE='1/16W',
 TOLERANCE='1%',
 MATERIAL='EMPTY',
 PHYS_PAGE='198',
 XY='(-6950,1675)',
 ROT='0',
 VER='1',
 PACK_TYPE='0402LF',
 LOCATION='PR359',
 CDS_LIB='pure_quanta',
 CDS_PART_NAME='Q_RES_0402LF-8.87K,1%,1/16W,EMPTY,CS28872FB01',
 PART_NUMBER='CS28872FB01',
 VALUE='8.87K',
 PRIM_FILE='./archive_libs/logical/q_res/chips/chips.prt';

PART_NAME
 PR360 'Q_RES_0402LF-5.6,1%,1/16W,CHIP,CS-5602FB01':;

SECTION_NUMBER 1
 '@T6G_MB_LIB.T6G(SCH_1):PAGE173_I48@PURE_QUANTA.Q_RES(CHIPS)':
 C_PATH='@t6g_mb_lib.t6g(sch_1):page173_i48@pure_quanta.q_res(chips)',
 P_PATH='@t6g_mb_lib.t6g(sch_1):page198_i48@pure_quanta.q_res(chips)',
 PATH='I48',
 DRAWING='@T6G_MB_LIB.T6G(SCH_1):PAGE173',
 WATTAGE='1/16W',
 TOLERANCE='1%',
 MATERIAL='CHIP',
 PHYS_PAGE='198',
 XY='(-4525,5425)',
 ROT='0',
 VER='1',
 PACK_TYPE='0402LF',
 LOCATION='PR360',
 CDS_LIB='pure_quanta',
 CDS_PART_NAME='Q_RES_0402LF-5.6,1%,1/16W,CHIP,CS-5602FB01',
 PART_NUMBER='CS-5602FB01',
 VALUE='5.6',
 PRIM_FILE='./archive_libs/logical/q_res/chips/chips.prt';

PART_NAME
 PR361 'Q_RES_0402LF-5.6,1%,1/16W,CHIP,CS-5602FB01':;

SECTION_NUMBER 1
 '@T6G_MB_LIB.T6G(SCH_1):PAGE173_I22@PURE_QUANTA.Q_RES(CHIPS)':
 C_PATH='@t6g_mb_lib.t6g(sch_1):page173_i22@pure_quanta.q_res(chips)',
 P_PATH='@t6g_mb_lib.t6g(sch_1):page198_i22@pure_quanta.q_res(chips)',
 PATH='I22',
 DRAWING='@T6G_MB_LIB.T6G(SCH_1):PAGE173',
 WATTAGE='1/16W',
 TOLERANCE='1%',
 MATERIAL='CHIP',
 PHYS_PAGE='198',
 XY='(-4475,2325)',
 ROT='0',
 VER='1',
 PACK_TYPE='0402LF',
 LOCATION='PR361',
 CDS_LIB='pure_quanta',
 CDS_PART_NAME='Q_RES_0402LF-5.6,1%,1/16W,CHIP,CS-5602FB01',
 PART_NUMBER='CS-5602FB01',
 VALUE='5.6',
 PRIM_FILE='./archive_libs/logical/q_res/chips/chips.prt';

PART_NAME
 PR362 'Q_RES_0402LF-0,5%,1/16W,CHIP,CS00002JB13':;

SECTION_NUMBER 1
 '@T6G_MB_LIB.T6G(SCH_1):PAGE173_I27@PURE_QUANTA.Q_RES(CHIPS)':
 C_PATH='@t6g_mb_lib.t6g(sch_1):page173_i27@pure_quanta.q_res(chips)',
 P_PATH='@t6g_mb_lib.t6g(sch_1):page198_i27@pure_quanta.q_res(chips)',
 PATH='I27',
 DRAWING='@T6G_MB_LIB.T6G(SCH_1):PAGE173',
 WATTAGE='1/16W',
 TOLERANCE='5%',
 MATERIAL='CHIP',
 PHYS_PAGE='198',
 XY='(-4000,3900)',
 ROT='0',
 VER='1',
 PACK_TYPE='0402LF',
 LOCATION='PR362',
 CDS_LIB='pure_quanta',
 CDS_PART_NAME='Q_RES_0402LF-0,5%,1/16W,CHIP,CS00002JB13',
 PART_NUMBER='CS00002JB13',
 VALUE='0',
 PRIM_FILE='./archive_libs/logical/q_res/chips/chips.prt';

PART_NAME
 PR363 'Q_RES_0402LF-0,5%,1/16W,CHIP,CS00002JB13':;

SECTION_NUMBER 1
 '@T6G_MB_LIB.T6G(SCH_1):PAGE173_I18@PURE_QUANTA.Q_RES(CHIPS)':
 C_PATH='@t6g_mb_lib.t6g(sch_1):page173_i18@pure_quanta.q_res(chips)',
 P_PATH='@t6g_mb_lib.t6g(sch_1):page198_i18@pure_quanta.q_res(chips)',
 PATH='I18',
 DRAWING='@T6G_MB_LIB.T6G(SCH_1):PAGE173',
 WATTAGE='1/16W',
 TOLERANCE='5%',
 MATERIAL='CHIP',
 PHYS_PAGE='198',
 XY='(-4025,975)',
 ROT='0',
 VER='1',
 PACK_TYPE='0402LF',
 LOCATION='PR363',
 CDS_LIB='pure_quanta',
 CDS_PART_NAME='Q_RES_0402LF-0,5%,1/16W,CHIP,CS00002JB13',
 PART_NUMBER='CS00002JB13',
 VALUE='0',
 PRIM_FILE='./archive_libs/logical/q_res/chips/chips.prt';

PART_NAME
 PR364 'Q_RES_0402LF-2.2,1%,1/16W,CHIP,CS-2202FB01':;

SECTION_NUMBER 1
 '@T6G_MB_LIB.T6G(SCH_1):PAGE174_I15@PURE_QUANTA.Q_RES(CHIPS)':
 C_PATH='@t6g_mb_lib.t6g(sch_1):page174_i15@pure_quanta.q_res(chips)',
 P_PATH='@t6g_mb_lib.t6g(sch_1):page199_i15@pure_quanta.q_res(chips)',
 PATH='I15',
 DRAWING='@T6G_MB_LIB.T6G(SCH_1):PAGE174',
 WATTAGE='1/16W',
 TOLERANCE='1%',
 MATERIAL='CHIP',
 PHYS_PAGE='199',
 XY='(-7225,5050)',
 ROT='0',
 VER='2',
 PACK_TYPE='0402LF',
 LOCATION='PR364',
 CDS_LIB='pure_quanta',
 CDS_PART_NAME='Q_RES_0402LF-2.2,1%,1/16W,CHIP,CS-2202FB01',
 PART_NUMBER='CS-2202FB01',
 VALUE='2.2',
 PRIM_FILE='./archive_libs/logical/q_res/chips/chips.prt';

PART_NAME
 PR365 'Q_RES_0402LF-8.87K,1%,1/16W,EMPTY,CS28872FB01':;

SECTION_NUMBER 1
 '@T6G_MB_LIB.T6G(SCH_1):PAGE174_I7@PURE_QUANTA.Q_RES(CHIPS)':
 C_PATH='@t6g_mb_lib.t6g(sch_1):page174_i7@pure_quanta.q_res(chips)',
 P_PATH='@t6g_mb_lib.t6g(sch_1):page199_i7@pure_quanta.q_res(chips)',
 PATH='I7',
 DRAWING='@T6G_MB_LIB.T6G(SCH_1):PAGE174',
 WATTAGE='1/16W',
 TOLERANCE='1%',
 MATERIAL='EMPTY',
 PHYS_PAGE='199',
 XY='(-6900,3925)',
 ROT='0',
 VER='1',
 PACK_TYPE='0402LF',
 LOCATION='PR365',
 CDS_LIB='pure_quanta',
 CDS_PART_NAME='Q_RES_0402LF-8.87K,1%,1/16W,EMPTY,CS28872FB01',
 PART_NUMBER='CS28872FB01',
 VALUE='8.87K',
 PRIM_FILE='./archive_libs/logical/q_res/chips/chips.prt';

PART_NAME
 PR366 'Q_RES_0402LF-5.6,1%,1/16W,CHIP,CS-5602FB01':;

SECTION_NUMBER 1
 '@T6G_MB_LIB.T6G(SCH_1):PAGE174_I20@PURE_QUANTA.Q_RES(CHIPS)':
 C_PATH='@t6g_mb_lib.t6g(sch_1):page174_i20@pure_quanta.q_res(chips)',
 P_PATH='@t6g_mb_lib.t6g(sch_1):page199_i20@pure_quanta.q_res(chips)',
 PATH='I20',
 DRAWING='@T6G_MB_LIB.T6G(SCH_1):PAGE174',
 WATTAGE='1/16W',
 TOLERANCE='1%',
 MATERIAL='CHIP',
 PHYS_PAGE='199',
 XY='(-4425,4575)',
 ROT='0',
 VER='1',
 PACK_TYPE='0402LF',
 LOCATION='PR366',
 CDS_LIB='pure_quanta',
 CDS_PART_NAME='Q_RES_0402LF-5.6,1%,1/16W,CHIP,CS-5602FB01',
 PART_NUMBER='CS-5602FB01',
 VALUE='5.6',
 PRIM_FILE='./archive_libs/logical/q_res/chips/chips.prt';

PART_NAME
 PR367 'Q_RES_0402LF-0,5%,1/16W,CHIP,CS00002JB13':;

SECTION_NUMBER 1
 '@T6G_MB_LIB.T6G(SCH_1):PAGE174_I11@PURE_QUANTA.Q_RES(CHIPS)':
 C_PATH='@t6g_mb_lib.t6g(sch_1):page174_i11@pure_quanta.q_res(chips)',
 P_PATH='@t6g_mb_lib.t6g(sch_1):page199_i11@pure_quanta.q_res(chips)',
 PATH='I11',
 DRAWING='@T6G_MB_LIB.T6G(SCH_1):PAGE174',
 WATTAGE='1/16W',
 TOLERANCE='5%',
 MATERIAL='CHIP',
 PHYS_PAGE='199',
 XY='(-3950,3275)',
 ROT='0',
 VER='1',
 PACK_TYPE='0402LF',
 LOCATION='PR367',
 CDS_LIB='pure_quanta',
 CDS_PART_NAME='Q_RES_0402LF-0,5%,1/16W,CHIP,CS00002JB13',
 PART_NUMBER='CS00002JB13',
 VALUE='0',
 PRIM_FILE='./archive_libs/logical/q_res/chips/chips.prt';

PART_NAME
 PR368 'Q_RES_0402LF-8.87K,1%,1/16W,EMPTY,CS28872FB01':;

SECTION_NUMBER 1
 '@T6G_MB_LIB.T6G(SCH_1):PAGE198_I4@PURE_QUANTA.Q_RES(CHIPS)':
 C_PATH='@t6g_mb_lib.t6g(sch_1):page198_i4@pure_quanta.q_res(chips)',
 P_PATH='@t6g_mb_lib.t6g(sch_1):page223_i4@pure_quanta.q_res(chips)',
 PATH='I4',
 DRAWING='@T6G_MB_LIB.T6G(SCH_1):PAGE198',
 WATTAGE='1/16W',
 TOLERANCE='1%',
 MATERIAL='EMPTY',
 PHYS_PAGE='223',
 XY='(-11375,1800)',
 ROT='2',
 VER='2',
 PACK_TYPE='0402LF',
 LOCATION='PR368',
 CDS_LIB='pure_quanta',
 CDS_PART_NAME='Q_RES_0402LF-8.87K,1%,1/16W,EMPTY,CS28872FB01',
 PART_NUMBER='CS28872FB01',
 VALUE='8.87K',
 PRIM_FILE='./archive_libs/logical/q_res/chips/chips.prt';

PART_NAME
 PR369 'Q_RES_0402LF-8.87K,1%,1/16W,EMPTY,CS28872FB01':;

SECTION_NUMBER 1
 '@T6G_MB_LIB.T6G(SCH_1):PAGE198_I22@PURE_QUANTA.Q_RES(CHIPS)':
 C_PATH='@t6g_mb_lib.t6g(sch_1):page198_i22@pure_quanta.q_res(chips)',
 P_PATH='@t6g_mb_lib.t6g(sch_1):page223_i22@pure_quanta.q_res(chips)',
 PATH='I22',
 DRAWING='@T6G_MB_LIB.T6G(SCH_1):PAGE198',
 WATTAGE='1/16W',
 TOLERANCE='1%',
 MATERIAL='EMPTY',
 PHYS_PAGE='223',
 XY='(-11350,4650)',
 ROT='2',
 VER='2',
 PACK_TYPE='0402LF',
 LOCATION='PR369',
 CDS_LIB='pure_quanta',
 CDS_PART_NAME='Q_RES_0402LF-8.87K,1%,1/16W,EMPTY,CS28872FB01',
 PART_NUMBER='CS28872FB01',
 VALUE='8.87K',
 PRIM_FILE='./archive_libs/logical/q_res/chips/chips.prt';

PART_NAME
 PR370 'Q_RES_0402LF-2.2,1%,1/16W,CHIP,CS-2202FB01':;

SECTION_NUMBER 1
 '@T6G_MB_LIB.T6G(SCH_1):PAGE198_I12@PURE_QUANTA.Q_RES(CHIPS)':
 C_PATH='@t6g_mb_lib.t6g(sch_1):page198_i12@pure_quanta.q_res(chips)',
 P_PATH='@t6g_mb_lib.t6g(sch_1):page223_i12@pure_quanta.q_res(chips)',
 PATH='I12',
 DRAWING='@T6G_MB_LIB.T6G(SCH_1):PAGE198',
 WATTAGE='1/16W',
 TOLERANCE='1%',
 MATERIAL='CHIP',
 PHYS_PAGE='223',
 XY='(-11050,3250)',
 ROT='0',
 VER='2',
 PACK_TYPE='0402LF',
 LOCATION='PR370',
 CDS_LIB='pure_quanta',
 CDS_PART_NAME='Q_RES_0402LF-2.2,1%,1/16W,CHIP,CS-2202FB01',
 PART_NUMBER='CS-2202FB01',
 VALUE='2.2',
 PRIM_FILE='./archive_libs/logical/q_res/chips/chips.prt';

PART_NAME
 PR371 'Q_RES_0402LF-2.2,1%,1/16W,CHIP,CS-2202FB01':;

SECTION_NUMBER 1
 '@T6G_MB_LIB.T6G(SCH_1):PAGE198_I29@PURE_QUANTA.Q_RES(CHIPS)':
 C_PATH='@t6g_mb_lib.t6g(sch_1):page198_i29@pure_quanta.q_res(chips)',
 P_PATH='@t6g_mb_lib.t6g(sch_1):page223_i29@pure_quanta.q_res(chips)',
 PATH='I29',
 DRAWING='@T6G_MB_LIB.T6G(SCH_1):PAGE198',
 WATTAGE='1/16W',
 TOLERANCE='1%',
 MATERIAL='CHIP',
 PHYS_PAGE='223',
 XY='(-11025,5950)',
 ROT='0',
 VER='2',
 PACK_TYPE='0402LF',
 LOCATION='PR371',
 CDS_LIB='pure_quanta',
 CDS_PART_NAME='Q_RES_0402LF-2.2,1%,1/16W,CHIP,CS-2202FB01',
 PART_NUMBER='CS-2202FB01',
 VALUE='2.2',
 PRIM_FILE='./archive_libs/logical/q_res/chips/chips.prt';

PART_NAME
 PR372 'Q_RES_0402LF-5.6,1%,1/16W,CHIP,CS-5602FB01':;

SECTION_NUMBER 1
 '@T6G_MB_LIB.T6G(SCH_1):PAGE198_I17@PURE_QUANTA.Q_RES(CHIPS)':
 C_PATH='@t6g_mb_lib.t6g(sch_1):page198_i17@pure_quanta.q_res(chips)',
 P_PATH='@t6g_mb_lib.t6g(sch_1):page223_i17@pure_quanta.q_res(chips)',
 PATH='I17',
 DRAWING='@T6G_MB_LIB.T6G(SCH_1):PAGE198',
 WATTAGE='1/16W',
 TOLERANCE='1%',
 MATERIAL='CHIP',
 PHYS_PAGE='223',
 XY='(-8050,2650)',
 ROT='0',
 VER='1',
 PACK_TYPE='0402LF',
 LOCATION='PR372',
 CDS_LIB='pure_quanta',
 CDS_PART_NAME='Q_RES_0402LF-5.6,1%,1/16W,CHIP,CS-5602FB01',
 PART_NUMBER='CS-5602FB01',
 VALUE='5.6',
 PRIM_FILE='./archive_libs/logical/q_res/chips/chips.prt';

PART_NAME
 PR373 'Q_RES_0402LF-5.6,1%,1/16W,CHIP,CS-5602FB01':;

SECTION_NUMBER 1
 '@T6G_MB_LIB.T6G(SCH_1):PAGE198_I34@PURE_QUANTA.Q_RES(CHIPS)':
 C_PATH='@t6g_mb_lib.t6g(sch_1):page198_i34@pure_quanta.q_res(chips)',
 P_PATH='@t6g_mb_lib.t6g(sch_1):page223_i34@pure_quanta.q_res(chips)',
 PATH='I34',
 DRAWING='@T6G_MB_LIB.T6G(SCH_1):PAGE198',
 WATTAGE='1/16W',
 TOLERANCE='1%',
 MATERIAL='CHIP',
 PHYS_PAGE='223',
 XY='(-7975,5450)',
 ROT='0',
 VER='1',
 PACK_TYPE='0402LF',
 LOCATION='PR373',
 CDS_LIB='pure_quanta',
 CDS_PART_NAME='Q_RES_0402LF-5.6,1%,1/16W,CHIP,CS-5602FB01',
 PART_NUMBER='CS-5602FB01',
 VALUE='5.6',
 PRIM_FILE='./archive_libs/logical/q_res/chips/chips.prt';

PART_NAME
 PR374 'Q_RES_0402LF-0,5%,1/16W,CHIP,CS00002JB13':;

SECTION_NUMBER 1
 '@T6G_MB_LIB.T6G(SCH_1):PAGE198_I55@PURE_QUANTA.Q_RES(CHIPS)':
 C_PATH='@t6g_mb_lib.t6g(sch_1):page198_i55@pure_quanta.q_res(chips)',
 P_PATH='@t6g_mb_lib.t6g(sch_1):page223_i55@pure_quanta.q_res(chips)',
 PATH='I55',
 DRAWING='@T6G_MB_LIB.T6G(SCH_1):PAGE198',
 WATTAGE='1/16W',
 TOLERANCE='5%',
 MATERIAL='CHIP',
 PHYS_PAGE='223',
 XY='(-6950,4075)',
 ROT='0',
 VER='1',
 PACK_TYPE='0402LF',
 LOCATION='PR374',
 CDS_LIB='pure_quanta',
 CDS_PART_NAME='Q_RES_0402LF-0,5%,1/16W,CHIP,CS00002JB13',
 PART_NUMBER='CS00002JB13',
 VALUE='0',
 PRIM_FILE='./archive_libs/logical/q_res/chips/chips.prt';

PART_NAME
 PR375 'Q_RES_0402LF-0,5%,1/16W,CHIP,CS00002JB13':;

SECTION_NUMBER 1
 '@T6G_MB_LIB.T6G(SCH_1):PAGE198_I41@PURE_QUANTA.Q_RES(CHIPS)':
 C_PATH='@t6g_mb_lib.t6g(sch_1):page198_i41@pure_quanta.q_res(chips)',
 P_PATH='@t6g_mb_lib.t6g(sch_1):page223_i41@pure_quanta.q_res(chips)',
 PATH='I41',
 DRAWING='@T6G_MB_LIB.T6G(SCH_1):PAGE198',
 WATTAGE='1/16W',
 TOLERANCE='5%',
 MATERIAL='CHIP',
 PHYS_PAGE='223',
 XY='(-6750,1275)',
 ROT='0',
 VER='1',
 PACK_TYPE='0402LF',
 LOCATION='PR375',
 CDS_LIB='pure_quanta',
 CDS_PART_NAME='Q_RES_0402LF-0,5%,1/16W,CHIP,CS00002JB13',
 PART_NUMBER='CS00002JB13',
 VALUE='0',
 PRIM_FILE='./archive_libs/logical/q_res/chips/chips.prt';

PART_NAME
 PR376 'Q_RES_0402LF-40.2K,1%,1/16W,CHIP,CS34022FB04':;

SECTION_NUMBER 1
 '@T6G_MB_LIB.T6G(SCH_1):PAGE199_I2@PURE_QUANTA.Q_RES(CHIPS)':
 C_PATH='@t6g_mb_lib.t6g(sch_1):page199_i2@pure_quanta.q_res(chips)',
 P_PATH='@t6g_mb_lib.t6g(sch_1):page224_i2@pure_quanta.q_res(chips)',
 PATH='I2',
 DRAWING='@T6G_MB_LIB.T6G(SCH_1):PAGE199',
 WATTAGE='1/16W',
 TOLERANCE='1%',
 MATERIAL='CHIP',
 PHYS_PAGE='224',
 XY='(-7275,850)',
 ROT='0',
 VER='1',
 PACK_TYPE='0402LF',
 LOCATION='PR376',
 CDS_LIB='pure_quanta',
 CDS_PART_NAME='Q_RES_0402LF-40.2K,1%,1/16W,CHIP,CS34022FB04',
 PART_NUMBER='CS34022FB04',
 VALUE='40.2K',
 PRIM_FILE='./archive_libs/logical/q_res/chips/chips.prt';

PART_NAME
 PR378 'Q_RES_0402LF-1K,1%,1/16W,CHIP,CS21002FB06':;

SECTION_NUMBER 1
 '@T6G_MB_LIB.T6G(SCH_1):PAGE197_I81@PURE_QUANTA.Q_RES(CHIPS)':
 C_PATH='@t6g_mb_lib.t6g(sch_1):page197_i81@pure_quanta.q_res(chips)',
 P_PATH='@t6g_mb_lib.t6g(sch_1):page222_i81@pure_quanta.q_res(chips)',
 PATH='I81',
 DRAWING='@T6G_MB_LIB.T6G(SCH_1):PAGE197',
 WATTAGE='1/16W',
 TOLERANCE='1%',
 MATERIAL='CHIP',
 PHYS_PAGE='222',
 XY='(8250,4800)',
 ROT='0',
 VER='2',
 PACK_TYPE='0402LF',
 LOCATION='PR378',
 CDS_LIB='pure_quanta',
 CDS_PART_NAME='Q_RES_0402LF-1K,1%,1/16W,CHIP,CS21002FB06',
 PART_NUMBER='CS21002FB06',
 VALUE='1K',
 PRIM_FILE='./archive_libs/logical/q_res/chips/chips.prt';

PART_NAME
 PR379 'Q_RES_0402LF-1.5,1%,1/8W,EMPTY,CS-1504FB00':;

SECTION_NUMBER 1
 '@T6G_MB_LIB.T6G(SCH_1):PAGE181_I55@PURE_QUANTA.Q_RES(CHIPS)':
 C_PATH='@t6g_mb_lib.t6g(sch_1):page181_i55@pure_quanta.q_res(chips)',
 P_PATH='@t6g_mb_lib.t6g(sch_1):page206_i55@pure_quanta.q_res(chips)',
 PATH='I55',
 DRAWING='@T6G_MB_LIB.T6G(SCH_1):PAGE181',
 WATTAGE='1/8W',
 TOLERANCE='1%',
 MATERIAL='EMPTY',
 PHYS_PAGE='206',
 XY='(-7950,4700)',
 ROT='0',
 VER='2',
 PACK_TYPE='0402LF',
 LOCATION='PR379',
 CDS_LIB='pure_quanta',
 CDS_PART_NAME='Q_RES_0402LF-1.5,1%,1/8W,EMPTY,CS-1504FB00',
 PART_NUMBER='CS-1504FB00',
 VALUE='1.5',
 PRIM_FILE='./archive_libs/logical/q_res/chips/chips.prt';

PART_NAME
 PR384 'Q_RES_0402LF-0,5%,1/16W,CHIP,CS00002JB13':;

SECTION_NUMBER 1
 '@T6G_MB_LIB.T6G(SCH_1):PAGE199_I27@PURE_QUANTA.Q_RES(CHIPS)':
 C_PATH='@t6g_mb_lib.t6g(sch_1):page199_i27@pure_quanta.q_res(chips)',
 P_PATH='@t6g_mb_lib.t6g(sch_1):page224_i27@pure_quanta.q_res(chips)',
 PATH='I27',
 DRAWING='@T6G_MB_LIB.T6G(SCH_1):PAGE199',
 WATTAGE='1/16W',
 TOLERANCE='5%',
 MATERIAL='CHIP',
 PHYS_PAGE='224',
 XY='(-6050,4075)',
 ROT='0',
 VER='1',
 PACK_TYPE='0402LF',
 LOCATION='PR384',
 CDS_LIB='pure_quanta',
 CDS_PART_NAME='Q_RES_0402LF-0,5%,1/16W,CHIP,CS00002JB13',
 PART_NUMBER='CS00002JB13',
 VALUE='0',
 PRIM_FILE='./archive_libs/logical/q_res/chips/chips.prt';

PART_NAME
 PR387 'Q_RES_0402LF-0,5%,1/16W,CHIP,CS00002JB13':;

SECTION_NUMBER 1
 '@T6G_MB_LIB.T6G(SCH_1):PAGE200_I3@PURE_QUANTA.Q_RES(CHIPS)':
 C_PATH='@t6g_mb_lib.t6g(sch_1):page200_i3@pure_quanta.q_res(chips)',
 P_PATH='@t6g_mb_lib.t6g(sch_1):page225_i3@pure_quanta.q_res(chips)',
 PATH='I3',
 DRAWING='@T6G_MB_LIB.T6G(SCH_1):PAGE200',
 WATTAGE='1/16W',
 TOLERANCE='5%',
 MATERIAL='CHIP',
 PHYS_PAGE='225',
 XY='(-8425,5900)',
 ROT='1',
 VER='1',
 PACK_TYPE='0402LF',
 LOCATION='PR387',
 CDS_LIB='pure_quanta',
 CDS_PART_NAME='Q_RES_0402LF-0,5%,1/16W,CHIP,CS00002JB13',
 PART_NUMBER='CS00002JB13',
 VALUE='0',
 PRIM_FILE='./archive_libs/logical/q_res/chips/chips.prt';

PART_NAME
 PR388 'Q_RES_0402LF-0,5%,1/16W,CHIP,CS00002JB13':;

SECTION_NUMBER 1
 '@T6G_MB_LIB.T6G(SCH_1):PAGE199_I18@PURE_QUANTA.Q_RES(CHIPS)':
 C_PATH='@t6g_mb_lib.t6g(sch_1):page199_i18@pure_quanta.q_res(chips)',
 P_PATH='@t6g_mb_lib.t6g(sch_1):page224_i18@pure_quanta.q_res(chips)',
 PATH='I18',
 DRAWING='@T6G_MB_LIB.T6G(SCH_1):PAGE199',
 WATTAGE='1/16W',
 TOLERANCE='5%',
 MATERIAL='CHIP',
 PHYS_PAGE='224',
 XY='(-6050,675)',
 ROT='0',
 VER='1',
 PACK_TYPE='0402LF',
 LOCATION='PR388',
 CDS_LIB='pure_quanta',
 CDS_PART_NAME='Q_RES_0402LF-0,5%,1/16W,CHIP,CS00002JB13',
 PART_NUMBER='CS00002JB13',
 VALUE='0',
 PRIM_FILE='./archive_libs/logical/q_res/chips/chips.prt';

PART_NAME
 PR389 'Q_RES_0402LF-1.5,1%,1/8W,EMPTY,CS-1504FB00':;

SECTION_NUMBER 1
 '@T6G_MB_LIB.T6G(SCH_1):PAGE183_I24@PURE_QUANTA.Q_RES(CHIPS)':
 C_PATH='@t6g_mb_lib.t6g(sch_1):page183_i24@pure_quanta.q_res(chips)',
 P_PATH='@t6g_mb_lib.t6g(sch_1):page208_i24@pure_quanta.q_res(chips)',
 PATH='I24',
 DRAWING='@T6G_MB_LIB.T6G(SCH_1):PAGE183',
 WATTAGE='1/8W',
 TOLERANCE='1%',
 MATERIAL='EMPTY',
 PHYS_PAGE='208',
 XY='(-4550,825)',
 ROT='0',
 VER='2',
 PACK_TYPE='0402LF',
 LOCATION='PR389',
 CDS_LIB='pure_quanta',
 CDS_PART_NAME='Q_RES_0402LF-1.5,1%,1/8W,EMPTY,CS-1504FB00',
 PART_NUMBER='CS-1504FB00',
 VALUE='1.5',
 PRIM_FILE='./archive_libs/logical/q_res/chips/chips.prt';

PART_NAME
 PR390 'Q_RES_0402LF-0,5%,1/16W,EMPTY,CS00002JB13':;

SECTION_NUMBER 1
 '@T6G_MB_LIB.T6G(SCH_1):PAGE199_I56@PURE_QUANTA.Q_RES(CHIPS)':
 C_PATH='@t6g_mb_lib.t6g(sch_1):page199_i56@pure_quanta.q_res(chips)',
 P_PATH='@t6g_mb_lib.t6g(sch_1):page224_i56@pure_quanta.q_res(chips)',
 PATH='I56',
 DRAWING='@T6G_MB_LIB.T6G(SCH_1):PAGE199',
 WATTAGE='1/16W',
 TOLERANCE='5%',
 MATERIAL='EMPTY',
 PHYS_PAGE='224',
 XY='(-2125,1425)',
 ROT='0',
 VER='2',
 PACK_TYPE='0402LF',
 LOCATION='PR390',
 CDS_LIB='pure_quanta',
 CDS_PART_NAME='Q_RES_0402LF-0,5%,1/16W,EMPTY,CS00002JB13',
 PART_NUMBER='CS00002JB13',
 VALUE='0',
 PRIM_FILE='./archive_libs/logical/q_res/chips/chips.prt';

PART_NAME
 PR391 'Q_RES_0402LF-1K,1%,1/16W,EMPTY,CS21002FB06':;

SECTION_NUMBER 1
 '@T6G_MB_LIB.T6G(SCH_1):PAGE199_I67@PURE_QUANTA.Q_RES(CHIPS)':
 C_PATH='@t6g_mb_lib.t6g(sch_1):page199_i67@pure_quanta.q_res(chips)',
 P_PATH='@t6g_mb_lib.t6g(sch_1):page224_i67@pure_quanta.q_res(chips)',
 PATH='I67',
 DRAWING='@T6G_MB_LIB.T6G(SCH_1):PAGE199',
 WATTAGE='1/16W',
 TOLERANCE='1%',
 MATERIAL='EMPTY',
 PHYS_PAGE='224',
 XY='(-1700,1850)',
 ROT='0',
 VER='1',
 PACK_TYPE='0402LF',
 LOCATION='PR391',
 CDS_LIB='pure_quanta',
 CDS_PART_NAME='Q_RES_0402LF-1K,1%,1/16W,EMPTY,CS21002FB06',
 PART_NUMBER='CS21002FB06',
 VALUE='1K',
 PRIM_FILE='./archive_libs/logical/q_res/chips/chips.prt';

PART_NAME
 PR392 'Q_RES_0402LF-0,5%,1/16W,EMPTY,CS00002JB13':;

SECTION_NUMBER 1
 '@T6G_MB_LIB.T6G(SCH_1):PAGE199_I66@PURE_QUANTA.Q_RES(CHIPS)':
 C_PATH='@t6g_mb_lib.t6g(sch_1):page199_i66@pure_quanta.q_res(chips)',
 P_PATH='@t6g_mb_lib.t6g(sch_1):page224_i66@pure_quanta.q_res(chips)',
 PATH='I66',
 DRAWING='@T6G_MB_LIB.T6G(SCH_1):PAGE199',
 WATTAGE='1/16W',
 TOLERANCE='5%',
 MATERIAL='EMPTY',
 PHYS_PAGE='224',
 XY='(-1650,1625)',
 ROT='0',
 VER='1',
 PACK_TYPE='0402LF',
 LOCATION='PR392',
 CDS_LIB='pure_quanta',
 CDS_PART_NAME='Q_RES_0402LF-0,5%,1/16W,EMPTY,CS00002JB13',
 PART_NUMBER='CS00002JB13',
 VALUE='0',
 PRIM_FILE='./archive_libs/logical/q_res/chips/chips.prt';

PART_NAME
 PR393 'Q_RES_0402LF-1,1%,1/16W,CHIP,CS-1002FB04':;

SECTION_NUMBER 1
 '@T6G_MB_LIB.T6G(SCH_1):PAGE199_I84@PURE_QUANTA.Q_RES(CHIPS)':
 C_PATH='@t6g_mb_lib.t6g(sch_1):page199_i84@pure_quanta.q_res(chips)',
 P_PATH='@t6g_mb_lib.t6g(sch_1):page224_i84@pure_quanta.q_res(chips)',
 PATH='I84',
 DRAWING='@T6G_MB_LIB.T6G(SCH_1):PAGE199',
 WATTAGE='1/16W',
 TOLERANCE='1%',
 MATERIAL='CHIP',
 PHYS_PAGE='224',
 XY='(-2575,6300)',
 ROT='0',
 VER='1',
 PACK_TYPE='0402LF',
 LOCATION='PR393',
 CDS_LIB='pure_quanta',
 CDS_PART_NAME='Q_RES_0402LF-1,1%,1/16W,CHIP,CS-1002FB04',
 PART_NUMBER='CS-1002FB04',
 VALUE='1',
 PRIM_FILE='./archive_libs/logical/q_res/chips/chips.prt';

PART_NAME
 PR394 'Q_RES_0402LF-0,5%,1/16W,EMPTY,CS00002JB13':;

SECTION_NUMBER 1
 '@T6G_MB_LIB.T6G(SCH_1):PAGE200_I41@PURE_QUANTA.Q_RES(CHIPS)':
 C_PATH='@t6g_mb_lib.t6g(sch_1):page200_i41@pure_quanta.q_res(chips)',
 P_PATH='@t6g_mb_lib.t6g(sch_1):page225_i41@pure_quanta.q_res(chips)',
 PATH='I41',
 DRAWING='@T6G_MB_LIB.T6G(SCH_1):PAGE200',
 WATTAGE='1/16W',
 TOLERANCE='5%',
 MATERIAL='EMPTY',
 PHYS_PAGE='225',
 XY='(-8075,5900)',
 ROT='1',
 VER='1',
 PACK_TYPE='0402LF',
 LOCATION='PR394',
 CDS_LIB='pure_quanta',
 CDS_PART_NAME='Q_RES_0402LF-0,5%,1/16W,EMPTY,CS00002JB13',
 PART_NUMBER='CS00002JB13',
 VALUE='0',
 PRIM_FILE='./archive_libs/logical/q_res/chips/chips.prt';

PART_NAME
 PR395 'Q_RES_0402LF-1K,1%,1/16W,CHIP,CS21002FB06':;

SECTION_NUMBER 1
 '@T6G_MB_LIB.T6G(SCH_1):PAGE200_I89@PURE_QUANTA.Q_RES(CHIPS)':
 C_PATH='@t6g_mb_lib.t6g(sch_1):page200_i89@pure_quanta.q_res(chips)',
 P_PATH='@t6g_mb_lib.t6g(sch_1):page225_i89@pure_quanta.q_res(chips)',
 PATH='I89',
 DRAWING='@T6G_MB_LIB.T6G(SCH_1):PAGE200',
 WATTAGE='1/16W',
 TOLERANCE='1%',
 MATERIAL='CHIP',
 PHYS_PAGE='225',
 XY='(-1125,4425)',
 ROT='0',
 VER='2',
 PACK_TYPE='0402LF',
 LOCATION='PR395',
 CDS_LIB='pure_quanta',
 CDS_PART_NAME='Q_RES_0402LF-1K,1%,1/16W,CHIP,CS21002FB06',
 PART_NUMBER='CS21002FB06',
 VALUE='1K',
 PRIM_FILE='./archive_libs/logical/q_res/chips/chips.prt';

PART_NAME
 PR397 'Q_RES_0402LF-0,5%,1/16W,CHIP,CS00002JB13':;

SECTION_NUMBER 1
 '@T6G_MB_LIB.T6G(SCH_1):PAGE201_I12@PURE_QUANTA.Q_RES(CHIPS)':
 C_PATH='@t6g_mb_lib.t6g(sch_1):page201_i12@pure_quanta.q_res(chips)',
 P_PATH='@t6g_mb_lib.t6g(sch_1):page226_i12@pure_quanta.q_res(chips)',
 PATH='I12',
 DRAWING='@T6G_MB_LIB.T6G(SCH_1):PAGE201',
 WATTAGE='1/16W',
 TOLERANCE='5%',
 MATERIAL='CHIP',
 PHYS_PAGE='226',
 XY='(-6875,3400)',
 ROT='0',
 VER='2',
 PACK_TYPE='0402LF',
 LOCATION='PR397',
 CDS_LIB='pure_quanta',
 CDS_PART_NAME='Q_RES_0402LF-0,5%,1/16W,CHIP,CS00002JB13',
 PART_NUMBER='CS00002JB13',
 VALUE='0',
 PRIM_FILE='./archive_libs/logical/q_res/chips/chips.prt';

PART_NAME
 PR398 'Q_RES_0402LF-0,5%,1/16W,CHIP,CS00002JB13':;

SECTION_NUMBER 1
 '@T6G_MB_LIB.T6G(SCH_1):PAGE201_I14@PURE_QUANTA.Q_RES(CHIPS)':
 C_PATH='@t6g_mb_lib.t6g(sch_1):page201_i14@pure_quanta.q_res(chips)',
 P_PATH='@t6g_mb_lib.t6g(sch_1):page226_i14@pure_quanta.q_res(chips)',
 PATH='I14',
 DRAWING='@T6G_MB_LIB.T6G(SCH_1):PAGE201',
 WATTAGE='1/16W',
 TOLERANCE='5%',
 MATERIAL='CHIP',
 PHYS_PAGE='226',
 XY='(-6850,3800)',
 ROT='0',
 VER='1',
 PACK_TYPE='0402LF',
 LOCATION='PR398',
 CDS_LIB='pure_quanta',
 CDS_PART_NAME='Q_RES_0402LF-0,5%,1/16W,CHIP,CS00002JB13',
 PART_NUMBER='CS00002JB13',
 VALUE='0',
 PRIM_FILE='./archive_libs/logical/q_res/chips/chips.prt';

PART_NAME
 PR399 'Q_RES_0402LF-49.9,1%,1/16W,CHIP,CS04992FB07':;

SECTION_NUMBER 1
 '@T6G_MB_LIB.T6G(SCH_1):PAGE201_I29@PURE_QUANTA.Q_RES(CHIPS)':
 C_PATH='@t6g_mb_lib.t6g(sch_1):page201_i29@pure_quanta.q_res(chips)',
 P_PATH='@t6g_mb_lib.t6g(sch_1):page226_i29@pure_quanta.q_res(chips)',
 PATH='I29',
 DRAWING='@T6G_MB_LIB.T6G(SCH_1):PAGE201',
 WATTAGE='1/16W',
 TOLERANCE='1%',
 MATERIAL='CHIP',
 PHYS_PAGE='226',
 XY='(-3300,2350)',
 ROT='1',
 VER='1',
 PACK_TYPE='0402LF',
 LOCATION='PR399',
 CDS_LIB='pure_quanta',
 CDS_PART_NAME='Q_RES_0402LF-49.9,1%,1/16W,CHIP,CS04992FB07',
 PART_NUMBER='CS04992FB07',
 VALUE='49.9',
 PRIM_FILE='./archive_libs/logical/q_res/chips/chips.prt';

PART_NAME
 PR400 'Q_RES_0402LF-10,1%,1/16W,CHIP,CS01002FB07':;

SECTION_NUMBER 1
 '@T6G_MB_LIB.T6G(SCH_1):PAGE201_I36@PURE_QUANTA.Q_RES(CHIPS)':
 C_PATH='@t6g_mb_lib.t6g(sch_1):page201_i36@pure_quanta.q_res(chips)',
 P_PATH='@t6g_mb_lib.t6g(sch_1):page226_i36@pure_quanta.q_res(chips)',
 PATH='I36',
 DRAWING='@T6G_MB_LIB.T6G(SCH_1):PAGE201',
 WATTAGE='1/16W',
 TOLERANCE='1%',
 MATERIAL='CHIP',
 PHYS_PAGE='226',
 XY='(-2150,2750)',
 ROT='0',
 VER='1',
 PACK_TYPE='0402LF',
 LOCATION='PR400',
 CDS_LIB='pure_quanta',
 CDS_PART_NAME='Q_RES_0402LF-10,1%,1/16W,CHIP,CS01002FB07',
 PART_NUMBER='CS01002FB07',
 VALUE='10',
 PRIM_FILE='./archive_libs/logical/q_res/chips/chips.prt';

PART_NAME
 PR401 'Q_RES_0402LF-0,5%,1/16W,CHIP,CS00002JB13':;

SECTION_NUMBER 1
 '@T6G_MB_LIB.T6G(SCH_1):PAGE201_I35@PURE_QUANTA.Q_RES(CHIPS)':
 C_PATH='@t6g_mb_lib.t6g(sch_1):page201_i35@pure_quanta.q_res(chips)',
 P_PATH='@t6g_mb_lib.t6g(sch_1):page226_i35@pure_quanta.q_res(chips)',
 PATH='I35',
 DRAWING='@T6G_MB_LIB.T6G(SCH_1):PAGE201',
 WATTAGE='1/16W',
 TOLERANCE='5%',
 MATERIAL='CHIP',
 PHYS_PAGE='226',
 XY='(-2150,2500)',
 ROT='1',
 VER='2',
 PACK_TYPE='0402LF',
 LOCATION='PR401',
 CDS_LIB='pure_quanta',
 CDS_PART_NAME='Q_RES_0402LF-0,5%,1/16W,CHIP,CS00002JB13',
 PART_NUMBER='CS00002JB13',
 VALUE='0',
 PRIM_FILE='./archive_libs/logical/q_res/chips/chips.prt';

PART_NAME
 PR402 'Q_RES_0402LF-49.9,1%,1/16W,CHIP,CS04992FB07':;

SECTION_NUMBER 1
 '@T6G_MB_LIB.T6G(SCH_1):PAGE201_I39@PURE_QUANTA.Q_RES(CHIPS)':
 C_PATH='@t6g_mb_lib.t6g(sch_1):page201_i39@pure_quanta.q_res(chips)',
 P_PATH='@t6g_mb_lib.t6g(sch_1):page226_i39@pure_quanta.q_res(chips)',
 PATH='I39',
 DRAWING='@T6G_MB_LIB.T6G(SCH_1):PAGE201',
 WATTAGE='1/16W',
 TOLERANCE='1%',
 MATERIAL='CHIP',
 PHYS_PAGE='226',
 XY='(-1450,3225)',
 ROT='2',
 VER='1',
 PACK_TYPE='0402LF',
 LOCATION='PR402',
 CDS_LIB='pure_quanta',
 CDS_PART_NAME='Q_RES_0402LF-49.9,1%,1/16W,CHIP,CS04992FB07',
 PART_NUMBER='CS04992FB07',
 VALUE='49.9',
 PRIM_FILE='./archive_libs/logical/q_res/chips/chips.prt';

PART_NAME
 PR403 'Q_RES_0402LF-1K,1%,1/16W,CHIP,CS21002FB06':;

SECTION_NUMBER 1
 '@T6G_MB_LIB.T6G(SCH_1):PAGE201_I50@PURE_QUANTA.Q_RES(CHIPS)':
 C_PATH='@t6g_mb_lib.t6g(sch_1):page201_i50@pure_quanta.q_res(chips)',
 P_PATH='@t6g_mb_lib.t6g(sch_1):page226_i50@pure_quanta.q_res(chips)',
 PATH='I50',
 DRAWING='@T6G_MB_LIB.T6G(SCH_1):PAGE201',
 WATTAGE='1/16W',
 TOLERANCE='1%',
 MATERIAL='CHIP',
 PHYS_PAGE='226',
 XY='(50,3750)',
 ROT='0',
 VER='2',
 PACK_TYPE='0402LF',
 LOCATION='PR403',
 CDS_LIB='pure_quanta',
 CDS_PART_NAME='Q_RES_0402LF-1K,1%,1/16W,CHIP,CS21002FB06',
 PART_NUMBER='CS21002FB06',
 VALUE='1K',
 PRIM_FILE='./archive_libs/logical/q_res/chips/chips.prt';

PART_NAME
 PR406 'Q_RES_0402LF-0,5%,1/16W,CHIP,CS00002JB13':;

SECTION_NUMBER 1
 '@T6G_MB_LIB.T6G(SCH_1):PAGE199_I70@PURE_QUANTA.Q_RES(CHIPS)':
 C_PATH='@t6g_mb_lib.t6g(sch_1):page199_i70@pure_quanta.q_res(chips)',
 P_PATH='@t6g_mb_lib.t6g(sch_1):page224_i70@pure_quanta.q_res(chips)',
 PATH='I70',
 DRAWING='@T6G_MB_LIB.T6G(SCH_1):PAGE199',
 WATTAGE='1/16W',
 TOLERANCE='5%',
 MATERIAL='CHIP',
 PHYS_PAGE='224',
 XY='(-3125,4125)',
 ROT='0',
 VER='1',
 PACK_TYPE='0402LF',
 LOCATION='PR406',
 CDS_LIB='pure_quanta',
 CDS_PART_NAME='Q_RES_0402LF-0,5%,1/16W,CHIP,CS00002JB13',
 PART_NUMBER='CS00002JB13',
 VALUE='0',
 PRIM_FILE='./archive_libs/logical/q_res/chips/chips.prt';

PART_NAME
 PR407 'Q_RES_0402LF-0,5%,1/16W,CHIP,CS00002JB13':;

SECTION_NUMBER 1
 '@T6G_MB_LIB.T6G(SCH_1):PAGE199_I60@PURE_QUANTA.Q_RES(CHIPS)':
 C_PATH='@t6g_mb_lib.t6g(sch_1):page199_i60@pure_quanta.q_res(chips)',
 P_PATH='@t6g_mb_lib.t6g(sch_1):page224_i60@pure_quanta.q_res(chips)',
 PATH='I60',
 DRAWING='@T6G_MB_LIB.T6G(SCH_1):PAGE199',
 WATTAGE='1/16W',
 TOLERANCE='5%',
 MATERIAL='CHIP',
 PHYS_PAGE='224',
 XY='(-3125,3675)',
 ROT='0',
 VER='1',
 PACK_TYPE='0402LF',
 LOCATION='PR407',
 CDS_LIB='pure_quanta',
 CDS_PART_NAME='Q_RES_0402LF-0,5%,1/16W,CHIP,CS00002JB13',
 PART_NUMBER='CS00002JB13',
 VALUE='0',
 PRIM_FILE='./archive_libs/logical/q_res/chips/chips.prt';

PART_NAME
 PR408 'Q_RES_0402LF-0,5%,1/16W,CHIP,CS00002JB13':;

SECTION_NUMBER 1
 '@T6G_MB_LIB.T6G(SCH_1):PAGE199_I57@PURE_QUANTA.Q_RES(CHIPS)':
 C_PATH='@t6g_mb_lib.t6g(sch_1):page199_i57@pure_quanta.q_res(chips)',
 P_PATH='@t6g_mb_lib.t6g(sch_1):page224_i57@pure_quanta.q_res(chips)',
 PATH='I57',
 DRAWING='@T6G_MB_LIB.T6G(SCH_1):PAGE199',
 WATTAGE='1/16W',
 TOLERANCE='5%',
 MATERIAL='CHIP',
 PHYS_PAGE='224',
 XY='(-3125,2325)',
 ROT='0',
 VER='1',
 PACK_TYPE='0402LF',
 LOCATION='PR408',
 CDS_LIB='pure_quanta',
 CDS_PART_NAME='Q_RES_0402LF-0,5%,1/16W,CHIP,CS00002JB13',
 PART_NUMBER='CS00002JB13',
 VALUE='0',
 PRIM_FILE='./archive_libs/logical/q_res/chips/chips.prt';

PART_NAME
 PR409 'Q_RES_0402LF-0,5%,1/16W,CHIP,CS00002JB13':;

SECTION_NUMBER 1
 '@T6G_MB_LIB.T6G(SCH_1):PAGE199_I52@PURE_QUANTA.Q_RES(CHIPS)':
 C_PATH='@t6g_mb_lib.t6g(sch_1):page199_i52@pure_quanta.q_res(chips)',
 P_PATH='@t6g_mb_lib.t6g(sch_1):page224_i52@pure_quanta.q_res(chips)',
 PATH='I52',
 DRAWING='@T6G_MB_LIB.T6G(SCH_1):PAGE199',
 WATTAGE='1/16W',
 TOLERANCE='5%',
 MATERIAL='CHIP',
 PHYS_PAGE='224',
 XY='(-3125,1875)',
 ROT='0',
 VER='1',
 PACK_TYPE='0402LF',
 LOCATION='PR409',
 CDS_LIB='pure_quanta',
 CDS_PART_NAME='Q_RES_0402LF-0,5%,1/16W,CHIP,CS00002JB13',
 PART_NUMBER='CS00002JB13',
 VALUE='0',
 PRIM_FILE='./archive_libs/logical/q_res/chips/chips.prt';

PART_NAME
 PR410 'Q_RES_0402LF-1K,1%,1/16W,CHIP,CS21002FB06':;

SECTION_NUMBER 1
 '@T6G_MB_LIB.T6G(SCH_1):PAGE180_I78@PURE_QUANTA.Q_RES(CHIPS)':
 C_PATH='@t6g_mb_lib.t6g(sch_1):page180_i78@pure_quanta.q_res(chips)',
 P_PATH='@t6g_mb_lib.t6g(sch_1):page205_i78@pure_quanta.q_res(chips)',
 PATH='I78',
 DRAWING='@T6G_MB_LIB.T6G(SCH_1):PAGE180',
 WATTAGE='1/16W',
 TOLERANCE='1%',
 MATERIAL='CHIP',
 PHYS_PAGE='205',
 XY='(8425,4775)',
 ROT='0',
 VER='2',
 PACK_TYPE='0402LF',
 LOCATION='PR410',
 CDS_LIB='pure_quanta',
 CDS_PART_NAME='Q_RES_0402LF-1K,1%,1/16W,CHIP,CS21002FB06',
 PART_NUMBER='CS21002FB06',
 VALUE='1K',
 PRIM_FILE='./archive_libs/logical/q_res/chips/chips.prt';

PART_NAME
 PR411 'Q_RES_0402LF-0,5%,1/16W,CHIP,CS00002JB13':;

SECTION_NUMBER 1
 '@T6G_MB_LIB.T6G(SCH_1):PAGE183_I85@PURE_QUANTA.Q_RES(CHIPS)':
 C_PATH='@t6g_mb_lib.t6g(sch_1):page183_i85@pure_quanta.q_res(chips)',
 P_PATH='@t6g_mb_lib.t6g(sch_1):page208_i85@pure_quanta.q_res(chips)',
 PATH='I85',
 DRAWING='@T6G_MB_LIB.T6G(SCH_1):PAGE183',
 WATTAGE='1/16W',
 TOLERANCE='5%',
 MATERIAL='CHIP',
 PHYS_PAGE='208',
 XY='(-8425,5700)',
 ROT='1',
 VER='1',
 PACK_TYPE='0402LF',
 LOCATION='PR411',
 CDS_LIB='pure_quanta',
 CDS_PART_NAME='Q_RES_0402LF-0,5%,1/16W,CHIP,CS00002JB13',
 PART_NUMBER='CS00002JB13',
 VALUE='0',
 PRIM_FILE='./archive_libs/logical/q_res/chips/chips.prt';

PART_NAME
 PR412 'Q_RES_0402LF-0,5%,1/16W,CHIP,CS00002JB13':;

SECTION_NUMBER 1
 '@T6G_MB_LIB.T6G(SCH_1):PAGE182_I52@PURE_QUANTA.Q_RES(CHIPS)':
 C_PATH='@t6g_mb_lib.t6g(sch_1):page182_i52@pure_quanta.q_res(chips)',
 P_PATH='@t6g_mb_lib.t6g(sch_1):page207_i52@pure_quanta.q_res(chips)',
 PATH='I52',
 DRAWING='@T6G_MB_LIB.T6G(SCH_1):PAGE182',
 WATTAGE='1/16W',
 TOLERANCE='5%',
 MATERIAL='CHIP',
 PHYS_PAGE='207',
 XY='(-3150,1225)',
 ROT='0',
 VER='1',
 PACK_TYPE='0402LF',
 LOCATION='PR412',
 CDS_LIB='pure_quanta',
 CDS_PART_NAME='Q_RES_0402LF-0,5%,1/16W,CHIP,CS00002JB13',
 PART_NUMBER='CS00002JB13',
 VALUE='0',
 PRIM_FILE='./archive_libs/logical/q_res/chips/chips.prt';

PART_NAME
 PR413 'Q_RES_0402LF-0,5%,1/16W,EMPTY,CS00002JB13':;

SECTION_NUMBER 1
 '@T6G_MB_LIB.T6G(SCH_1):PAGE183_I86@PURE_QUANTA.Q_RES(CHIPS)':
 C_PATH='@t6g_mb_lib.t6g(sch_1):page183_i86@pure_quanta.q_res(chips)',
 P_PATH='@t6g_mb_lib.t6g(sch_1):page208_i86@pure_quanta.q_res(chips)',
 PATH='I86',
 DRAWING='@T6G_MB_LIB.T6G(SCH_1):PAGE183',
 WATTAGE='1/16W',
 TOLERANCE='5%',
 MATERIAL='EMPTY',
 PHYS_PAGE='208',
 XY='(-8075,5700)',
 ROT='1',
 VER='1',
 PACK_TYPE='0402LF',
 LOCATION='PR413',
 CDS_LIB='pure_quanta',
 CDS_PART_NAME='Q_RES_0402LF-0,5%,1/16W,EMPTY,CS00002JB13',
 PART_NUMBER='CS00002JB13',
 VALUE='0',
 PRIM_FILE='./archive_libs/logical/q_res/chips/chips.prt';

PART_NAME
 PR414 'Q_RES_0402LF-1K,1%,1/16W,CHIP,CS21002FB06':;

SECTION_NUMBER 1
 '@T6G_MB_LIB.T6G(SCH_1):PAGE183_I83@PURE_QUANTA.Q_RES(CHIPS)':
 C_PATH='@t6g_mb_lib.t6g(sch_1):page183_i83@pure_quanta.q_res(chips)',
 P_PATH='@t6g_mb_lib.t6g(sch_1):page208_i83@pure_quanta.q_res(chips)',
 PATH='I83',
 DRAWING='@T6G_MB_LIB.T6G(SCH_1):PAGE183',
 WATTAGE='1/16W',
 TOLERANCE='1%',
 MATERIAL='CHIP',
 PHYS_PAGE='208',
 XY='(-1200,4225)',
 ROT='0',
 VER='2',
 PACK_TYPE='0402LF',
 LOCATION='PR414',
 CDS_LIB='pure_quanta',
 CDS_PART_NAME='Q_RES_0402LF-1K,1%,1/16W,CHIP,CS21002FB06',
 PART_NUMBER='CS21002FB06',
 VALUE='1K',
 PRIM_FILE='./archive_libs/logical/q_res/chips/chips.prt';

PART_NAME
 PR415 'Q_RES_0402LF-0,5%,1/16W,CHIP,CS00002JB13':;

SECTION_NUMBER 1
 '@T6G_MB_LIB.T6G(SCH_1):PAGE199_I51@PURE_QUANTA.Q_RES(CHIPS)':
 C_PATH='@t6g_mb_lib.t6g(sch_1):page199_i51@pure_quanta.q_res(chips)',
 P_PATH='@t6g_mb_lib.t6g(sch_1):page224_i51@pure_quanta.q_res(chips)',
 PATH='I51',
 DRAWING='@T6G_MB_LIB.T6G(SCH_1):PAGE199',
 WATTAGE='1/16W',
 TOLERANCE='5%',
 MATERIAL='CHIP',
 PHYS_PAGE='224',
 XY='(-3125,1225)',
 ROT='0',
 VER='1',
 PACK_TYPE='0402LF',
 LOCATION='PR415',
 CDS_LIB='pure_quanta',
 CDS_PART_NAME='Q_RES_0402LF-0,5%,1/16W,CHIP,CS00002JB13',
 PART_NUMBER='CS00002JB13',
 VALUE='0',
 PRIM_FILE='./archive_libs/logical/q_res/chips/chips.prt';

PART_NAME
 PR416 'Q_RES_0402LF-2.2,1%,1/16W,CHIP,CS-2202FB01':;

SECTION_NUMBER 1
 '@T6G_MB_LIB.T6G(SCH_1):PAGE178_I13@PURE_QUANTA.Q_RES(CHIPS)':
 C_PATH='@t6g_mb_lib.t6g(sch_1):page178_i13@pure_quanta.q_res(chips)',
 P_PATH='@t6g_mb_lib.t6g(sch_1):page203_i13@pure_quanta.q_res(chips)',
 PATH='I13',
 DRAWING='@T6G_MB_LIB.T6G(SCH_1):PAGE178',
 WATTAGE='1/16W',
 TOLERANCE='1%',
 MATERIAL='CHIP',
 PHYS_PAGE='203',
 XY='(1900,3200)',
 ROT='0',
 VER='2',
 PACK_TYPE='0402LF',
 LOCATION='PR416',
 CDS_LIB='pure_quanta',
 CDS_PART_NAME='Q_RES_0402LF-2.2,1%,1/16W,CHIP,CS-2202FB01',
 PART_NUMBER='CS-2202FB01',
 VALUE='2.2',
 PRIM_FILE='./archive_libs/logical/q_res/chips/chips.prt';

PART_NAME
 PR417 'Q_RES_0402LF-0,5%,1/16W,CHIP,CS00002JB13':;

SECTION_NUMBER 1
 '@T6G_MB_LIB.T6G(SCH_1):PAGE184_I15@PURE_QUANTA.Q_RES(CHIPS)':
 C_PATH='@t6g_mb_lib.t6g(sch_1):page184_i15@pure_quanta.q_res(chips)',
 P_PATH='@t6g_mb_lib.t6g(sch_1):page209_i15@pure_quanta.q_res(chips)',
 PATH='I15',
 DRAWING='@T6G_MB_LIB.T6G(SCH_1):PAGE184',
 WATTAGE='1/16W',
 TOLERANCE='5%',
 MATERIAL='CHIP',
 PHYS_PAGE='209',
 XY='(-7075,3375)',
 ROT='0',
 VER='1',
 PACK_TYPE='0402LF',
 LOCATION='PR417',
 CDS_LIB='pure_quanta',
 CDS_PART_NAME='Q_RES_0402LF-0,5%,1/16W,CHIP,CS00002JB13',
 PART_NUMBER='CS00002JB13',
 VALUE='0',
 PRIM_FILE='./archive_libs/logical/q_res/chips/chips.prt';

PART_NAME
 PR418 'Q_RES_0402LF-49.9,1%,1/16W,CHIP,CS04992FB07':;

SECTION_NUMBER 1
 '@T6G_MB_LIB.T6G(SCH_1):PAGE184_I31@PURE_QUANTA.Q_RES(CHIPS)':
 C_PATH='@t6g_mb_lib.t6g(sch_1):page184_i31@pure_quanta.q_res(chips)',
 P_PATH='@t6g_mb_lib.t6g(sch_1):page209_i31@pure_quanta.q_res(chips)',
 PATH='I31',
 DRAWING='@T6G_MB_LIB.T6G(SCH_1):PAGE184',
 WATTAGE='1/16W',
 TOLERANCE='1%',
 MATERIAL='CHIP',
 PHYS_PAGE='209',
 XY='(-3575,1775)',
 ROT='1',
 VER='1',
 PACK_TYPE='0402LF',
 LOCATION='PR418',
 CDS_LIB='pure_quanta',
 CDS_PART_NAME='Q_RES_0402LF-49.9,1%,1/16W,CHIP,CS04992FB07',
 PART_NUMBER='CS04992FB07',
 VALUE='49.9',
 PRIM_FILE='./archive_libs/logical/q_res/chips/chips.prt';

PART_NAME
 PR419 'Q_RES_0402LF-0,5%,1/16W,CHIP,CS00002JB13':;

SECTION_NUMBER 1
 '@T6G_MB_LIB.T6G(SCH_1):PAGE182_I58@PURE_QUANTA.Q_RES(CHIPS)':
 C_PATH='@t6g_mb_lib.t6g(sch_1):page182_i58@pure_quanta.q_res(chips)',
 P_PATH='@t6g_mb_lib.t6g(sch_1):page207_i58@pure_quanta.q_res(chips)',
 PATH='I58',
 DRAWING='@T6G_MB_LIB.T6G(SCH_1):PAGE182',
 WATTAGE='1/16W',
 TOLERANCE='5%',
 MATERIAL='CHIP',
 PHYS_PAGE='207',
 XY='(-3150,2325)',
 ROT='0',
 VER='1',
 PACK_TYPE='0402LF',
 LOCATION='PR419',
 CDS_LIB='pure_quanta',
 CDS_PART_NAME='Q_RES_0402LF-0,5%,1/16W,CHIP,CS00002JB13',
 PART_NUMBER='CS00002JB13',
 VALUE='0',
 PRIM_FILE='./archive_libs/logical/q_res/chips/chips.prt';

PART_NAME
 PR420 'Q_RES_0402LF-5.6,1%,1/16W,CHIP,CS-5602FB01':;

SECTION_NUMBER 1
 '@T6G_MB_LIB.T6G(SCH_1):PAGE178_I39@PURE_QUANTA.Q_RES(CHIPS)':
 C_PATH='@t6g_mb_lib.t6g(sch_1):page178_i39@pure_quanta.q_res(chips)',
 P_PATH='@t6g_mb_lib.t6g(sch_1):page203_i39@pure_quanta.q_res(chips)',
 PATH='I39',
 DRAWING='@T6G_MB_LIB.T6G(SCH_1):PAGE178',
 WATTAGE='1/16W',
 TOLERANCE='1%',
 MATERIAL='CHIP',
 PHYS_PAGE='203',
 XY='(4625,2575)',
 ROT='0',
 VER='1',
 PACK_TYPE='0402LF',
 LOCATION='PR420',
 CDS_LIB='pure_quanta',
 CDS_PART_NAME='Q_RES_0402LF-5.6,1%,1/16W,CHIP,CS-5602FB01',
 PART_NUMBER='CS-5602FB01',
 VALUE='5.6',
 PRIM_FILE='./archive_libs/logical/q_res/chips/chips.prt';

PART_NAME
 PR421 'Q_RES_0402LF-0,5%,1/16W,CHIP,CS00002JB13':;

SECTION_NUMBER 1
 '@T6G_MB_LIB.T6G(SCH_1):PAGE178_I35@PURE_QUANTA.Q_RES(CHIPS)':
 C_PATH='@t6g_mb_lib.t6g(sch_1):page178_i35@pure_quanta.q_res(chips)',
 P_PATH='@t6g_mb_lib.t6g(sch_1):page203_i35@pure_quanta.q_res(chips)',
 PATH='I35',
 DRAWING='@T6G_MB_LIB.T6G(SCH_1):PAGE178',
 WATTAGE='1/16W',
 TOLERANCE='5%',
 MATERIAL='CHIP',
 PHYS_PAGE='203',
 XY='(5975,1100)',
 ROT='0',
 VER='1',
 PACK_TYPE='0402LF',
 LOCATION='PR421',
 CDS_LIB='pure_quanta',
 CDS_PART_NAME='Q_RES_0402LF-0,5%,1/16W,CHIP,CS00002JB13',
 PART_NUMBER='CS00002JB13',
 VALUE='0',
 PRIM_FILE='./archive_libs/logical/q_res/chips/chips.prt';

PART_NAME
 PR422 'Q_RES_0402LF-2.2,1%,1/16W,CHIP,CS-2202FB01':;

SECTION_NUMBER 1
 '@T6G_MB_LIB.T6G(SCH_1):PAGE188_I12@PURE_QUANTA.Q_RES(CHIPS)':
 C_PATH='@t6g_mb_lib.t6g(sch_1):page188_i12@pure_quanta.q_res(chips)',
 P_PATH='@t6g_mb_lib.t6g(sch_1):page213_i12@pure_quanta.q_res(chips)',
 PATH='I12',
 DRAWING='@T6G_MB_LIB.T6G(SCH_1):PAGE188',
 WATTAGE='1/16W',
 TOLERANCE='1%',
 MATERIAL='CHIP',
 PHYS_PAGE='213',
 XY='(-7150,2850)',
 ROT='0',
 VER='2',
 PACK_TYPE='0402LF',
 LOCATION='PR422',
 CDS_LIB='pure_quanta',
 CDS_PART_NAME='Q_RES_0402LF-2.2,1%,1/16W,CHIP,CS-2202FB01',
 PART_NUMBER='CS-2202FB01',
 VALUE='2.2',
 PRIM_FILE='./archive_libs/logical/q_res/chips/chips.prt';

PART_NAME
 PR423 'Q_RES_0402LF-8.87K,1%,1/16W,EMPTY,CS28872FB01':;

SECTION_NUMBER 1
 '@T6G_MB_LIB.T6G(SCH_1):PAGE188_I8@PURE_QUANTA.Q_RES(CHIPS)':
 C_PATH='@t6g_mb_lib.t6g(sch_1):page188_i8@pure_quanta.q_res(chips)',
 P_PATH='@t6g_mb_lib.t6g(sch_1):page213_i8@pure_quanta.q_res(chips)',
 PATH='I8',
 DRAWING='@T6G_MB_LIB.T6G(SCH_1):PAGE188',
 WATTAGE='1/16W',
 TOLERANCE='1%',
 MATERIAL='EMPTY',
 PHYS_PAGE='213',
 XY='(-6825,1650)',
 ROT='0',
 VER='1',
 PACK_TYPE='0402LF',
 LOCATION='PR423',
 CDS_LIB='pure_quanta',
 CDS_PART_NAME='Q_RES_0402LF-8.87K,1%,1/16W,EMPTY,CS28872FB01',
 PART_NUMBER='CS28872FB01',
 VALUE='8.87K',
 PRIM_FILE='./archive_libs/logical/q_res/chips/chips.prt';

PART_NAME
 PR424 'Q_RES_0402LF-5.6,1%,1/16W,CHIP,CS-5602FB01':;

SECTION_NUMBER 1
 '@T6G_MB_LIB.T6G(SCH_1):PAGE188_I28@PURE_QUANTA.Q_RES(CHIPS)':
 C_PATH='@t6g_mb_lib.t6g(sch_1):page188_i28@pure_quanta.q_res(chips)',
 P_PATH='@t6g_mb_lib.t6g(sch_1):page213_i28@pure_quanta.q_res(chips)',
 PATH='I28',
 DRAWING='@T6G_MB_LIB.T6G(SCH_1):PAGE188',
 WATTAGE='1/16W',
 TOLERANCE='1%',
 MATERIAL='CHIP',
 PHYS_PAGE='213',
 XY='(-4250,2300)',
 ROT='0',
 VER='1',
 PACK_TYPE='0402LF',
 LOCATION='PR424',
 CDS_LIB='pure_quanta',
 CDS_PART_NAME='Q_RES_0402LF-5.6,1%,1/16W,CHIP,CS-5602FB01',
 PART_NUMBER='CS-5602FB01',
 VALUE='5.6',
 PRIM_FILE='./archive_libs/logical/q_res/chips/chips.prt';

PART_NAME
 PR425 'Q_RES_0402LF-0,5%,1/16W,CHIP,CS00002JB13':;

SECTION_NUMBER 1
 '@T6G_MB_LIB.T6G(SCH_1):PAGE188_I22@PURE_QUANTA.Q_RES(CHIPS)':
 C_PATH='@t6g_mb_lib.t6g(sch_1):page188_i22@pure_quanta.q_res(chips)',
 P_PATH='@t6g_mb_lib.t6g(sch_1):page213_i22@pure_quanta.q_res(chips)',
 PATH='I22',
 DRAWING='@T6G_MB_LIB.T6G(SCH_1):PAGE188',
 WATTAGE='1/16W',
 TOLERANCE='5%',
 MATERIAL='CHIP',
 PHYS_PAGE='213',
 XY='(-3825,900)',
 ROT='0',
 VER='1',
 PACK_TYPE='0402LF',
 LOCATION='PR425',
 CDS_LIB='pure_quanta',
 CDS_PART_NAME='Q_RES_0402LF-0,5%,1/16W,CHIP,CS00002JB13',
 PART_NUMBER='CS00002JB13',
 VALUE='0',
 PRIM_FILE='./archive_libs/logical/q_res/chips/chips.prt';

PART_NAME
 PR426 'Q_RES_0402LF-8.87K,1%,1/16W,EMPTY,CS28872FB01':;

SECTION_NUMBER 1
 '@T6G_MB_LIB.T6G(SCH_1):PAGE195_I4@PURE_QUANTA.Q_RES(CHIPS)':
 C_PATH='@t6g_mb_lib.t6g(sch_1):page195_i4@pure_quanta.q_res(chips)',
 P_PATH='@t6g_mb_lib.t6g(sch_1):page220_i4@pure_quanta.q_res(chips)',
 PATH='I4',
 DRAWING='@T6G_MB_LIB.T6G(SCH_1):PAGE195',
 WATTAGE='1/16W',
 TOLERANCE='1%',
 MATERIAL='EMPTY',
 PHYS_PAGE='220',
 XY='(1275,1725)',
 ROT='2',
 VER='2',
 PACK_TYPE='0402LF',
 LOCATION='PR426',
 CDS_LIB='pure_quanta',
 CDS_PART_NAME='Q_RES_0402LF-8.87K,1%,1/16W,EMPTY,CS28872FB01',
 PART_NUMBER='CS28872FB01',
 VALUE='8.87K',
 PRIM_FILE='./archive_libs/logical/q_res/chips/chips.prt';

PART_NAME
 PR427 'Q_RES_0402LF-2.2,1%,1/16W,CHIP,CS-2202FB01':;

SECTION_NUMBER 1
 '@T6G_MB_LIB.T6G(SCH_1):PAGE195_I13@PURE_QUANTA.Q_RES(CHIPS)':
 C_PATH='@t6g_mb_lib.t6g(sch_1):page195_i13@pure_quanta.q_res(chips)',
 P_PATH='@t6g_mb_lib.t6g(sch_1):page220_i13@pure_quanta.q_res(chips)',
 PATH='I13',
 DRAWING='@T6G_MB_LIB.T6G(SCH_1):PAGE195',
 WATTAGE='1/16W',
 TOLERANCE='1%',
 MATERIAL='CHIP',
 PHYS_PAGE='220',
 XY='(1725,3200)',
 ROT='0',
 VER='2',
 PACK_TYPE='0402LF',
 LOCATION='PR427',
 CDS_LIB='pure_quanta',
 CDS_PART_NAME='Q_RES_0402LF-2.2,1%,1/16W,CHIP,CS-2202FB01',
 PART_NUMBER='CS-2202FB01',
 VALUE='2.2',
 PRIM_FILE='./archive_libs/logical/q_res/chips/chips.prt';

PART_NAME
 PR428 'Q_RES_0402LF-5.6,1%,1/16W,CHIP,CS-5602FB01':;

SECTION_NUMBER 1
 '@T6G_MB_LIB.T6G(SCH_1):PAGE195_I39@PURE_QUANTA.Q_RES(CHIPS)':
 C_PATH='@t6g_mb_lib.t6g(sch_1):page195_i39@pure_quanta.q_res(chips)',
 P_PATH='@t6g_mb_lib.t6g(sch_1):page220_i39@pure_quanta.q_res(chips)',
 PATH='I39',
 DRAWING='@T6G_MB_LIB.T6G(SCH_1):PAGE195',
 WATTAGE='1/16W',
 TOLERANCE='1%',
 MATERIAL='CHIP',
 PHYS_PAGE='220',
 XY='(4550,2575)',
 ROT='0',
 VER='1',
 PACK_TYPE='0402LF',
 LOCATION='PR428',
 CDS_LIB='pure_quanta',
 CDS_PART_NAME='Q_RES_0402LF-5.6,1%,1/16W,CHIP,CS-5602FB01',
 PART_NUMBER='CS-5602FB01',
 VALUE='5.6',
 PRIM_FILE='./archive_libs/logical/q_res/chips/chips.prt';

PART_NAME
 PR429 'Q_RES_0402LF-0,5%,1/16W,CHIP,CS00002JB13':;

SECTION_NUMBER 1
 '@T6G_MB_LIB.T6G(SCH_1):PAGE195_I35@PURE_QUANTA.Q_RES(CHIPS)':
 C_PATH='@t6g_mb_lib.t6g(sch_1):page195_i35@pure_quanta.q_res(chips)',
 P_PATH='@t6g_mb_lib.t6g(sch_1):page220_i35@pure_quanta.q_res(chips)',
 PATH='I35',
 DRAWING='@T6G_MB_LIB.T6G(SCH_1):PAGE195',
 WATTAGE='1/16W',
 TOLERANCE='5%',
 MATERIAL='CHIP',
 PHYS_PAGE='220',
 XY='(5750,1075)',
 ROT='0',
 VER='1',
 PACK_TYPE='0402LF',
 LOCATION='PR429',
 CDS_LIB='pure_quanta',
 CDS_PART_NAME='Q_RES_0402LF-0,5%,1/16W,CHIP,CS00002JB13',
 PART_NUMBER='CS00002JB13',
 VALUE='0',
 PRIM_FILE='./archive_libs/logical/q_res/chips/chips.prt';

PART_NAME
 PR430 'Q_RES_0402LF-2.2,1%,1/16W,CHIP,CS-2202FB01':;

SECTION_NUMBER 1
 '@T6G_MB_LIB.T6G(SCH_1):PAGE171_I13@PURE_QUANTA.Q_RES(CHIPS)':
 C_PATH='@t6g_mb_lib.t6g(sch_1):page171_i13@pure_quanta.q_res(chips)',
 P_PATH='@t6g_mb_lib.t6g(sch_1):page196_i13@pure_quanta.q_res(chips)',
 PATH='I13',
 DRAWING='@T6G_MB_LIB.T6G(SCH_1):PAGE171',
 WATTAGE='1/16W',
 TOLERANCE='1%',
 MATERIAL='CHIP',
 PHYS_PAGE='196',
 XY='(-7200,2700)',
 ROT='0',
 VER='2',
 PACK_TYPE='0402LF',
 LOCATION='PR430',
 CDS_LIB='pure_quanta',
 CDS_PART_NAME='Q_RES_0402LF-2.2,1%,1/16W,CHIP,CS-2202FB01',
 PART_NUMBER='CS-2202FB01',
 VALUE='2.2',
 PRIM_FILE='./archive_libs/logical/q_res/chips/chips.prt';

PART_NAME
 PR431 'Q_RES_0402LF-8.87K,1%,1/16W,EMPTY,CS28872FB01':;

SECTION_NUMBER 1
 '@T6G_MB_LIB.T6G(SCH_1):PAGE171_I8@PURE_QUANTA.Q_RES(CHIPS)':
 C_PATH='@t6g_mb_lib.t6g(sch_1):page171_i8@pure_quanta.q_res(chips)',
 P_PATH='@t6g_mb_lib.t6g(sch_1):page196_i8@pure_quanta.q_res(chips)',
 PATH='I8',
 DRAWING='@T6G_MB_LIB.T6G(SCH_1):PAGE171',
 WATTAGE='1/16W',
 TOLERANCE='1%',
 MATERIAL='EMPTY',
 PHYS_PAGE='196',
 XY='(-6875,1550)',
 ROT='0',
 VER='1',
 PACK_TYPE='0402LF',
 LOCATION='PR431',
 CDS_LIB='pure_quanta',
 CDS_PART_NAME='Q_RES_0402LF-8.87K,1%,1/16W,EMPTY,CS28872FB01',
 PART_NUMBER='CS28872FB01',
 VALUE='8.87K',
 PRIM_FILE='./archive_libs/logical/q_res/chips/chips.prt';

PART_NAME
 PR432 'Q_RES_0402LF-5.6,1%,1/16W,CHIP,CS-5602FB01':;

SECTION_NUMBER 1
 '@T6G_MB_LIB.T6G(SCH_1):PAGE171_I26@PURE_QUANTA.Q_RES(CHIPS)':
 C_PATH='@t6g_mb_lib.t6g(sch_1):page171_i26@pure_quanta.q_res(chips)',
 P_PATH='@t6g_mb_lib.t6g(sch_1):page196_i26@pure_quanta.q_res(chips)',
 PATH='I26',
 DRAWING='@T6G_MB_LIB.T6G(SCH_1):PAGE171',
 WATTAGE='1/16W',
 TOLERANCE='1%',
 MATERIAL='CHIP',
 PHYS_PAGE='196',
 XY='(-4275,2200)',
 ROT='0',
 VER='1',
 PACK_TYPE='0402LF',
 LOCATION='PR432',
 CDS_LIB='pure_quanta',
 CDS_PART_NAME='Q_RES_0402LF-5.6,1%,1/16W,CHIP,CS-5602FB01',
 PART_NUMBER='CS-5602FB01',
 VALUE='5.6',
 PRIM_FILE='./archive_libs/logical/q_res/chips/chips.prt';

PART_NAME
 PR433 'Q_RES_0402LF-0,5%,1/16W,CHIP,CS00002JB13':;

SECTION_NUMBER 1
 '@T6G_MB_LIB.T6G(SCH_1):PAGE171_I21@PURE_QUANTA.Q_RES(CHIPS)':
 C_PATH='@t6g_mb_lib.t6g(sch_1):page171_i21@pure_quanta.q_res(chips)',
 P_PATH='@t6g_mb_lib.t6g(sch_1):page196_i21@pure_quanta.q_res(chips)',
 PATH='I21',
 DRAWING='@T6G_MB_LIB.T6G(SCH_1):PAGE171',
 WATTAGE='1/16W',
 TOLERANCE='5%',
 MATERIAL='CHIP',
 PHYS_PAGE='196',
 XY='(-3900,800)',
 ROT='0',
 VER='1',
 PACK_TYPE='0402LF',
 LOCATION='PR433',
 CDS_LIB='pure_quanta',
 CDS_PART_NAME='Q_RES_0402LF-0,5%,1/16W,CHIP,CS00002JB13',
 PART_NUMBER='CS00002JB13',
 VALUE='0',
 PRIM_FILE='./archive_libs/logical/q_res/chips/chips.prt';

PART_NAME
 PR434 'Q_RES_0402LF-10,1%,1/16W,CHIP,CS01002FB07':;

SECTION_NUMBER 1
 '@T6G_MB_LIB.T6G(SCH_1):PAGE184_I38@PURE_QUANTA.Q_RES(CHIPS)':
 C_PATH='@t6g_mb_lib.t6g(sch_1):page184_i38@pure_quanta.q_res(chips)',
 P_PATH='@t6g_mb_lib.t6g(sch_1):page209_i38@pure_quanta.q_res(chips)',
 PATH='I38',
 DRAWING='@T6G_MB_LIB.T6G(SCH_1):PAGE184',
 WATTAGE='1/16W',
 TOLERANCE='1%',
 MATERIAL='CHIP',
 PHYS_PAGE='209',
 XY='(-2600,2325)',
 ROT='0',
 VER='1',
 PACK_TYPE='0402LF',
 LOCATION='PR434',
 CDS_LIB='pure_quanta',
 CDS_PART_NAME='Q_RES_0402LF-10,1%,1/16W,CHIP,CS01002FB07',
 PART_NUMBER='CS01002FB07',
 VALUE='10',
 PRIM_FILE='./archive_libs/logical/q_res/chips/chips.prt';

PART_NAME
 PR435 'Q_RES_0402LF-0,5%,1/16W,CHIP,CS00002JB13':;

SECTION_NUMBER 1
 '@T6G_MB_LIB.T6G(SCH_1):PAGE184_I37@PURE_QUANTA.Q_RES(CHIPS)':
 C_PATH='@t6g_mb_lib.t6g(sch_1):page184_i37@pure_quanta.q_res(chips)',
 P_PATH='@t6g_mb_lib.t6g(sch_1):page209_i37@pure_quanta.q_res(chips)',
 PATH='I37',
 DRAWING='@T6G_MB_LIB.T6G(SCH_1):PAGE184',
 WATTAGE='1/16W',
 TOLERANCE='5%',
 MATERIAL='CHIP',
 PHYS_PAGE='209',
 XY='(-2600,2025)',
 ROT='1',
 VER='2',
 PACK_TYPE='0402LF',
 LOCATION='PR435',
 CDS_LIB='pure_quanta',
 CDS_PART_NAME='Q_RES_0402LF-0,5%,1/16W,CHIP,CS00002JB13',
 PART_NUMBER='CS00002JB13',
 VALUE='0',
 PRIM_FILE='./archive_libs/logical/q_res/chips/chips.prt';

PART_NAME
 PR436 'Q_RES_0402LF-0,5%,1/16W,CHIP,CS00002JB13':;

SECTION_NUMBER 1
 '@T6G_MB_LIB.T6G(SCH_1):PAGE185_I103@PURE_QUANTA.Q_RES(CHIPS)':
 C_PATH='@t6g_mb_lib.t6g(sch_1):page185_i103@pure_quanta.q_res(chips)',
 P_PATH='@t6g_mb_lib.t6g(sch_1):page210_i103@pure_quanta.q_res(chips)',
 PATH='I103',
 DRAWING='@T6G_MB_LIB.T6G(SCH_1):PAGE185',
 WATTAGE='1/16W',
 TOLERANCE='5%',
 MATERIAL='CHIP',
 PHYS_PAGE='210',
 XY='(400,4675)',
 ROT='0',
 VER='1',
 PACK_TYPE='0402LF',
 LOCATION='PR436',
 CDS_LIB='pure_quanta',
 CDS_PART_NAME='Q_RES_0402LF-0,5%,1/16W,CHIP,CS00002JB13',
 PART_NUMBER='CS00002JB13',
 VALUE='0',
 PRIM_FILE='./archive_libs/logical/q_res/chips/chips.prt';

PART_NAME
 PR437 'Q_RES_0402LF-0,5%,1/16W,CHIP,CS00002JB13':;

SECTION_NUMBER 1
 '@T6G_MB_LIB.T6G(SCH_1):PAGE185_I102@PURE_QUANTA.Q_RES(CHIPS)':
 C_PATH='@t6g_mb_lib.t6g(sch_1):page185_i102@pure_quanta.q_res(chips)',
 P_PATH='@t6g_mb_lib.t6g(sch_1):page210_i102@pure_quanta.q_res(chips)',
 PATH='I102',
 DRAWING='@T6G_MB_LIB.T6G(SCH_1):PAGE185',
 WATTAGE='1/16W',
 TOLERANCE='5%',
 MATERIAL='CHIP',
 PHYS_PAGE='210',
 XY='(400,4375)',
 ROT='0',
 VER='1',
 PACK_TYPE='0402LF',
 LOCATION='PR437',
 CDS_LIB='pure_quanta',
 CDS_PART_NAME='Q_RES_0402LF-0,5%,1/16W,CHIP,CS00002JB13',
 PART_NUMBER='CS00002JB13',
 VALUE='0',
 PRIM_FILE='./archive_libs/logical/q_res/chips/chips.prt';

PART_NAME
 PR438 'Q_RES_0402LF-49.9,1%,1/16W,CHIP,CS04992FB07':;

SECTION_NUMBER 1
 '@T6G_MB_LIB.T6G(SCH_1):PAGE184_I42@PURE_QUANTA.Q_RES(CHIPS)':
 C_PATH='@t6g_mb_lib.t6g(sch_1):page184_i42@pure_quanta.q_res(chips)',
 P_PATH='@t6g_mb_lib.t6g(sch_1):page209_i42@pure_quanta.q_res(chips)',
 PATH='I42',
 DRAWING='@T6G_MB_LIB.T6G(SCH_1):PAGE184',
 WATTAGE='1/16W',
 TOLERANCE='1%',
 MATERIAL='CHIP',
 PHYS_PAGE='209',
 XY='(-1700,2825)',
 ROT='0',
 VER='1',
 PACK_TYPE='0402LF',
 LOCATION='PR438',
 CDS_LIB='pure_quanta',
 CDS_PART_NAME='Q_RES_0402LF-49.9,1%,1/16W,CHIP,CS04992FB07',
 PART_NUMBER='CS04992FB07',
 VALUE='49.9',
 PRIM_FILE='./archive_libs/logical/q_res/chips/chips.prt';

PART_NAME
 PR439 'Q_RES_0402LF-1K,1%,1/16W,CHIP,CS21002FB06':;

SECTION_NUMBER 1
 '@T6G_MB_LIB.T6G(SCH_1):PAGE184_I51@PURE_QUANTA.Q_RES(CHIPS)':
 C_PATH='@t6g_mb_lib.t6g(sch_1):page184_i51@pure_quanta.q_res(chips)',
 P_PATH='@t6g_mb_lib.t6g(sch_1):page209_i51@pure_quanta.q_res(chips)',
 PATH='I51',
 DRAWING='@T6G_MB_LIB.T6G(SCH_1):PAGE184',
 WATTAGE='1/16W',
 TOLERANCE='1%',
 MATERIAL='CHIP',
 PHYS_PAGE='209',
 XY='(-500,3300)',
 ROT='0',
 VER='2',
 PACK_TYPE='0402LF',
 LOCATION='PR439',
 CDS_LIB='pure_quanta',
 CDS_PART_NAME='Q_RES_0402LF-1K,1%,1/16W,CHIP,CS21002FB06',
 PART_NUMBER='CS21002FB06',
 VALUE='1K',
 PRIM_FILE='./archive_libs/logical/q_res/chips/chips.prt';

PART_NAME
 PR440 'Q_RES_0402LF-0,5%,1/16W,CHIP,CS00002JB13':;

SECTION_NUMBER 1
 '@T6G_MB_LIB.T6G(SCH_1):PAGE168_I108@PURE_QUANTA.Q_RES(CHIPS)':
 C_PATH='@t6g_mb_lib.t6g(sch_1):page168_i108@pure_quanta.q_res(chips)',
 P_PATH='@t6g_mb_lib.t6g(sch_1):page193_i108@pure_quanta.q_res(chips)',
 PATH='I108',
 DRAWING='@T6G_MB_LIB.T6G(SCH_1):PAGE168',
 WATTAGE='1/16W',
 TOLERANCE='5%',
 MATERIAL='CHIP',
 PHYS_PAGE='193',
 XY='(-2500,3300)',
 ROT='0',
 VER='1',
 PACK_TYPE='0402LF',
 LOCATION='PR440',
 CDS_LIB='pure_quanta',
 CDS_PART_NAME='Q_RES_0402LF-0,5%,1/16W,CHIP,CS00002JB13',
 PART_NUMBER='CS00002JB13',
 VALUE='0',
 PRIM_FILE='./archive_libs/logical/q_res/chips/chips.prt';

PART_NAME
 PR441 'Q_RES_0402LF-0,5%,1/16W,CHIP,CS00002JB13':;

SECTION_NUMBER 1
 '@T6G_MB_LIB.T6G(SCH_1):PAGE168_I107@PURE_QUANTA.Q_RES(CHIPS)':
 C_PATH='@t6g_mb_lib.t6g(sch_1):page168_i107@pure_quanta.q_res(chips)',
 P_PATH='@t6g_mb_lib.t6g(sch_1):page193_i107@pure_quanta.q_res(chips)',
 PATH='I107',
 DRAWING='@T6G_MB_LIB.T6G(SCH_1):PAGE168',
 WATTAGE='1/16W',
 TOLERANCE='5%',
 MATERIAL='CHIP',
 PHYS_PAGE='193',
 XY='(-2500,3000)',
 ROT='0',
 VER='1',
 PACK_TYPE='0402LF',
 LOCATION='PR441',
 CDS_LIB='pure_quanta',
 CDS_PART_NAME='Q_RES_0402LF-0,5%,1/16W,CHIP,CS00002JB13',
 PART_NUMBER='CS00002JB13',
 VALUE='0',
 PRIM_FILE='./archive_libs/logical/q_res/chips/chips.prt';

PART_NAME
 PR442 'Q_RES_0402LF-0,5%,1/16W,CHIP,CS00002JB13':;

SECTION_NUMBER 1
 '@T6G_MB_LIB.T6G(SCH_1):PAGE176_I21@PURE_QUANTA.Q_RES(CHIPS)':
 C_PATH='@t6g_mb_lib.t6g(sch_1):page176_i21@pure_quanta.q_res(chips)',
 P_PATH='@t6g_mb_lib.t6g(sch_1):page201_i21@pure_quanta.q_res(chips)',
 PATH='I21',
 DRAWING='@T6G_MB_LIB.T6G(SCH_1):PAGE176',
 WATTAGE='1/16W',
 TOLERANCE='5%',
 MATERIAL='CHIP',
 PHYS_PAGE='201',
 XY='(-9625,5450)',
 ROT='1',
 VER='1',
 PACK_TYPE='0402LF',
 LOCATION='PR442',
 CDS_LIB='pure_quanta',
 CDS_PART_NAME='Q_RES_0402LF-0,5%,1/16W,CHIP,CS00002JB13',
 PART_NUMBER='CS00002JB13',
 VALUE='0',
 PRIM_FILE='./archive_libs/logical/q_res/chips/chips.prt';

PART_NAME
 PR443 'Q_RES_0402LF-0,5%,1/16W,EMPTY,CS00002JB13':;

SECTION_NUMBER 1
 '@T6G_MB_LIB.T6G(SCH_1):PAGE176_I27@PURE_QUANTA.Q_RES(CHIPS)':
 C_PATH='@t6g_mb_lib.t6g(sch_1):page176_i27@pure_quanta.q_res(chips)',
 P_PATH='@t6g_mb_lib.t6g(sch_1):page201_i27@pure_quanta.q_res(chips)',
 PATH='I27',
 DRAWING='@T6G_MB_LIB.T6G(SCH_1):PAGE176',
 WATTAGE='1/16W',
 TOLERANCE='5%',
 MATERIAL='EMPTY',
 PHYS_PAGE='201',
 XY='(-9275,5450)',
 ROT='1',
 VER='1',
 PACK_TYPE='0402LF',
 LOCATION='PR443',
 CDS_LIB='pure_quanta',
 CDS_PART_NAME='Q_RES_0402LF-0,5%,1/16W,EMPTY,CS00002JB13',
 PART_NUMBER='CS00002JB13',
 VALUE='0',
 PRIM_FILE='./archive_libs/logical/q_res/chips/chips.prt';

PART_NAME
 PR444 'Q_RES_0402LF-1K,1%,1/16W,CHIP,CS21002FB06':;

SECTION_NUMBER 1
 '@T6G_MB_LIB.T6G(SCH_1):PAGE176_I90@PURE_QUANTA.Q_RES(CHIPS)':
 C_PATH='@t6g_mb_lib.t6g(sch_1):page176_i90@pure_quanta.q_res(chips)',
 P_PATH='@t6g_mb_lib.t6g(sch_1):page201_i90@pure_quanta.q_res(chips)',
 PATH='I90',
 DRAWING='@T6G_MB_LIB.T6G(SCH_1):PAGE176',
 WATTAGE='1/16W',
 TOLERANCE='1%',
 MATERIAL='CHIP',
 PHYS_PAGE='201',
 XY='(-1850,3900)',
 ROT='0',
 VER='2',
 PACK_TYPE='0402LF',
 LOCATION='PR444',
 CDS_LIB='pure_quanta',
 CDS_PART_NAME='Q_RES_0402LF-1K,1%,1/16W,CHIP,CS21002FB06',
 PART_NUMBER='CS21002FB06',
 VALUE='1K',
 PRIM_FILE='./archive_libs/logical/q_res/chips/chips.prt';

PART_NAME
 PR445 'Q_RES_0402LF-0,5%,1/16W,CHIP,CS00002JB13':;

SECTION_NUMBER 1
 '@T6G_MB_LIB.T6G(SCH_1):PAGE169_I3@PURE_QUANTA.Q_RES(CHIPS)':
 C_PATH='@t6g_mb_lib.t6g(sch_1):page169_i3@pure_quanta.q_res(chips)',
 P_PATH='@t6g_mb_lib.t6g(sch_1):page194_i3@pure_quanta.q_res(chips)',
 PATH='I3',
 DRAWING='@T6G_MB_LIB.T6G(SCH_1):PAGE169',
 WATTAGE='1/16W',
 TOLERANCE='5%',
 MATERIAL='CHIP',
 PHYS_PAGE='194',
 XY='(-8625,5625)',
 ROT='1',
 VER='1',
 PACK_TYPE='0402LF',
 LOCATION='PR445',
 CDS_LIB='pure_quanta',
 CDS_PART_NAME='Q_RES_0402LF-0,5%,1/16W,CHIP,CS00002JB13',
 PART_NUMBER='CS00002JB13',
 VALUE='0',
 PRIM_FILE='./archive_libs/logical/q_res/chips/chips.prt';

PART_NAME
 PR446 'Q_RES_0402LF-0,5%,1/16W,EMPTY,CS00002JB13':;

SECTION_NUMBER 1
 '@T6G_MB_LIB.T6G(SCH_1):PAGE169_I4@PURE_QUANTA.Q_RES(CHIPS)':
 C_PATH='@t6g_mb_lib.t6g(sch_1):page169_i4@pure_quanta.q_res(chips)',
 P_PATH='@t6g_mb_lib.t6g(sch_1):page194_i4@pure_quanta.q_res(chips)',
 PATH='I4',
 DRAWING='@T6G_MB_LIB.T6G(SCH_1):PAGE169',
 WATTAGE='1/16W',
 TOLERANCE='5%',
 MATERIAL='EMPTY',
 PHYS_PAGE='194',
 XY='(-8275,5625)',
 ROT='1',
 VER='1',
 PACK_TYPE='0402LF',
 LOCATION='PR446',
 CDS_LIB='pure_quanta',
 CDS_PART_NAME='Q_RES_0402LF-0,5%,1/16W,EMPTY,CS00002JB13',
 PART_NUMBER='CS00002JB13',
 VALUE='0',
 PRIM_FILE='./archive_libs/logical/q_res/chips/chips.prt';

PART_NAME
 PR447 'Q_RES_0402LF-1K,1%,1/16W,CHIP,CS21002FB06':;

SECTION_NUMBER 1
 '@T6G_MB_LIB.T6G(SCH_1):PAGE169_I90@PURE_QUANTA.Q_RES(CHIPS)':
 C_PATH='@t6g_mb_lib.t6g(sch_1):page169_i90@pure_quanta.q_res(chips)',
 P_PATH='@t6g_mb_lib.t6g(sch_1):page194_i90@pure_quanta.q_res(chips)',
 PATH='I90',
 DRAWING='@T6G_MB_LIB.T6G(SCH_1):PAGE169',
 WATTAGE='1/16W',
 TOLERANCE='1%',
 MATERIAL='CHIP',
 PHYS_PAGE='194',
 XY='(-775,4150)',
 ROT='0',
 VER='2',
 PACK_TYPE='0402LF',
 LOCATION='PR447',
 CDS_LIB='pure_quanta',
 CDS_PART_NAME='Q_RES_0402LF-1K,1%,1/16W,CHIP,CS21002FB06',
 PART_NUMBER='CS21002FB06',
 VALUE='1K',
 PRIM_FILE='./archive_libs/logical/q_res/chips/chips.prt';

PART_NAME
 PR448 'Q_RES_0402LF-8.66K,1%,1/16W,CHIP,CS28662FB02':;

SECTION_NUMBER 1
 '@T6G_MB_LIB.T6G(SCH_1):PAGE184_I17@PURE_QUANTA.Q_RES(CHIPS)':
 C_PATH='@t6g_mb_lib.t6g(sch_1):page184_i17@pure_quanta.q_res(chips)',
 P_PATH='@t6g_mb_lib.t6g(sch_1):page209_i17@pure_quanta.q_res(chips)',
 PATH='I17',
 DRAWING='@T6G_MB_LIB.T6G(SCH_1):PAGE184',
 SEC_TYPE='0402LF',
 WATTAGE='1/16W',
 TOLERANCE='1%',
 MATERIAL='CHIP',
 PHYS_PAGE='209',
 XY='(-6700,2550)',
 ROT='0',
 VER='2',
 PACK_TYPE='0402LF',
 LOCATION='PR448',
 SEC='1',
 CDS_LIB='pure_quanta',
 CDS_PART_NAME='Q_RES_0402LF-8.66K,1%,1/16W,CHIP,CS28662FB02',
 PART_NUMBER='CS28662FB02',
 VALUE='8.66K',
 PRIM_FILE='./archive_libs/logical/q_res/chips/chips.prt';

PART_NAME
 PR452 'Q_RES_0402LF-6.98K,1%,1/16W,CHIP,CS26982FB08':;

SECTION_NUMBER 1
 '@T6G_MB_LIB.T6G(SCH_1):PAGE167_I15@PURE_QUANTA.Q_RES(CHIPS)':
 C_PATH='@t6g_mb_lib.t6g(sch_1):page167_i15@pure_quanta.q_res(chips)',
 P_PATH='@t6g_mb_lib.t6g(sch_1):page192_i15@pure_quanta.q_res(chips)',
 PATH='I15',
 DRAWING='@T6G_MB_LIB.T6G(SCH_1):PAGE167',
 SEC_TYPE='0402LF',
 WATTAGE='1/16W',
 TOLERANCE='1%',
 MATERIAL='CHIP',
 PHYS_PAGE='192',
 XY='(-7875,2575)',
 ROT='0',
 VER='2',
 PACK_TYPE='0402LF',
 LOCATION='PR452',
 SEC='1',
 CDS_LIB='pure_quanta',
 CDS_PART_NAME='Q_RES_0402LF-6.98K,1%,1/16W,CHIP,CS26982FB08',
 PART_NUMBER='CS26982FB08',
 VALUE='6.98K',
 PRIM_FILE='./archive_libs/logical/q_res/chips/chips.prt';

PART_NAME
 PR454 'Q_RES_0402LF-12.4K,1%,1/16W,CHIP,CS31242FB02':;

SECTION_NUMBER 1
 '@T6G_MB_LIB.T6G(SCH_1):PAGE167_I23@PURE_QUANTA.Q_RES(CHIPS)':
 C_PATH='@t6g_mb_lib.t6g(sch_1):page167_i23@pure_quanta.q_res(chips)',
 P_PATH='@t6g_mb_lib.t6g(sch_1):page192_i23@pure_quanta.q_res(chips)',
 PATH='I23',
 DRAWING='@T6G_MB_LIB.T6G(SCH_1):PAGE167',
 SEC_TYPE='0402LF',
 WATTAGE='1/16W',
 TOLERANCE='1%',
 MATERIAL='CHIP',
 PHYS_PAGE='192',
 XY='(-5175,2400)',
 ROT='2',
 VER='2',
 PACK_TYPE='0402LF',
 LOCATION='PR454',
 SEC='1',
 CDS_LIB='pure_quanta',
 CDS_PART_NAME='Q_RES_0402LF-12.4K,1%,1/16W,CHIP,CS31242FB02',
 PART_NUMBER='CS31242FB02',
 VALUE='12.4K',
 PRIM_FILE='./archive_libs/logical/q_res/chips/chips.prt';

PART_NAME
 PR455 'Q_RES_0402LF-56K,1%,1/16W,CHIP,CS35602FB00':;

SECTION_NUMBER 1
 '@T6G_MB_LIB.T6G(SCH_1):PAGE167_I25@PURE_QUANTA.Q_RES(CHIPS)':
 C_PATH='@t6g_mb_lib.t6g(sch_1):page167_i25@pure_quanta.q_res(chips)',
 P_PATH='@t6g_mb_lib.t6g(sch_1):page192_i25@pure_quanta.q_res(chips)',
 PATH='I25',
 DRAWING='@T6G_MB_LIB.T6G(SCH_1):PAGE167',
 SEC_TYPE='0402LF',
 WATTAGE='1/16W',
 TOLERANCE='1%',
 MATERIAL='CHIP',
 PHYS_PAGE='192',
 XY='(-4225,2650)',
 ROT='0',
 VER='1',
 PACK_TYPE='0402LF',
 LOCATION='PR455',
 SEC='1',
 CDS_LIB='pure_quanta',
 CDS_PART_NAME='Q_RES_0402LF-56K,1%,1/16W,CHIP,CS35602FB00',
 PART_NUMBER='CS35602FB00',
 VALUE='56K',
 PRIM_FILE='./archive_libs/logical/q_res/chips/chips.prt';

PART_NAME
 PR460 'Q_RES_0402LF-49.9,1%,1/16W,CHIP,CS04992FB07':;

SECTION_NUMBER 1
 '@T6G_MB_LIB.T6G(SCH_1):PAGE192_I19@PURE_QUANTA.Q_RES(CHIPS)':
 C_PATH='@t6g_mb_lib.t6g(sch_1):page192_i19@pure_quanta.q_res(chips)',
 P_PATH='@t6g_mb_lib.t6g(sch_1):page217_i19@pure_quanta.q_res(chips)',
 PATH='I19',
 DRAWING='@T6G_MB_LIB.T6G(SCH_1):PAGE192',
 WATTAGE='1/16W',
 TOLERANCE='1%',
 MATERIAL='CHIP',
 PHYS_PAGE='217',
 XY='(-3425,3600)',
 ROT='0',
 VER='1',
 PACK_TYPE='0402LF',
 LOCATION='PR460',
 CDS_LIB='pure_quanta',
 CDS_PART_NAME='Q_RES_0402LF-49.9,1%,1/16W,CHIP,CS04992FB07',
 PART_NUMBER='CS04992FB07',
 VALUE='49.9',
 PRIM_FILE='./archive_libs/logical/q_res/chips/chips.prt';

PART_NAME
 PR464 'Q_RES_0402LF-13.7K,1%,1/16W,CHIP,CS31372FB03':;

SECTION_NUMBER 1
 '@T6G_MB_LIB.T6G(SCH_1):PAGE199_I89@PURE_QUANTA.Q_RES(CHIPS)':
 C_PATH='@t6g_mb_lib.t6g(sch_1):page199_i89@pure_quanta.q_res(chips)',
 P_PATH='@t6g_mb_lib.t6g(sch_1):page224_i89@pure_quanta.q_res(chips)',
 PATH='I89',
 DRAWING='@T6G_MB_LIB.T6G(SCH_1):PAGE199',
 WATTAGE='1/16W',
 TOLERANCE='1%',
 MATERIAL='CHIP',
 PHYS_PAGE='224',
 XY='(-5900,1425)',
 ROT='0',
 VER='1',
 PACK_TYPE='0402LF',
 LOCATION='PR464',
 CDS_LIB='pure_quanta',
 CDS_PART_NAME='Q_RES_0402LF-13.7K,1%,1/16W,CHIP,CS31372FB03',
 PART_NUMBER='CS31372FB03',
 VALUE='13.7K',
 PRIM_FILE='./archive_libs/logical/q_res/chips/chips.prt';

PART_NAME
 PR470 'Q_RES_0402LF-10K,1%,1/16W,CHIP,CS31002FB08':;

SECTION_NUMBER 1
 '@T6G_MB_LIB.T6G(SCH_1):PAGE184_I23@PURE_QUANTA.Q_RES(CHIPS)':
 C_PATH='@t6g_mb_lib.t6g(sch_1):page184_i23@pure_quanta.q_res(chips)',
 P_PATH='@t6g_mb_lib.t6g(sch_1):page209_i23@pure_quanta.q_res(chips)',
 PATH='I23',
 DRAWING='@T6G_MB_LIB.T6G(SCH_1):PAGE184',
 WATTAGE='1/16W',
 TOLERANCE='1%',
 MATERIAL='CHIP',
 PHYS_PAGE='209',
 XY='(-4150,2600)',
 ROT='0',
 VER='2',
 PACK_TYPE='0402LF',
 LOCATION='PR470',
 CDS_LIB='pure_quanta',
 CDS_PART_NAME='Q_RES_0402LF-10K,1%,1/16W,CHIP,CS31002FB08',
 PART_NUMBER='CS31002FB08',
 VALUE='10K',
 PRIM_FILE='./archive_libs/logical/q_res/chips/chips.prt';

PART_NAME
 PR471 'Q_RES_0402LF-20K,1%,1/16W,CHIP,CS32002FB06':;

SECTION_NUMBER 1
 '@T6G_MB_LIB.T6G(SCH_1):PAGE184_I35@PURE_QUANTA.Q_RES(CHIPS)':
 C_PATH='@t6g_mb_lib.t6g(sch_1):page184_i35@pure_quanta.q_res(chips)',
 P_PATH='@t6g_mb_lib.t6g(sch_1):page209_i35@pure_quanta.q_res(chips)',
 PATH='I35',
 DRAWING='@T6G_MB_LIB.T6G(SCH_1):PAGE184',
 WATTAGE='1/16W',
 TOLERANCE='1%',
 MATERIAL='CHIP',
 PHYS_PAGE='209',
 XY='(-3575,3125)',
 ROT='0',
 VER='1',
 PACK_TYPE='0402LF',
 LOCATION='PR471',
 CDS_LIB='pure_quanta',
 CDS_PART_NAME='Q_RES_0402LF-20K,1%,1/16W,CHIP,CS32002FB06',
 PART_NUMBER='CS32002FB06',
 VALUE='20K',
 PRIM_FILE='./archive_libs/logical/q_res/chips/chips.prt';

PART_NAME
 PR477 'Q_RES_0402LF-0,5%,1/16W,CHIP,CS00002JB13':;

SECTION_NUMBER 1
 '@T6G_MB_LIB.T6G(SCH_1):PAGE184_I12@PURE_QUANTA.Q_RES(CHIPS)':
 C_PATH='@t6g_mb_lib.t6g(sch_1):page184_i12@pure_quanta.q_res(chips)',
 P_PATH='@t6g_mb_lib.t6g(sch_1):page209_i12@pure_quanta.q_res(chips)',
 PATH='I12',
 DRAWING='@T6G_MB_LIB.T6G(SCH_1):PAGE184',
 WATTAGE='1/16W',
 TOLERANCE='5%',
 MATERIAL='CHIP',
 PHYS_PAGE='209',
 XY='(-7575,2975)',
 ROT='0',
 VER='2',
 PACK_TYPE='0402LF',
 LOCATION='PR477',
 CDS_LIB='pure_quanta',
 CDS_PART_NAME='Q_RES_0402LF-0,5%,1/16W,CHIP,CS00002JB13',
 PART_NUMBER='CS00002JB13',
 VALUE='0',
 PRIM_FILE='./archive_libs/logical/q_res/chips/chips.prt';

PART_NAME
 PR482 'Q_RES_0402LF-1.5,1%,1/8W,EMPTY,CS-1504FB00':;

SECTION_NUMBER 1
 '@T6G_MB_LIB.T6G(SCH_1):PAGE183_I33@PURE_QUANTA.Q_RES(CHIPS)':
 C_PATH='@t6g_mb_lib.t6g(sch_1):page183_i33@pure_quanta.q_res(chips)',
 P_PATH='@t6g_mb_lib.t6g(sch_1):page208_i33@pure_quanta.q_res(chips)',
 PATH='I33',
 DRAWING='@T6G_MB_LIB.T6G(SCH_1):PAGE183',
 WATTAGE='1/8W',
 TOLERANCE='1%',
 MATERIAL='EMPTY',
 PHYS_PAGE='208',
 XY='(-4650,3750)',
 ROT='0',
 VER='2',
 PACK_TYPE='0402LF',
 LOCATION='PR482',
 CDS_LIB='pure_quanta',
 CDS_PART_NAME='Q_RES_0402LF-1.5,1%,1/8W,EMPTY,CS-1504FB00',
 PART_NUMBER='CS-1504FB00',
 VALUE='1.5',
 PRIM_FILE='./archive_libs/logical/q_res/chips/chips.prt';

PART_NAME
 PR485 'Q_RES_0402LF-1.5,1%,1/8W,EMPTY,CS-1504FB00':;

SECTION_NUMBER 1
 '@T6G_MB_LIB.T6G(SCH_1):PAGE186_I34@PURE_QUANTA.Q_RES(CHIPS)':
 C_PATH='@t6g_mb_lib.t6g(sch_1):page186_i34@pure_quanta.q_res(chips)',
 P_PATH='@t6g_mb_lib.t6g(sch_1):page211_i34@pure_quanta.q_res(chips)',
 PATH='I34',
 DRAWING='@T6G_MB_LIB.T6G(SCH_1):PAGE186',
 WATTAGE='1/8W',
 TOLERANCE='1%',
 MATERIAL='EMPTY',
 PHYS_PAGE='211',
 XY='(-4800,3775)',
 ROT='0',
 VER='2',
 PACK_TYPE='0402LF',
 LOCATION='PR485',
 CDS_LIB='pure_quanta',
 CDS_PART_NAME='Q_RES_0402LF-1.5,1%,1/8W,EMPTY,CS-1504FB00',
 PART_NUMBER='CS-1504FB00',
 VALUE='1.5',
 PRIM_FILE='./archive_libs/logical/q_res/chips/chips.prt';

PART_NAME
 PR486 'Q_RES_0402LF-1.5,1%,1/8W,EMPTY,CS-1504FB00':;

SECTION_NUMBER 1
 '@T6G_MB_LIB.T6G(SCH_1):PAGE186_I22@PURE_QUANTA.Q_RES(CHIPS)':
 C_PATH='@t6g_mb_lib.t6g(sch_1):page186_i22@pure_quanta.q_res(chips)',
 P_PATH='@t6g_mb_lib.t6g(sch_1):page211_i22@pure_quanta.q_res(chips)',
 PATH='I22',
 DRAWING='@T6G_MB_LIB.T6G(SCH_1):PAGE186',
 WATTAGE='1/8W',
 TOLERANCE='1%',
 MATERIAL='EMPTY',
 PHYS_PAGE='211',
 XY='(-4650,1000)',
 ROT='0',
 VER='2',
 PACK_TYPE='0402LF',
 LOCATION='PR486',
 CDS_LIB='pure_quanta',
 CDS_PART_NAME='Q_RES_0402LF-1.5,1%,1/8W,EMPTY,CS-1504FB00',
 PART_NUMBER='CS-1504FB00',
 VALUE='1.5',
 PRIM_FILE='./archive_libs/logical/q_res/chips/chips.prt';

PART_NAME
 PR488 'Q_RES_0402LF-1.5,1%,1/8W,EMPTY,CS-1504FB00':;

SECTION_NUMBER 1
 '@T6G_MB_LIB.T6G(SCH_1):PAGE197_I26@PURE_QUANTA.Q_RES(CHIPS)':
 C_PATH='@t6g_mb_lib.t6g(sch_1):page197_i26@pure_quanta.q_res(chips)',
 P_PATH='@t6g_mb_lib.t6g(sch_1):page222_i26@pure_quanta.q_res(chips)',
 PATH='I26',
 DRAWING='@T6G_MB_LIB.T6G(SCH_1):PAGE197',
 WATTAGE='1/8W',
 TOLERANCE='1%',
 MATERIAL='EMPTY',
 PHYS_PAGE='222',
 XY='(4125,4300)',
 ROT='0',
 VER='2',
 PACK_TYPE='0402LF',
 LOCATION='PR488',
 CDS_LIB='pure_quanta',
 CDS_PART_NAME='Q_RES_0402LF-1.5,1%,1/8W,EMPTY,CS-1504FB00',
 PART_NUMBER='CS-1504FB00',
 VALUE='1.5',
 PRIM_FILE='./archive_libs/logical/q_res/chips/chips.prt';

PART_NAME
 PR489 'Q_RES_0402LF-1.5,1%,1/8W,EMPTY,CS-1504FB00':;

SECTION_NUMBER 1
 '@T6G_MB_LIB.T6G(SCH_1):PAGE197_I19@PURE_QUANTA.Q_RES(CHIPS)':
 C_PATH='@t6g_mb_lib.t6g(sch_1):page197_i19@pure_quanta.q_res(chips)',
 P_PATH='@t6g_mb_lib.t6g(sch_1):page222_i19@pure_quanta.q_res(chips)',
 PATH='I19',
 DRAWING='@T6G_MB_LIB.T6G(SCH_1):PAGE197',
 WATTAGE='1/8W',
 TOLERANCE='1%',
 MATERIAL='EMPTY',
 PHYS_PAGE='222',
 XY='(4025,1550)',
 ROT='0',
 VER='2',
 PACK_TYPE='0402LF',
 LOCATION='PR489',
 CDS_LIB='pure_quanta',
 CDS_PART_NAME='Q_RES_0402LF-1.5,1%,1/8W,EMPTY,CS-1504FB00',
 PART_NUMBER='CS-1504FB00',
 VALUE='1.5',
 PRIM_FILE='./archive_libs/logical/q_res/chips/chips.prt';

PART_NAME
 PR491 'Q_RES_0402LF-1.5,1%,1/8W,EMPTY,CS-1504FB00':;

SECTION_NUMBER 1
 '@T6G_MB_LIB.T6G(SCH_1):PAGE198_I39@PURE_QUANTA.Q_RES(CHIPS)':
 C_PATH='@t6g_mb_lib.t6g(sch_1):page198_i39@pure_quanta.q_res(chips)',
 P_PATH='@t6g_mb_lib.t6g(sch_1):page223_i39@pure_quanta.q_res(chips)',
 PATH='I39',
 DRAWING='@T6G_MB_LIB.T6G(SCH_1):PAGE198',
 WATTAGE='1/8W',
 TOLERANCE='1%',
 MATERIAL='EMPTY',
 PHYS_PAGE='223',
 XY='(-8025,1600)',
 ROT='0',
 VER='2',
 PACK_TYPE='0402LF',
 LOCATION='PR491',
 CDS_LIB='pure_quanta',
 CDS_PART_NAME='Q_RES_0402LF-1.5,1%,1/8W,EMPTY,CS-1504FB00',
 PART_NUMBER='CS-1504FB00',
 VALUE='1.5',
 PRIM_FILE='./archive_libs/logical/q_res/chips/chips.prt';

PART_NAME
 PR492 'Q_RES_0402LF-1.5,1%,1/8W,EMPTY,CS-1504FB00':;

SECTION_NUMBER 1
 '@T6G_MB_LIB.T6G(SCH_1):PAGE198_I57@PURE_QUANTA.Q_RES(CHIPS)':
 C_PATH='@t6g_mb_lib.t6g(sch_1):page198_i57@pure_quanta.q_res(chips)',
 P_PATH='@t6g_mb_lib.t6g(sch_1):page223_i57@pure_quanta.q_res(chips)',
 PATH='I57',
 DRAWING='@T6G_MB_LIB.T6G(SCH_1):PAGE198',
 WATTAGE='1/8W',
 TOLERANCE='1%',
 MATERIAL='EMPTY',
 PHYS_PAGE='223',
 XY='(-7925,4400)',
 ROT='0',
 VER='2',
 PACK_TYPE='0402LF',
 LOCATION='PR492',
 CDS_LIB='pure_quanta',
 CDS_PART_NAME='Q_RES_0402LF-1.5,1%,1/8W,EMPTY,CS-1504FB00',
 PART_NUMBER='CS-1504FB00',
 VALUE='1.5',
 PRIM_FILE='./archive_libs/logical/q_res/chips/chips.prt';

PART_NAME
 PR495 'Q_RES_0402LF-1.5,1%,1/8W,EMPTY,CS-1504FB00':;

SECTION_NUMBER 1
 '@T6G_MB_LIB.T6G(SCH_1):PAGE169_I42@PURE_QUANTA.Q_RES(CHIPS)':
 C_PATH='@t6g_mb_lib.t6g(sch_1):page169_i42@pure_quanta.q_res(chips)',
 P_PATH='@t6g_mb_lib.t6g(sch_1):page194_i42@pure_quanta.q_res(chips)',
 PATH='I42',
 DRAWING='@T6G_MB_LIB.T6G(SCH_1):PAGE169',
 WATTAGE='1/8W',
 TOLERANCE='1%',
 MATERIAL='EMPTY',
 PHYS_PAGE='194',
 XY='(-4825,3725)',
 ROT='0',
 VER='2',
 PACK_TYPE='0402LF',
 LOCATION='PR495',
 CDS_LIB='pure_quanta',
 CDS_PART_NAME='Q_RES_0402LF-1.5,1%,1/8W,EMPTY,CS-1504FB00',
 PART_NUMBER='CS-1504FB00',
 VALUE='1.5',
 PRIM_FILE='./archive_libs/logical/q_res/chips/chips.prt';

PART_NAME
 PR496 'Q_RES_0402LF-1.5,1%,1/8W,EMPTY,CS-1504FB00':;

SECTION_NUMBER 1
 '@T6G_MB_LIB.T6G(SCH_1):PAGE169_I28@PURE_QUANTA.Q_RES(CHIPS)':
 C_PATH='@t6g_mb_lib.t6g(sch_1):page169_i28@pure_quanta.q_res(chips)',
 P_PATH='@t6g_mb_lib.t6g(sch_1):page194_i28@pure_quanta.q_res(chips)',
 PATH='I28',
 DRAWING='@T6G_MB_LIB.T6G(SCH_1):PAGE169',
 WATTAGE='1/8W',
 TOLERANCE='1%',
 MATERIAL='EMPTY',
 PHYS_PAGE='194',
 XY='(-4650,975)',
 ROT='0',
 VER='2',
 PACK_TYPE='0402LF',
 LOCATION='PR496',
 CDS_LIB='pure_quanta',
 CDS_PART_NAME='Q_RES_0402LF-1.5,1%,1/8W,EMPTY,CS-1504FB00',
 PART_NUMBER='CS-1504FB00',
 VALUE='1.5',
 PRIM_FILE='./archive_libs/logical/q_res/chips/chips.prt';

PART_NAME
 PR498 'Q_RES_0402LF-1.5,1%,1/8W,EMPTY,CS-1504FB00':;

SECTION_NUMBER 1
 '@T6G_MB_LIB.T6G(SCH_1):PAGE170_I44@PURE_QUANTA.Q_RES(CHIPS)':
 C_PATH='@t6g_mb_lib.t6g(sch_1):page170_i44@pure_quanta.q_res(chips)',
 P_PATH='@t6g_mb_lib.t6g(sch_1):page195_i44@pure_quanta.q_res(chips)',
 PATH='I44',
 DRAWING='@T6G_MB_LIB.T6G(SCH_1):PAGE170',
 WATTAGE='1/8W',
 TOLERANCE='1%',
 MATERIAL='EMPTY',
 PHYS_PAGE='195',
 XY='(-4375,4150)',
 ROT='0',
 VER='2',
 PACK_TYPE='0402LF',
 LOCATION='PR498',
 CDS_LIB='pure_quanta',
 CDS_PART_NAME='Q_RES_0402LF-1.5,1%,1/8W,EMPTY,CS-1504FB00',
 PART_NUMBER='CS-1504FB00',
 VALUE='1.5',
 PRIM_FILE='./archive_libs/logical/q_res/chips/chips.prt';

PART_NAME
 PR499 'Q_RES_0402LF-1.5,1%,1/8W,EMPTY,CS-1504FB00':;

SECTION_NUMBER 1
 '@T6G_MB_LIB.T6G(SCH_1):PAGE170_I18@PURE_QUANTA.Q_RES(CHIPS)':
 C_PATH='@t6g_mb_lib.t6g(sch_1):page170_i18@pure_quanta.q_res(chips)',
 P_PATH='@t6g_mb_lib.t6g(sch_1):page195_i18@pure_quanta.q_res(chips)',
 PATH='I18',
 DRAWING='@T6G_MB_LIB.T6G(SCH_1):PAGE170',
 WATTAGE='1/8W',
 TOLERANCE='1%',
 MATERIAL='EMPTY',
 PHYS_PAGE='195',
 XY='(-4300,875)',
 ROT='0',
 VER='2',
 PACK_TYPE='0402LF',
 LOCATION='PR499',
 CDS_LIB='pure_quanta',
 CDS_PART_NAME='Q_RES_0402LF-1.5,1%,1/8W,EMPTY,CS-1504FB00',
 PART_NUMBER='CS-1504FB00',
 VALUE='1.5',
 PRIM_FILE='./archive_libs/logical/q_res/chips/chips.prt';

PART_NAME
 PR500 'Q_RES_0402LF-1.5,1%,1/8W,EMPTY,CS-1504FB00':;

SECTION_NUMBER 1
 '@T6G_MB_LIB.T6G(SCH_1):PAGE171_I22@PURE_QUANTA.Q_RES(CHIPS)':
 C_PATH='@t6g_mb_lib.t6g(sch_1):page171_i22@pure_quanta.q_res(chips)',
 P_PATH='@t6g_mb_lib.t6g(sch_1):page196_i22@pure_quanta.q_res(chips)',
 PATH='I22',
 DRAWING='@T6G_MB_LIB.T6G(SCH_1):PAGE171',
 WATTAGE='1/8W',
 TOLERANCE='1%',
 MATERIAL='EMPTY',
 PHYS_PAGE='196',
 XY='(-4225,1175)',
 ROT='0',
 VER='2',
 PACK_TYPE='0402LF',
 LOCATION='PR500',
 CDS_LIB='pure_quanta',
 CDS_PART_NAME='Q_RES_0402LF-1.5,1%,1/8W,EMPTY,CS-1504FB00',
 PART_NUMBER='CS-1504FB00',
 VALUE='1.5',
 PRIM_FILE='./archive_libs/logical/q_res/chips/chips.prt';

PART_NAME
 PR501 'Q_RES_0402LF-1.5,1%,1/8W,EMPTY,CS-1504FB00':;

SECTION_NUMBER 1
 '@T6G_MB_LIB.T6G(SCH_1):PAGE171_I31@PURE_QUANTA.Q_RES(CHIPS)':
 C_PATH='@t6g_mb_lib.t6g(sch_1):page171_i31@pure_quanta.q_res(chips)',
 P_PATH='@t6g_mb_lib.t6g(sch_1):page196_i31@pure_quanta.q_res(chips)',
 PATH='I31',
 DRAWING='@T6G_MB_LIB.T6G(SCH_1):PAGE171',
 WATTAGE='1/8W',
 TOLERANCE='1%',
 MATERIAL='EMPTY',
 PHYS_PAGE='196',
 XY='(-4200,3950)',
 ROT='0',
 VER='2',
 PACK_TYPE='0402LF',
 LOCATION='PR501',
 CDS_LIB='pure_quanta',
 CDS_PART_NAME='Q_RES_0402LF-1.5,1%,1/8W,EMPTY,CS-1504FB00',
 PART_NUMBER='CS-1504FB00',
 VALUE='1.5',
 PRIM_FILE='./archive_libs/logical/q_res/chips/chips.prt';

PART_NAME
 PR502 'Q_RES_0402LF-1.5,1%,1/8W,EMPTY,CS-1504FB00':;

SECTION_NUMBER 1
 '@T6G_MB_LIB.T6G(SCH_1):PAGE173_I45@PURE_QUANTA.Q_RES(CHIPS)':
 C_PATH='@t6g_mb_lib.t6g(sch_1):page173_i45@pure_quanta.q_res(chips)',
 P_PATH='@t6g_mb_lib.t6g(sch_1):page198_i45@pure_quanta.q_res(chips)',
 PATH='I45',
 DRAWING='@T6G_MB_LIB.T6G(SCH_1):PAGE173',
 WATTAGE='1/8W',
 TOLERANCE='1%',
 MATERIAL='EMPTY',
 PHYS_PAGE='198',
 XY='(-4475,4375)',
 ROT='0',
 VER='2',
 PACK_TYPE='0402LF',
 LOCATION='PR502',
 CDS_LIB='pure_quanta',
 CDS_PART_NAME='Q_RES_0402LF-1.5,1%,1/8W,EMPTY,CS-1504FB00',
 PART_NUMBER='CS-1504FB00',
 VALUE='1.5',
 PRIM_FILE='./archive_libs/logical/q_res/chips/chips.prt';

PART_NAME
 PR503 'Q_RES_0402LF-1.5,1%,1/8W,EMPTY,CS-1504FB00':;

SECTION_NUMBER 1
 '@T6G_MB_LIB.T6G(SCH_1):PAGE173_I19@PURE_QUANTA.Q_RES(CHIPS)':
 C_PATH='@t6g_mb_lib.t6g(sch_1):page173_i19@pure_quanta.q_res(chips)',
 P_PATH='@t6g_mb_lib.t6g(sch_1):page198_i19@pure_quanta.q_res(chips)',
 PATH='I19',
 DRAWING='@T6G_MB_LIB.T6G(SCH_1):PAGE173',
 WATTAGE='1/8W',
 TOLERANCE='1%',
 MATERIAL='EMPTY',
 PHYS_PAGE='198',
 XY='(-4500,1300)',
 ROT='0',
 VER='2',
 PACK_TYPE='0402LF',
 LOCATION='PR503',
 CDS_LIB='pure_quanta',
 CDS_PART_NAME='Q_RES_0402LF-1.5,1%,1/8W,EMPTY,CS-1504FB00',
 PART_NUMBER='CS-1504FB00',
 VALUE='1.5',
 PRIM_FILE='./archive_libs/logical/q_res/chips/chips.prt';

PART_NAME
 PR505 'Q_RES_0402LF-1.5,1%,1/8W,EMPTY,CS-1504FB00':;

SECTION_NUMBER 1
 '@T6G_MB_LIB.T6G(SCH_1):PAGE174_I10@PURE_QUANTA.Q_RES(CHIPS)':
 C_PATH='@t6g_mb_lib.t6g(sch_1):page174_i10@pure_quanta.q_res(chips)',
 P_PATH='@t6g_mb_lib.t6g(sch_1):page199_i10@pure_quanta.q_res(chips)',
 PATH='I10',
 DRAWING='@T6G_MB_LIB.T6G(SCH_1):PAGE174',
 WATTAGE='1/8W',
 TOLERANCE='1%',
 MATERIAL='EMPTY',
 PHYS_PAGE='199',
 XY='(-4375,3575)',
 ROT='0',
 VER='2',
 PACK_TYPE='0402LF',
 LOCATION='PR505',
 CDS_LIB='pure_quanta',
 CDS_PART_NAME='Q_RES_0402LF-1.5,1%,1/8W,EMPTY,CS-1504FB00',
 PART_NUMBER='CS-1504FB00',
 VALUE='1.5',
 PRIM_FILE='./archive_libs/logical/q_res/chips/chips.prt';

PART_NAME
 PR506 'Q_RES_0402LF-1.5,1%,1/8W,EMPTY,CS-1504FB00':;

SECTION_NUMBER 1
 '@T6G_MB_LIB.T6G(SCH_1):PAGE176_I50@PURE_QUANTA.Q_RES(CHIPS)':
 C_PATH='@t6g_mb_lib.t6g(sch_1):page176_i50@pure_quanta.q_res(chips)',
 P_PATH='@t6g_mb_lib.t6g(sch_1):page201_i50@pure_quanta.q_res(chips)',
 PATH='I50',
 DRAWING='@T6G_MB_LIB.T6G(SCH_1):PAGE176',
 WATTAGE='1/8W',
 TOLERANCE='1%',
 MATERIAL='EMPTY',
 PHYS_PAGE='201',
 XY='(-5875,3500)',
 ROT='0',
 VER='2',
 PACK_TYPE='0402LF',
 LOCATION='PR506',
 CDS_LIB='pure_quanta',
 CDS_PART_NAME='Q_RES_0402LF-1.5,1%,1/8W,EMPTY,CS-1504FB00',
 PART_NUMBER='CS-1504FB00',
 VALUE='1.5',
 PRIM_FILE='./archive_libs/logical/q_res/chips/chips.prt';

PART_NAME
 PR507 'Q_RES_0402LF-1.5,1%,1/8W,EMPTY,CS-1504FB00':;

SECTION_NUMBER 1
 '@T6G_MB_LIB.T6G(SCH_1):PAGE176_I39@PURE_QUANTA.Q_RES(CHIPS)':
 C_PATH='@t6g_mb_lib.t6g(sch_1):page176_i39@pure_quanta.q_res(chips)',
 P_PATH='@t6g_mb_lib.t6g(sch_1):page201_i39@pure_quanta.q_res(chips)',
 PATH='I39',
 DRAWING='@T6G_MB_LIB.T6G(SCH_1):PAGE176',
 WATTAGE='1/8W',
 TOLERANCE='1%',
 MATERIAL='EMPTY',
 PHYS_PAGE='201',
 XY='(-5875,550)',
 ROT='0',
 VER='2',
 PACK_TYPE='0402LF',
 LOCATION='PR507',
 CDS_LIB='pure_quanta',
 CDS_PART_NAME='Q_RES_0402LF-1.5,1%,1/8W,EMPTY,CS-1504FB00',
 PART_NUMBER='CS-1504FB00',
 VALUE='1.5',
 PRIM_FILE='./archive_libs/logical/q_res/chips/chips.prt';

PART_NAME
 PR509 'Q_RES_0402LF-1.5,1%,1/8W,EMPTY,CS-1504FB00':;

SECTION_NUMBER 1
 '@T6G_MB_LIB.T6G(SCH_1):PAGE177_I36@PURE_QUANTA.Q_RES(CHIPS)':
 C_PATH='@t6g_mb_lib.t6g(sch_1):page177_i36@pure_quanta.q_res(chips)',
 P_PATH='@t6g_mb_lib.t6g(sch_1):page202_i36@pure_quanta.q_res(chips)',
 PATH='I36',
 DRAWING='@T6G_MB_LIB.T6G(SCH_1):PAGE177',
 WATTAGE='1/8W',
 TOLERANCE='1%',
 MATERIAL='EMPTY',
 PHYS_PAGE='202',
 XY='(4650,825)',
 ROT='0',
 VER='2',
 PACK_TYPE='0402LF',
 LOCATION='PR509',
 CDS_LIB='pure_quanta',
 CDS_PART_NAME='Q_RES_0402LF-1.5,1%,1/8W,EMPTY,CS-1504FB00',
 PART_NUMBER='CS-1504FB00',
 VALUE='1.5',
 PRIM_FILE='./archive_libs/logical/q_res/chips/chips.prt';

PART_NAME
 PR510 'Q_RES_0402LF-1.5,1%,1/8W,EMPTY,CS-1504FB00':;

SECTION_NUMBER 1
 '@T6G_MB_LIB.T6G(SCH_1):PAGE177_I46@PURE_QUANTA.Q_RES(CHIPS)':
 C_PATH='@t6g_mb_lib.t6g(sch_1):page177_i46@pure_quanta.q_res(chips)',
 P_PATH='@t6g_mb_lib.t6g(sch_1):page202_i46@pure_quanta.q_res(chips)',
 PATH='I46',
 DRAWING='@T6G_MB_LIB.T6G(SCH_1):PAGE177',
 WATTAGE='1/8W',
 TOLERANCE='1%',
 MATERIAL='EMPTY',
 PHYS_PAGE='202',
 XY='(4700,3600)',
 ROT='0',
 VER='2',
 PACK_TYPE='0402LF',
 LOCATION='PR510',
 CDS_LIB='pure_quanta',
 CDS_PART_NAME='Q_RES_0402LF-1.5,1%,1/8W,EMPTY,CS-1504FB00',
 PART_NUMBER='CS-1504FB00',
 VALUE='1.5',
 PRIM_FILE='./archive_libs/logical/q_res/chips/chips.prt';

PART_NAME
 PR511 'Q_RES_0402LF-1.5,1%,1/8W,EMPTY,CS-1504FB00':;

SECTION_NUMBER 1
 '@T6G_MB_LIB.T6G(SCH_1):PAGE191_I10@PURE_QUANTA.Q_RES(CHIPS)':
 C_PATH='@t6g_mb_lib.t6g(sch_1):page191_i10@pure_quanta.q_res(chips)',
 P_PATH='@t6g_mb_lib.t6g(sch_1):page216_i10@pure_quanta.q_res(chips)',
 PATH='I10',
 DRAWING='@T6G_MB_LIB.T6G(SCH_1):PAGE191',
 WATTAGE='1/8W',
 TOLERANCE='1%',
 MATERIAL='EMPTY',
 PHYS_PAGE='216',
 XY='(-4450,3775)',
 ROT='0',
 VER='2',
 PACK_TYPE='0402LF',
 LOCATION='PR511',
 CDS_LIB='pure_quanta',
 CDS_PART_NAME='Q_RES_0402LF-1.5,1%,1/8W,EMPTY,CS-1504FB00',
 PART_NUMBER='CS-1504FB00',
 VALUE='1.5',
 PRIM_FILE='./archive_libs/logical/q_res/chips/chips.prt';

PART_NAME
 PR512 'Q_RES_0402LF-1.5,1%,1/8W,EMPTY,CS-1504FB00':;

SECTION_NUMBER 1
 '@T6G_MB_LIB.T6G(SCH_1):PAGE193_I45@PURE_QUANTA.Q_RES(CHIPS)':
 C_PATH='@t6g_mb_lib.t6g(sch_1):page193_i45@pure_quanta.q_res(chips)',
 P_PATH='@t6g_mb_lib.t6g(sch_1):page218_i45@pure_quanta.q_res(chips)',
 PATH='I45',
 DRAWING='@T6G_MB_LIB.T6G(SCH_1):PAGE193',
 WATTAGE='1/8W',
 TOLERANCE='1%',
 MATERIAL='EMPTY',
 PHYS_PAGE='218',
 XY='(-5325,3875)',
 ROT='0',
 VER='2',
 PACK_TYPE='0402LF',
 LOCATION='PR512',
 CDS_LIB='pure_quanta',
 CDS_PART_NAME='Q_RES_0402LF-1.5,1%,1/8W,EMPTY,CS-1504FB00',
 PART_NUMBER='CS-1504FB00',
 VALUE='1.5',
 PRIM_FILE='./archive_libs/logical/q_res/chips/chips.prt';

PART_NAME
 PR513 'Q_RES_0402LF-1.5,1%,1/8W,EMPTY,CS-1504FB00':;

SECTION_NUMBER 1
 '@T6G_MB_LIB.T6G(SCH_1):PAGE193_I36@PURE_QUANTA.Q_RES(CHIPS)':
 C_PATH='@t6g_mb_lib.t6g(sch_1):page193_i36@pure_quanta.q_res(chips)',
 P_PATH='@t6g_mb_lib.t6g(sch_1):page218_i36@pure_quanta.q_res(chips)',
 PATH='I36',
 DRAWING='@T6G_MB_LIB.T6G(SCH_1):PAGE193',
 WATTAGE='1/8W',
 TOLERANCE='1%',
 MATERIAL='EMPTY',
 PHYS_PAGE='218',
 XY='(-5375,1250)',
 ROT='0',
 VER='2',
 PACK_TYPE='0402LF',
 LOCATION='PR513',
 CDS_LIB='pure_quanta',
 CDS_PART_NAME='Q_RES_0402LF-1.5,1%,1/8W,EMPTY,CS-1504FB00',
 PART_NUMBER='CS-1504FB00',
 VALUE='1.5',
 PRIM_FILE='./archive_libs/logical/q_res/chips/chips.prt';

PART_NAME
 PR515 'Q_RES_0402LF-1.5,1%,1/8W,EMPTY,CS-1504FB00':;

SECTION_NUMBER 1
 '@T6G_MB_LIB.T6G(SCH_1):PAGE194_I35@PURE_QUANTA.Q_RES(CHIPS)':
 C_PATH='@t6g_mb_lib.t6g(sch_1):page194_i35@pure_quanta.q_res(chips)',
 P_PATH='@t6g_mb_lib.t6g(sch_1):page219_i35@pure_quanta.q_res(chips)',
 PATH='I35',
 DRAWING='@T6G_MB_LIB.T6G(SCH_1):PAGE194',
 WATTAGE='1/8W',
 TOLERANCE='1%',
 MATERIAL='EMPTY',
 PHYS_PAGE='219',
 XY='(4675,775)',
 ROT='0',
 VER='2',
 PACK_TYPE='0402LF',
 LOCATION='PR515',
 CDS_LIB='pure_quanta',
 CDS_PART_NAME='Q_RES_0402LF-1.5,1%,1/8W,EMPTY,CS-1504FB00',
 PART_NUMBER='CS-1504FB00',
 VALUE='1.5',
 PRIM_FILE='./archive_libs/logical/q_res/chips/chips.prt';

PART_NAME
 PR516 'Q_RES_0402LF-1.5,1%,1/8W,EMPTY,CS-1504FB00':;

SECTION_NUMBER 1
 '@T6G_MB_LIB.T6G(SCH_1):PAGE194_I44@PURE_QUANTA.Q_RES(CHIPS)':
 C_PATH='@t6g_mb_lib.t6g(sch_1):page194_i44@pure_quanta.q_res(chips)',
 P_PATH='@t6g_mb_lib.t6g(sch_1):page219_i44@pure_quanta.q_res(chips)',
 PATH='I44',
 DRAWING='@T6G_MB_LIB.T6G(SCH_1):PAGE194',
 WATTAGE='1/8W',
 TOLERANCE='1%',
 MATERIAL='EMPTY',
 PHYS_PAGE='219',
 XY='(4775,3550)',
 ROT='0',
 VER='2',
 PACK_TYPE='0402LF',
 LOCATION='PR516',
 CDS_LIB='pure_quanta',
 CDS_PART_NAME='Q_RES_0402LF-1.5,1%,1/8W,EMPTY,CS-1504FB00',
 PART_NUMBER='CS-1504FB00',
 VALUE='1.5',
 PRIM_FILE='./archive_libs/logical/q_res/chips/chips.prt';

PART_NAME
 PR517 'Q_RES_0402LF-1.5,1%,1/8W,EMPTY,CS-1504FB00':;

SECTION_NUMBER 1
 '@T6G_MB_LIB.T6G(SCH_1):PAGE195_I43@PURE_QUANTA.Q_RES(CHIPS)':
 C_PATH='@t6g_mb_lib.t6g(sch_1):page195_i43@pure_quanta.q_res(chips)',
 P_PATH='@t6g_mb_lib.t6g(sch_1):page220_i43@pure_quanta.q_res(chips)',
 PATH='I43',
 DRAWING='@T6G_MB_LIB.T6G(SCH_1):PAGE195',
 WATTAGE='1/8W',
 TOLERANCE='1%',
 MATERIAL='EMPTY',
 PHYS_PAGE='220',
 XY='(4650,4175)',
 ROT='0',
 VER='2',
 PACK_TYPE='0402LF',
 LOCATION='PR517',
 CDS_LIB='pure_quanta',
 CDS_PART_NAME='Q_RES_0402LF-1.5,1%,1/8W,EMPTY,CS-1504FB00',
 PART_NUMBER='CS-1504FB00',
 VALUE='1.5',
 PRIM_FILE='./archive_libs/logical/q_res/chips/chips.prt';

PART_NAME
 PR518 'Q_RES_0402LF-1.5,1%,1/8W,EMPTY,CS-1504FB00':;

SECTION_NUMBER 1
 '@T6G_MB_LIB.T6G(SCH_1):PAGE195_I33@PURE_QUANTA.Q_RES(CHIPS)':
 C_PATH='@t6g_mb_lib.t6g(sch_1):page195_i33@pure_quanta.q_res(chips)',
 P_PATH='@t6g_mb_lib.t6g(sch_1):page220_i33@pure_quanta.q_res(chips)',
 PATH='I33',
 DRAWING='@T6G_MB_LIB.T6G(SCH_1):PAGE195',
 WATTAGE='1/8W',
 TOLERANCE='1%',
 MATERIAL='EMPTY',
 PHYS_PAGE='220',
 XY='(4725,1500)',
 ROT='0',
 VER='2',
 PACK_TYPE='0402LF',
 LOCATION='PR518',
 CDS_LIB='pure_quanta',
 CDS_PART_NAME='Q_RES_0402LF-1.5,1%,1/8W,EMPTY,CS-1504FB00',
 PART_NUMBER='CS-1504FB00',
 VALUE='1.5',
 PRIM_FILE='./archive_libs/logical/q_res/chips/chips.prt';

PART_NAME
 PR519 'Q_RES_0402LF-1.5,1%,1/8W,EMPTY,CS-1504FB00':;

SECTION_NUMBER 1
 '@T6G_MB_LIB.T6G(SCH_1):PAGE200_I25@PURE_QUANTA.Q_RES(CHIPS)':
 C_PATH='@t6g_mb_lib.t6g(sch_1):page200_i25@pure_quanta.q_res(chips)',
 P_PATH='@t6g_mb_lib.t6g(sch_1):page225_i25@pure_quanta.q_res(chips)',
 PATH='I25',
 DRAWING='@T6G_MB_LIB.T6G(SCH_1):PAGE200',
 WATTAGE='1/8W',
 TOLERANCE='1%',
 MATERIAL='EMPTY',
 PHYS_PAGE='225',
 XY='(-4550,1025)',
 ROT='0',
 VER='2',
 PACK_TYPE='0402LF',
 LOCATION='PR519',
 CDS_LIB='pure_quanta',
 CDS_PART_NAME='Q_RES_0402LF-1.5,1%,1/8W,EMPTY,CS-1504FB00',
 PART_NUMBER='CS-1504FB00',
 VALUE='1.5',
 PRIM_FILE='./archive_libs/logical/q_res/chips/chips.prt';

PART_NAME
 PR520 'Q_RES_0402LF-1.5,1%,1/8W,EMPTY,CS-1504FB00':;

SECTION_NUMBER 1
 '@T6G_MB_LIB.T6G(SCH_1):PAGE200_I33@PURE_QUANTA.Q_RES(CHIPS)':
 C_PATH='@t6g_mb_lib.t6g(sch_1):page200_i33@pure_quanta.q_res(chips)',
 P_PATH='@t6g_mb_lib.t6g(sch_1):page225_i33@pure_quanta.q_res(chips)',
 PATH='I33',
 DRAWING='@T6G_MB_LIB.T6G(SCH_1):PAGE200',
 WATTAGE='1/8W',
 TOLERANCE='1%',
 MATERIAL='EMPTY',
 PHYS_PAGE='225',
 XY='(-4600,3900)',
 ROT='0',
 VER='2',
 PACK_TYPE='0402LF',
 LOCATION='PR520',
 CDS_LIB='pure_quanta',
 CDS_PART_NAME='Q_RES_0402LF-1.5,1%,1/8W,EMPTY,CS-1504FB00',
 PART_NUMBER='CS-1504FB00',
 VALUE='1.5',
 PRIM_FILE='./archive_libs/logical/q_res/chips/chips.prt';

PART_NAME
 PR522 'Q_RES_0402LF-1.5,1%,1/8W,EMPTY,CS-1504FB00':;

SECTION_NUMBER 1
 '@T6G_MB_LIB.T6G(SCH_1):PAGE187_I45@PURE_QUANTA.Q_RES(CHIPS)':
 C_PATH='@t6g_mb_lib.t6g(sch_1):page187_i45@pure_quanta.q_res(chips)',
 P_PATH='@t6g_mb_lib.t6g(sch_1):page212_i45@pure_quanta.q_res(chips)',
 PATH='I45',
 DRAWING='@T6G_MB_LIB.T6G(SCH_1):PAGE187',
 WATTAGE='1/8W',
 TOLERANCE='1%',
 MATERIAL='EMPTY',
 PHYS_PAGE='212',
 XY='(-4250,4175)',
 ROT='0',
 VER='2',
 PACK_TYPE='0402LF',
 LOCATION='PR522',
 CDS_LIB='pure_quanta',
 CDS_PART_NAME='Q_RES_0402LF-1.5,1%,1/8W,EMPTY,CS-1504FB00',
 PART_NUMBER='CS-1504FB00',
 VALUE='1.5',
 PRIM_FILE='./archive_libs/logical/q_res/chips/chips.prt';

PART_NAME
 PR523 'Q_RES_0402LF-1.5,1%,1/8W,EMPTY,CS-1504FB00':;

SECTION_NUMBER 1
 '@T6G_MB_LIB.T6G(SCH_1):PAGE187_I19@PURE_QUANTA.Q_RES(CHIPS)':
 C_PATH='@t6g_mb_lib.t6g(sch_1):page187_i19@pure_quanta.q_res(chips)',
 P_PATH='@t6g_mb_lib.t6g(sch_1):page212_i19@pure_quanta.q_res(chips)',
 PATH='I19',
 DRAWING='@T6G_MB_LIB.T6G(SCH_1):PAGE187',
 WATTAGE='1/8W',
 TOLERANCE='1%',
 MATERIAL='EMPTY',
 PHYS_PAGE='212',
 XY='(-4250,875)',
 ROT='0',
 VER='2',
 PACK_TYPE='0402LF',
 LOCATION='PR523',
 CDS_LIB='pure_quanta',
 CDS_PART_NAME='Q_RES_0402LF-1.5,1%,1/8W,EMPTY,CS-1504FB00',
 PART_NUMBER='CS-1504FB00',
 VALUE='1.5',
 PRIM_FILE='./archive_libs/logical/q_res/chips/chips.prt';

PART_NAME
 PR524 'Q_RES_0402LF-1.5,1%,1/8W,EMPTY,CS-1504FB00':;

SECTION_NUMBER 1
 '@T6G_MB_LIB.T6G(SCH_1):PAGE188_I21@PURE_QUANTA.Q_RES(CHIPS)':
 C_PATH='@t6g_mb_lib.t6g(sch_1):page188_i21@pure_quanta.q_res(chips)',
 P_PATH='@t6g_mb_lib.t6g(sch_1):page213_i21@pure_quanta.q_res(chips)',
 PATH='I21',
 DRAWING='@T6G_MB_LIB.T6G(SCH_1):PAGE188',
 WATTAGE='1/8W',
 TOLERANCE='1%',
 MATERIAL='EMPTY',
 PHYS_PAGE='213',
 XY='(-4225,1250)',
 ROT='0',
 VER='2',
 PACK_TYPE='0402LF',
 LOCATION='PR524',
 CDS_LIB='pure_quanta',
 CDS_PART_NAME='Q_RES_0402LF-1.5,1%,1/8W,EMPTY,CS-1504FB00',
 PART_NUMBER='CS-1504FB00',
 VALUE='1.5',
 PRIM_FILE='./archive_libs/logical/q_res/chips/chips.prt';

PART_NAME
 PR525 'Q_RES_0402LF-1.5,1%,1/8W,EMPTY,CS-1504FB00':;

SECTION_NUMBER 1
 '@T6G_MB_LIB.T6G(SCH_1):PAGE190_I29@PURE_QUANTA.Q_RES(CHIPS)':
 C_PATH='@t6g_mb_lib.t6g(sch_1):page190_i29@pure_quanta.q_res(chips)',
 P_PATH='@t6g_mb_lib.t6g(sch_1):page215_i29@pure_quanta.q_res(chips)',
 PATH='I29',
 DRAWING='@T6G_MB_LIB.T6G(SCH_1):PAGE190',
 WATTAGE='1/8W',
 TOLERANCE='1%',
 MATERIAL='EMPTY',
 PHYS_PAGE='215',
 XY='(-4700,4050)',
 ROT='0',
 VER='2',
 PACK_TYPE='0402LF',
 LOCATION='PR525',
 CDS_LIB='pure_quanta',
 CDS_PART_NAME='Q_RES_0402LF-1.5,1%,1/8W,EMPTY,CS-1504FB00',
 PART_NUMBER='CS-1504FB00',
 VALUE='1.5',
 PRIM_FILE='./archive_libs/logical/q_res/chips/chips.prt';

PART_NAME
 PR526 'Q_RES_0402LF-1.5,1%,1/8W,EMPTY,CS-1504FB00':;

SECTION_NUMBER 1
 '@T6G_MB_LIB.T6G(SCH_1):PAGE190_I21@PURE_QUANTA.Q_RES(CHIPS)':
 C_PATH='@t6g_mb_lib.t6g(sch_1):page190_i21@pure_quanta.q_res(chips)',
 P_PATH='@t6g_mb_lib.t6g(sch_1):page215_i21@pure_quanta.q_res(chips)',
 PATH='I21',
 DRAWING='@T6G_MB_LIB.T6G(SCH_1):PAGE190',
 WATTAGE='1/8W',
 TOLERANCE='1%',
 MATERIAL='EMPTY',
 PHYS_PAGE='215',
 XY='(-4625,1225)',
 ROT='0',
 VER='2',
 PACK_TYPE='0402LF',
 LOCATION='PR526',
 CDS_LIB='pure_quanta',
 CDS_PART_NAME='Q_RES_0402LF-1.5,1%,1/8W,EMPTY,CS-1504FB00',
 PART_NUMBER='CS-1504FB00',
 VALUE='1.5',
 PRIM_FILE='./archive_libs/logical/q_res/chips/chips.prt';

PART_NAME
 PR530 'Q_RES_0402LF-0,5%,1/16W,CHIP,CS00002JB13':;

SECTION_NUMBER 1
 '@T6G_MB_LIB.T6G(SCH_1):PAGE185_I107@PURE_QUANTA.Q_RES(CHIPS)':
 C_PATH='@t6g_mb_lib.t6g(sch_1):page185_i107@pure_quanta.q_res(chips)',
 P_PATH='@t6g_mb_lib.t6g(sch_1):page210_i107@pure_quanta.q_res(chips)',
 PATH='I107',
 DRAWING='@T6G_MB_LIB.T6G(SCH_1):PAGE185',
 WATTAGE='1/16W',
 TOLERANCE='5%',
 MATERIAL='CHIP',
 PHYS_PAGE='210',
 XY='(400,4975)',
 ROT='0',
 VER='1',
 PACK_TYPE='0402LF',
 LOCATION='PR530',
 CDS_LIB='pure_quanta',
 CDS_PART_NAME='Q_RES_0402LF-0,5%,1/16W,CHIP,CS00002JB13',
 PART_NUMBER='CS00002JB13',
 VALUE='0',
 PRIM_FILE='./archive_libs/logical/q_res/chips/chips.prt';

PART_NAME
 PR531 'Q_RES_0402LF-0,5%,1/16W,CHIP,CS00002JB13':;

SECTION_NUMBER 1
 '@T6G_MB_LIB.T6G(SCH_1):PAGE168_I111@PURE_QUANTA.Q_RES(CHIPS)':
 C_PATH='@t6g_mb_lib.t6g(sch_1):page168_i111@pure_quanta.q_res(chips)',
 P_PATH='@t6g_mb_lib.t6g(sch_1):page193_i111@pure_quanta.q_res(chips)',
 PATH='I111',
 DRAWING='@T6G_MB_LIB.T6G(SCH_1):PAGE168',
 WATTAGE='1/16W',
 TOLERANCE='5%',
 MATERIAL='CHIP',
 PHYS_PAGE='193',
 XY='(-2500,3600)',
 ROT='0',
 VER='1',
 PACK_TYPE='0402LF',
 LOCATION='PR531',
 CDS_LIB='pure_quanta',
 CDS_PART_NAME='Q_RES_0402LF-0,5%,1/16W,CHIP,CS00002JB13',
 PART_NUMBER='CS00002JB13',
 VALUE='0',
 PRIM_FILE='./archive_libs/logical/q_res/chips/chips.prt';

PART_NAME
 PR532 'Q_RES_0402LF-0,5%,1/16W,CHIP,CS00002JB13':;

SECTION_NUMBER 1
 '@T6G_MB_LIB.T6G(SCH_1):PAGE175_I76@PURE_QUANTA.Q_RES(CHIPS)':
 C_PATH='@t6g_mb_lib.t6g(sch_1):page175_i76@pure_quanta.q_res(chips)',
 P_PATH='@t6g_mb_lib.t6g(sch_1):page200_i76@pure_quanta.q_res(chips)',
 PATH='I76',
 DRAWING='@T6G_MB_LIB.T6G(SCH_1):PAGE175',
 WATTAGE='1/16W',
 TOLERANCE='5%',
 MATERIAL='CHIP',
 PHYS_PAGE='200',
 XY='(-2675,3400)',
 ROT='0',
 VER='1',
 PACK_TYPE='0402LF',
 LOCATION='PR532',
 CDS_LIB='pure_quanta',
 CDS_PART_NAME='Q_RES_0402LF-0,5%,1/16W,CHIP,CS00002JB13',
 PART_NUMBER='CS00002JB13',
 VALUE='0',
 PRIM_FILE='./archive_libs/logical/q_res/chips/chips.prt';

PART_NAME
 PR533 'Q_RES_0402LF-0,5%,1/16W,CHIP,CS00002JB13':;

SECTION_NUMBER 1
 '@T6G_MB_LIB.T6G(SCH_1):PAGE192_I76@PURE_QUANTA.Q_RES(CHIPS)':
 C_PATH='@t6g_mb_lib.t6g(sch_1):page192_i76@pure_quanta.q_res(chips)',
 P_PATH='@t6g_mb_lib.t6g(sch_1):page217_i76@pure_quanta.q_res(chips)',
 PATH='I76',
 DRAWING='@T6G_MB_LIB.T6G(SCH_1):PAGE192',
 WATTAGE='1/16W',
 TOLERANCE='5%',
 MATERIAL='CHIP',
 PHYS_PAGE='217',
 XY='(925,4325)',
 ROT='0',
 VER='1',
 PACK_TYPE='0402LF',
 LOCATION='PR533',
 CDS_LIB='pure_quanta',
 CDS_PART_NAME='Q_RES_0402LF-0,5%,1/16W,CHIP,CS00002JB13',
 PART_NUMBER='CS00002JB13',
 VALUE='0',
 PRIM_FILE='./archive_libs/logical/q_res/chips/chips.prt';

PART_NAME
 PR599 'Q_RES_0402LF-4.99K,1%,1/16W,EMPTY,CS24992FB07':;

SECTION_NUMBER 1
 '@T6G_MB_LIB.T6G(SCH_1):PAGE168_I47@PURE_QUANTA.Q_RES(CHIPS)':
 C_PATH='@t6g_mb_lib.t6g(sch_1):page168_i47@pure_quanta.q_res(chips)',
 P_PATH='@t6g_mb_lib.t6g(sch_1):page193_i47@pure_quanta.q_res(chips)',
 PATH='I47',
 DRAWING='@T6G_MB_LIB.T6G(SCH_1):PAGE168',
 WATTAGE='1/16W',
 TOLERANCE='1%',
 MATERIAL='EMPTY',
 PHYS_PAGE='193',
 XY='(-5250,850)',
 ROT='0',
 VER='2',
 PACK_TYPE='0402LF',
 LOCATION='PR599',
 CDS_LIB='pure_quanta',
 CDS_PART_NAME='Q_RES_0402LF-4.99K,1%,1/16W,EMPTY,CS24992FB07',
 PART_NUMBER='CS24992FB07',
 VALUE='4.99K',
 PRIM_FILE='./archive_libs/logical/q_res/chips/chips.prt';

PART_NAME
 PR600 'Q_RES_0402LF-4.99K,1%,1/16W,EMPTY,CS24992FB07':;

SECTION_NUMBER 1
 '@T6G_MB_LIB.T6G(SCH_1):PAGE175_I59@PURE_QUANTA.Q_RES(CHIPS)':
 C_PATH='@t6g_mb_lib.t6g(sch_1):page175_i59@pure_quanta.q_res(chips)',
 P_PATH='@t6g_mb_lib.t6g(sch_1):page200_i59@pure_quanta.q_res(chips)',
 PATH='I59',
 DRAWING='@T6G_MB_LIB.T6G(SCH_1):PAGE175',
 WATTAGE='1/16W',
 TOLERANCE='1%',
 MATERIAL='EMPTY',
 PHYS_PAGE='200',
 XY='(-5400,575)',
 ROT='0',
 VER='2',
 PACK_TYPE='0402LF',
 LOCATION='PR600',
 CDS_LIB='pure_quanta',
 CDS_PART_NAME='Q_RES_0402LF-4.99K,1%,1/16W,EMPTY,CS24992FB07',
 PART_NUMBER='CS24992FB07',
 VALUE='4.99K',
 PRIM_FILE='./archive_libs/logical/q_res/chips/chips.prt';

PART_NAME
 PR601 'Q_RES_0402LF-4.99K,1%,1/16W,EMPTY,CS24992FB07':;

SECTION_NUMBER 1
 '@T6G_MB_LIB.T6G(SCH_1):PAGE182_I18@PURE_QUANTA.Q_RES(CHIPS)':
 C_PATH='@t6g_mb_lib.t6g(sch_1):page182_i18@pure_quanta.q_res(chips)',
 P_PATH='@t6g_mb_lib.t6g(sch_1):page207_i18@pure_quanta.q_res(chips)',
 PATH='I18',
 DRAWING='@T6G_MB_LIB.T6G(SCH_1):PAGE182',
 WATTAGE='1/16W',
 TOLERANCE='1%',
 MATERIAL='EMPTY',
 PHYS_PAGE='207',
 XY='(-5725,475)',
 ROT='0',
 VER='2',
 PACK_TYPE='0402LF',
 LOCATION='PR601',
 CDS_LIB='pure_quanta',
 CDS_PART_NAME='Q_RES_0402LF-4.99K,1%,1/16W,EMPTY,CS24992FB07',
 PART_NUMBER='CS24992FB07',
 VALUE='4.99K',
 PRIM_FILE='./archive_libs/logical/q_res/chips/chips.prt';

PART_NAME
 PR602 'Q_RES_0402LF-4.99K,1%,1/16W,EMPTY,CS24992FB07':;

SECTION_NUMBER 1
 '@T6G_MB_LIB.T6G(SCH_1):PAGE185_I48@PURE_QUANTA.Q_RES(CHIPS)':
 C_PATH='@t6g_mb_lib.t6g(sch_1):page185_i48@pure_quanta.q_res(chips)',
 P_PATH='@t6g_mb_lib.t6g(sch_1):page210_i48@pure_quanta.q_res(chips)',
 PATH='I48',
 DRAWING='@T6G_MB_LIB.T6G(SCH_1):PAGE185',
 WATTAGE='1/16W',
 TOLERANCE='1%',
 MATERIAL='EMPTY',
 PHYS_PAGE='210',
 XY='(-2400,2225)',
 ROT='0',
 VER='2',
 PACK_TYPE='0402LF',
 LOCATION='PR602',
 CDS_LIB='pure_quanta',
 CDS_PART_NAME='Q_RES_0402LF-4.99K,1%,1/16W,EMPTY,CS24992FB07',
 PART_NUMBER='CS24992FB07',
 VALUE='4.99K',
 PRIM_FILE='./archive_libs/logical/q_res/chips/chips.prt';

PART_NAME
 PR603 'Q_RES_0402LF-4.99K,1%,1/16W,EMPTY,CS24992FB07':;

SECTION_NUMBER 1
 '@T6G_MB_LIB.T6G(SCH_1):PAGE192_I55@PURE_QUANTA.Q_RES(CHIPS)':
 C_PATH='@t6g_mb_lib.t6g(sch_1):page192_i55@pure_quanta.q_res(chips)',
 P_PATH='@t6g_mb_lib.t6g(sch_1):page217_i55@pure_quanta.q_res(chips)',
 PATH='I55',
 DRAWING='@T6G_MB_LIB.T6G(SCH_1):PAGE192',
 WATTAGE='1/16W',
 TOLERANCE='1%',
 MATERIAL='EMPTY',
 PHYS_PAGE='217',
 XY='(-1800,1500)',
 ROT='0',
 VER='2',
 PACK_TYPE='0402LF',
 LOCATION='PR603',
 CDS_LIB='pure_quanta',
 CDS_PART_NAME='Q_RES_0402LF-4.99K,1%,1/16W,EMPTY,CS24992FB07',
 PART_NUMBER='CS24992FB07',
 VALUE='4.99K',
 PRIM_FILE='./archive_libs/logical/q_res/chips/chips.prt';

PART_NAME
 PR604 'Q_RES_0402LF-4.99K,1%,1/16W,EMPTY,CS24992FB07':;

SECTION_NUMBER 1
 '@T6G_MB_LIB.T6G(SCH_1):PAGE199_I17@PURE_QUANTA.Q_RES(CHIPS)':
 C_PATH='@t6g_mb_lib.t6g(sch_1):page199_i17@pure_quanta.q_res(chips)',
 P_PATH='@t6g_mb_lib.t6g(sch_1):page224_i17@pure_quanta.q_res(chips)',
 PATH='I17',
 DRAWING='@T6G_MB_LIB.T6G(SCH_1):PAGE199',
 WATTAGE='1/16W',
 TOLERANCE='1%',
 MATERIAL='EMPTY',
 PHYS_PAGE='224',
 XY='(-5725,475)',
 ROT='0',
 VER='2',
 PACK_TYPE='0402LF',
 LOCATION='PR604',
 CDS_LIB='pure_quanta',
 CDS_PART_NAME='Q_RES_0402LF-4.99K,1%,1/16W,EMPTY,CS24992FB07',
 PART_NUMBER='CS24992FB07',
 VALUE='4.99K',
 PRIM_FILE='./archive_libs/logical/q_res/chips/chips.prt';

PART_NAME
 PR830 'Q_RES_0402LF-15K,0.1%,1/16W,CHIP,CS31502BB03':;

SECTION_NUMBER 1
 '@T6G_MB_LIB.T6G(SCH_1):PAGE245_I51@PURE_QUANTA.Q_RES(CHIPS)':
 C_PATH='@t6g_mb_lib.t6g(sch_1):page245_i51@pure_quanta.q_res(chips)',
 P_PATH='@t6g_mb_lib.t6g(sch_1):page190_i51@pure_quanta.q_res(chips)',
 PATH='I51',
 DRAWING='@T6G_MB_LIB.T6G(SCH_1):PAGE245',
 WATTAGE='1/16W',
 TOLERANCE='0.1%',
 MATERIAL='CHIP',
 PHYS_PAGE='190',
 XY='(1200,-1475)',
 ROT='0',
 VER='2',
 PACK_TYPE='0402LF',
 LOCATION='PR830',
 CDS_LIB='pure_quanta',
 CDS_PART_NAME='Q_RES_0402LF-15K,0.1%,1/16W,CHIP,CS31502BB03',
 PART_NUMBER='CS31502BB03',
 VALUE='15K',
 PRIM_FILE='./archive_libs/logical/q_res/chips/chips.prt';

PART_NAME
 PR831 'Q_RES_0402LF-47K,0.1%,1/16W,CHIP,CS34702BB05':;

SECTION_NUMBER 1
 '@T6G_MB_LIB.T6G(SCH_1):PAGE245_I54@PURE_QUANTA.Q_RES(CHIPS)':
 C_PATH='@t6g_mb_lib.t6g(sch_1):page245_i54@pure_quanta.q_res(chips)',
 P_PATH='@t6g_mb_lib.t6g(sch_1):page190_i54@pure_quanta.q_res(chips)',
 PATH='I54',
 DRAWING='@T6G_MB_LIB.T6G(SCH_1):PAGE245',
 WATTAGE='1/16W',
 TOLERANCE='0.1%',
 MATERIAL='CHIP',
 PHYS_PAGE='190',
 XY='(2100,-1300)',
 ROT='0',
 VER='1',
 PACK_TYPE='0402LF',
 LOCATION='PR831',
 CDS_LIB='pure_quanta',
 CDS_PART_NAME='Q_RES_0402LF-47K,0.1%,1/16W,CHIP,CS34702BB05',
 PART_NUMBER='CS34702BB05',
 VALUE='47K',
 PRIM_FILE='./archive_libs/logical/q_res/chips/chips.prt';

PART_NAME
 PR832 'Q_RES_0402LF-0,5%,1/16W,CHIP,CS00002JB13':;

SECTION_NUMBER 1
 '@T6G_MB_LIB.T6G(SCH_1):PAGE245_I10@PURE_QUANTA.Q_RES(CHIPS)':
 C_PATH='@t6g_mb_lib.t6g(sch_1):page245_i10@pure_quanta.q_res(chips)',
 P_PATH='@t6g_mb_lib.t6g(sch_1):page190_i10@pure_quanta.q_res(chips)',
 PATH='I10',
 DRAWING='@T6G_MB_LIB.T6G(SCH_1):PAGE245',
 WATTAGE='1/16W',
 TOLERANCE='5%',
 MATERIAL='CHIP',
 PHYS_PAGE='190',
 XY='(-2150,-975)',
 ROT='0',
 VER='2',
 PACK_TYPE='0402LF',
 LOCATION='PR832',
 CDS_LIB='pure_quanta',
 CDS_PART_NAME='Q_RES_0402LF-0,5%,1/16W,CHIP,CS00002JB13',
 PART_NUMBER='CS00002JB13',
 VALUE='0',
 PRIM_FILE='./archive_libs/logical/q_res/chips/chips.prt';

PART_NAME
 PR833 'Q_RES_0402LF-1.5K,1%,1/16W,EMPTY,CS21502FB07':;

SECTION_NUMBER 1
 '@T6G_MB_LIB.T6G(SCH_1):PAGE245_I15@PURE_QUANTA.Q_RES(CHIPS)':
 C_PATH='@t6g_mb_lib.t6g(sch_1):page245_i15@pure_quanta.q_res(chips)',
 P_PATH='@t6g_mb_lib.t6g(sch_1):page190_i15@pure_quanta.q_res(chips)',
 PATH='I15',
 DRAWING='@T6G_MB_LIB.T6G(SCH_1):PAGE245',
 WATTAGE='1/16W',
 TOLERANCE='1%',
 MATERIAL='EMPTY',
 PHYS_PAGE='190',
 XY='(-1750,-1075)',
 ROT='0',
 VER='2',
 PACK_TYPE='0402LF',
 LOCATION='PR833',
 CDS_LIB='pure_quanta',
 CDS_PART_NAME='Q_RES_0402LF-1.5K,1%,1/16W,EMPTY,CS21502FB07',
 PART_NUMBER='CS21502FB07',
 VALUE='1.5K',
 PRIM_FILE='./archive_libs/logical/q_res/chips/chips.prt';

PART_NAME
 PR834 'Q_RES_0402LF-21.5K,1%,1/16W,CHIP,CS32152FB04':;

SECTION_NUMBER 1
 '@T6G_MB_LIB.T6G(SCH_1):PAGE245_I17@PURE_QUANTA.Q_RES(CHIPS)':
 C_PATH='@t6g_mb_lib.t6g(sch_1):page245_i17@pure_quanta.q_res(chips)',
 P_PATH='@t6g_mb_lib.t6g(sch_1):page190_i17@pure_quanta.q_res(chips)',
 PATH='I17',
 DRAWING='@T6G_MB_LIB.T6G(SCH_1):PAGE245',
 WATTAGE='1/16W',
 TOLERANCE='1%',
 MATERIAL='CHIP',
 PHYS_PAGE='190',
 XY='(-1350,-1175)',
 ROT='0',
 VER='2',
 PACK_TYPE='0402LF',
 LOCATION='PR834',
 CDS_LIB='pure_quanta',
 CDS_PART_NAME='Q_RES_0402LF-21.5K,1%,1/16W,CHIP,CS32152FB04',
 PART_NUMBER='CS32152FB04',
 VALUE='21.5K',
 PRIM_FILE='./archive_libs/logical/q_res/chips/chips.prt';

PART_NAME
 PR835 'Q_RES_0402LF-0,5%,1/16W,CHIP,CS00002JB13':;

SECTION_NUMBER 1
 '@T6G_MB_LIB.T6G(SCH_1):PAGE245_I49@PURE_QUANTA.Q_RES(CHIPS)':
 C_PATH='@t6g_mb_lib.t6g(sch_1):page245_i49@pure_quanta.q_res(chips)',
 P_PATH='@t6g_mb_lib.t6g(sch_1):page190_i49@pure_quanta.q_res(chips)',
 PATH='I49',
 DRAWING='@T6G_MB_LIB.T6G(SCH_1):PAGE245',
 WATTAGE='1/16W',
 TOLERANCE='5%',
 MATERIAL='CHIP',
 PHYS_PAGE='190',
 XY='(800,-100)',
 ROT='0',
 VER='1',
 PACK_TYPE='0402LF',
 LOCATION='PR835',
 CDS_LIB='pure_quanta',
 CDS_PART_NAME='Q_RES_0402LF-0,5%,1/16W,CHIP,CS00002JB13',
 PART_NUMBER='CS00002JB13',
 VALUE='0',
 PRIM_FILE='./archive_libs/logical/q_res/chips/chips.prt';

PART_NAME
 PR836 'Q_RES_0402LF-1K,1%,1/16W,CHIP,CS21002FB06':;

SECTION_NUMBER 1
 '@T6G_MB_LIB.T6G(SCH_1):PAGE245_I46@PURE_QUANTA.Q_RES(CHIPS)':
 C_PATH='@t6g_mb_lib.t6g(sch_1):page245_i46@pure_quanta.q_res(chips)',
 P_PATH='@t6g_mb_lib.t6g(sch_1):page190_i46@pure_quanta.q_res(chips)',
 PATH='I46',
 DRAWING='@T6G_MB_LIB.T6G(SCH_1):PAGE245',
 WATTAGE='1/16W',
 TOLERANCE='1%',
 MATERIAL='CHIP',
 PHYS_PAGE='190',
 XY='(825,-1000)',
 ROT='0',
 VER='1',
 PACK_TYPE='0402LF',
 LOCATION='PR836',
 CDS_LIB='pure_quanta',
 CDS_PART_NAME='Q_RES_0402LF-1K,1%,1/16W,CHIP,CS21002FB06',
 PART_NUMBER='CS21002FB06',
 VALUE='1K',
 PRIM_FILE='./archive_libs/logical/q_res/chips/chips.prt';

PART_NAME
 PR883 'Q_RES_0402LF-0,5%,1/16W,EMPTY,CS00002JB13':;

SECTION_NUMBER 1
 '@T6G_MB_LIB.T6G(SCH_1):PAGE475_I210@PURE_QUANTA.Q_RES(CHIPS)':
 C_PATH='@t6g_mb_lib.t6g(sch_1):page475_i210@pure_quanta.q_res(chips)',
 P_PATH='@t6g_mb_lib.t6g(sch_1):page362_i210@pure_quanta.q_res(chips)',
 PATH='I210',
 DRAWING='@T6G_MB_LIB.T6G(SCH_1):PAGE475',
 WATTAGE='1/16W',
 TOLERANCE='5%',
 MATERIAL='EMPTY',
 PHYS_PAGE='362',
 XY='(-8300,6950)',
 ROT='0',
 VER='2',
 PACK_TYPE='0402LF',
 LOCATION='PR883',
 CDS_LIB='pure_quanta',
 CDS_PART_NAME='Q_RES_0402LF-0,5%,1/16W,EMPTY,CS00002JB13',
 PART_NUMBER='CS00002JB13',
 VALUE='0',
 PRIM_FILE='./archive_libs/logical/q_res/chips/chips.prt';

PART_NAME
 PR885 'Q_RES_0402LF-5.36K,1%,1/16W,EMPTY,CS25362FB02':;

SECTION_NUMBER 1
 '@T6G_MB_LIB.T6G(SCH_1):PAGE477_I7@PURE_QUANTA.Q_RES(CHIPS)':
 C_PATH='@t6g_mb_lib.t6g(sch_1):page477_i7@pure_quanta.q_res(chips)',
 P_PATH='@t6g_mb_lib.t6g(sch_1):page364_i7@pure_quanta.q_res(chips)',
 PATH='I7',
 DRAWING='@T6G_MB_LIB.T6G(SCH_1):PAGE477',
 WATTAGE='1/16W',
 TOLERANCE='1%',
 MATERIAL='EMPTY',
 PHYS_PAGE='364',
 XY='(-6700,600)',
 ROT='0',
 VER='1',
 PACK_TYPE='0402LF',
 LOCATION='PR885',
 CDS_LIB='pure_quanta',
 CDS_PART_NAME='Q_RES_0402LF-5.36K,1%,1/16W,EMPTY,CS25362FB02',
 PART_NUMBER='CS25362FB02',
 VALUE='5.36K',
 PRIM_FILE='./archive_libs/logical/q_res/chips/chips.prt';

PART_NAME
 PR1101 'Q_RES_0402LF-2K,0.1%,1/16W,CHIP,CS22002BB07':
 ROOM='HSC BOM1';

SECTION_NUMBER 1
 '@T6G_MB_LIB.T6G(SCH_1):PAGE301_I15@PURE_QUANTA.Q_RES(CHIPS)':
 C_PATH='@t6g_mb_lib.t6g(sch_1):page301_i15@pure_quanta.q_res(chips)',
 P_PATH='@t6g_mb_lib.t6g(sch_1):page263_i15@pure_quanta.q_res(chips)',
 PATH='I15',
 DRAWING='@T6G_MB_LIB.T6G(SCH_1):PAGE301',
 WATTAGE='1/16W',
 TOLERANCE='0.1%',
 MATERIAL='CHIP',
 PHYS_PAGE='263',
 XY='(-975,-2075)',
 ROT='0',
 VER='2',
 PACK_TYPE='0402LF',
 LOCATION='PR1101',
 CDS_LIB='pure_quanta',
 CDS_PART_NAME='Q_RES_0402LF-2K,0.1%,1/16W,CHIP,CS22002BB07',
 ROOM='HSC BOM1',
 PART_NUMBER='CS22002BB07',
 VALUE='2K',
 PRIM_FILE='./archive_libs/logical/q_res/chips/chips.prt';

PART_NAME
 PR1131 'Q_RES_0402LF-2K,0.1%,1/16W,CHIP,CS22002BB07':
 ROOM='HSC BOM1';

SECTION_NUMBER 1
 '@T6G_MB_LIB.T6G(SCH_1):PAGE267_I65@PURE_QUANTA.Q_RES(CHIPS)':
 C_PATH='@t6g_mb_lib.t6g(sch_1):page267_i65@pure_quanta.q_res(chips)',
 P_PATH='@t6g_mb_lib.t6g(sch_1):page262_i65@pure_quanta.q_res(chips)',
 PATH='I65',
 DRAWING='@T6G_MB_LIB.T6G(SCH_1):PAGE267',
 WATTAGE='1/16W',
 TOLERANCE='0.1%',
 MATERIAL='CHIP',
 PHYS_PAGE='262',
 XY='(-10150,2975)',
 ROT='0',
 VER='1',
 PACK_TYPE='0402LF',
 LOCATION='PR1131',
 CDS_LIB='pure_quanta',
 CDS_PART_NAME='Q_RES_0402LF-2K,0.1%,1/16W,CHIP,CS22002BB07',
 ROOM='HSC BOM1',
 PART_NUMBER='CS22002BB07',
 VALUE='2K',
 PRIM_FILE='./archive_libs/logical/q_res/chips/chips.prt';

PART_NAME
 PR1133 'Q_RES_0402LF-2K,0.1%,1/16W,CHIP,CS22002BB07':
 ROOM='HSC BOM1';

SECTION_NUMBER 1
 '@T6G_MB_LIB.T6G(SCH_1):PAGE267_I86@PURE_QUANTA.Q_RES(CHIPS)':
 C_PATH='@t6g_mb_lib.t6g(sch_1):page267_i86@pure_quanta.q_res(chips)',
 P_PATH='@t6g_mb_lib.t6g(sch_1):page262_i86@pure_quanta.q_res(chips)',
 PATH='I86',
 DRAWING='@T6G_MB_LIB.T6G(SCH_1):PAGE267',
 WATTAGE='1/16W',
 TOLERANCE='0.1%',
 MATERIAL='CHIP',
 PHYS_PAGE='262',
 XY='(-7625,2875)',
 ROT='0',
 VER='2',
 PACK_TYPE='0402LF',
 LOCATION='PR1133',
 CDS_LIB='pure_quanta',
 CDS_PART_NAME='Q_RES_0402LF-2K,0.1%,1/16W,CHIP,CS22002BB07',
 ROOM='HSC BOM1',
 PART_NUMBER='CS22002BB07',
 VALUE='2K',
 PRIM_FILE='./archive_libs/logical/q_res/chips/chips.prt';

PART_NAME
 PR1134 'Q_RES_0402LF-120K,1%,1/16W,CHIP,CS41202FB05':
 ROOM='HSC BOM1';

SECTION_NUMBER 1
 '@T6G_MB_LIB.T6G(SCH_1):PAGE301_I29@PURE_QUANTA.Q_RES(CHIPS)':
 C_PATH='@t6g_mb_lib.t6g(sch_1):page301_i29@pure_quanta.q_res(chips)',
 P_PATH='@t6g_mb_lib.t6g(sch_1):page263_i29@pure_quanta.q_res(chips)',
 PATH='I29',
 DRAWING='@T6G_MB_LIB.T6G(SCH_1):PAGE301',
 WATTAGE='1/16W',
 TOLERANCE='1%',
 MATERIAL='CHIP',
 PHYS_PAGE='263',
 XY='(-1925,1550)',
 ROT='0',
 VER='1',
 PACK_TYPE='0402LF',
 LOCATION='PR1134',
 CDS_LIB='pure_quanta',
 CDS_PART_NAME='Q_RES_0402LF-120K,1%,1/16W,CHIP,CS41202FB05',
 ROOM='HSC BOM1',
 PART_NUMBER='CS41202FB05',
 VALUE='120K',
 PRIM_FILE='./archive_libs/logical/q_res/chips/chips.prt';

PART_NAME
 PR2106 'Q_RES_0402LF-10K,1%,1/16W,CHIP,CS31002FB08':
 ROOM='HSC BOM1';

SECTION_NUMBER 1
 '@T6G_MB_LIB.T6G(SCH_1):PAGE267_I56@PURE_QUANTA.Q_RES(CHIPS)':
 C_PATH='@t6g_mb_lib.t6g(sch_1):page267_i56@pure_quanta.q_res(chips)',
 P_PATH='@t6g_mb_lib.t6g(sch_1):page262_i56@pure_quanta.q_res(chips)',
 PATH='I56',
 DRAWING='@T6G_MB_LIB.T6G(SCH_1):PAGE267',
 WATTAGE='1/16W',
 TOLERANCE='1%',
 MATERIAL='CHIP',
 PHYS_PAGE='262',
 XY='(-13100,2775)',
 ROT='0',
 VER='1',
 PACK_TYPE='0402LF',
 LOCATION='PR2106',
 CDS_LIB='pure_quanta',
 CDS_PART_NAME='Q_RES_0402LF-10K,1%,1/16W,CHIP,CS31002FB08',
 ROOM='HSC BOM1',
 PART_NUMBER='CS31002FB08',
 VALUE='10K',
 PRIM_FILE='./archive_libs/logical/q_res/chips/chips.prt';

PART_NAME
 PR2149 'Q_RES_0402LF-0,5%,1/16W,CHIP,CS00002JB13':
 ROOM='HSC BOM1';

SECTION_NUMBER 1
 '@T6G_MB_LIB.T6G(SCH_1):PAGE267_I39@PURE_QUANTA.Q_RES(CHIPS)':
 C_PATH='@t6g_mb_lib.t6g(sch_1):page267_i39@pure_quanta.q_res(chips)',
 P_PATH='@t6g_mb_lib.t6g(sch_1):page262_i39@pure_quanta.q_res(chips)',
 PATH='I39',
 DRAWING='@T6G_MB_LIB.T6G(SCH_1):PAGE267',
 WATTAGE='1/16W',
 TOLERANCE='5%',
 MATERIAL='CHIP',
 PHYS_PAGE='262',
 XY='(-15225,4050)',
 ROT='1',
 VER='1',
 PACK_TYPE='0402LF',
 LOCATION='PR2149',
 CDS_LIB='pure_quanta',
 CDS_PART_NAME='Q_RES_0402LF-0,5%,1/16W,CHIP,CS00002JB13',
 ROOM='HSC BOM1',
 PART_NUMBER='CS00002JB13',
 VALUE='0',
 PRIM_FILE='./archive_libs/logical/q_res/chips/chips.prt';

PART_NAME
 PR2510 'Q_RES_0402LF-1,1%,1/16W,CHIP,CS-1002FB04':
 ROOM='HSC BOM2';

SECTION_NUMBER 1
 '@T6G_MB_LIB.T6G(SCH_1):PAGE302_I18@PURE_QUANTA.Q_RES(CHIPS)':
 C_PATH='@t6g_mb_lib.t6g(sch_1):page302_i18@pure_quanta.q_res(chips)',
 P_PATH='@t6g_mb_lib.t6g(sch_1):page266_i18@pure_quanta.q_res(chips)',
 PATH='I18',
 DRAWING='@T6G_MB_LIB.T6G(SCH_1):PAGE302',
 WATTAGE='1/16W',
 TOLERANCE='1%',
 MATERIAL='CHIP',
 PHYS_PAGE='266',
 XY='(-8275,4675)',
 ROT='0',
 VER='1',
 PACK_TYPE='0402LF',
 LOCATION='PR2510',
 CDS_LIB='pure_quanta',
 CDS_PART_NAME='Q_RES_0402LF-1,1%,1/16W,CHIP,CS-1002FB04',
 ROOM='HSC BOM2',
 PART_NUMBER='CS-1002FB04',
 VALUE='1',
 PRIM_FILE='./archive_libs/logical/q_res/chips/chips.prt';

PART_NAME
 PR2511 'Q_RES_0402LF-1,1%,1/16W,CHIP,CS-1002FB04':
 ROOM='HSC BOM2';

SECTION_NUMBER 1
 '@T6G_MB_LIB.T6G(SCH_1):PAGE302_I17@PURE_QUANTA.Q_RES(CHIPS)':
 C_PATH='@t6g_mb_lib.t6g(sch_1):page302_i17@pure_quanta.q_res(chips)',
 P_PATH='@t6g_mb_lib.t6g(sch_1):page266_i17@pure_quanta.q_res(chips)',
 PATH='I17',
 DRAWING='@T6G_MB_LIB.T6G(SCH_1):PAGE302',
 WATTAGE='1/16W',
 TOLERANCE='1%',
 MATERIAL='CHIP',
 PHYS_PAGE='266',
 XY='(-8275,4575)',
 ROT='0',
 VER='1',
 PACK_TYPE='0402LF',
 LOCATION='PR2511',
 CDS_LIB='pure_quanta',
 CDS_PART_NAME='Q_RES_0402LF-1,1%,1/16W,CHIP,CS-1002FB04',
 ROOM='HSC BOM2',
 PART_NUMBER='CS-1002FB04',
 VALUE='1',
 PRIM_FILE='./archive_libs/logical/q_res/chips/chips.prt';

PART_NAME
 PR2512 'Q_RES_0402LF-1,1%,1/16W,CHIP,CS-1002FB04':
 ROOM='HSC BOM2';

SECTION_NUMBER 1
 '@T6G_MB_LIB.T6G(SCH_1):PAGE302_I16@PURE_QUANTA.Q_RES(CHIPS)':
 C_PATH='@t6g_mb_lib.t6g(sch_1):page302_i16@pure_quanta.q_res(chips)',
 P_PATH='@t6g_mb_lib.t6g(sch_1):page266_i16@pure_quanta.q_res(chips)',
 PATH='I16',
 DRAWING='@T6G_MB_LIB.T6G(SCH_1):PAGE302',
 WATTAGE='1/16W',
 TOLERANCE='1%',
 MATERIAL='CHIP',
 PHYS_PAGE='266',
 XY='(-8275,4475)',
 ROT='0',
 VER='1',
 PACK_TYPE='0402LF',
 LOCATION='PR2512',
 CDS_LIB='pure_quanta',
 CDS_PART_NAME='Q_RES_0402LF-1,1%,1/16W,CHIP,CS-1002FB04',
 ROOM='HSC BOM2',
 PART_NUMBER='CS-1002FB04',
 VALUE='1',
 PRIM_FILE='./archive_libs/logical/q_res/chips/chips.prt';

PART_NAME
 PR2513 'Q_RES_0402LF-1,1%,1/16W,CHIP,CS-1002FB04':
 ROOM='HSC BOM2';

SECTION_NUMBER 1
 '@T6G_MB_LIB.T6G(SCH_1):PAGE302_I15@PURE_QUANTA.Q_RES(CHIPS)':
 C_PATH='@t6g_mb_lib.t6g(sch_1):page302_i15@pure_quanta.q_res(chips)',
 P_PATH='@t6g_mb_lib.t6g(sch_1):page266_i15@pure_quanta.q_res(chips)',
 PATH='I15',
 DRAWING='@T6G_MB_LIB.T6G(SCH_1):PAGE302',
 WATTAGE='1/16W',
 TOLERANCE='1%',
 MATERIAL='CHIP',
 PHYS_PAGE='266',
 XY='(-8275,4375)',
 ROT='0',
 VER='1',
 PACK_TYPE='0402LF',
 LOCATION='PR2513',
 CDS_LIB='pure_quanta',
 CDS_PART_NAME='Q_RES_0402LF-1,1%,1/16W,CHIP,CS-1002FB04',
 ROOM='HSC BOM2',
 PART_NUMBER='CS-1002FB04',
 VALUE='1',
 PRIM_FILE='./archive_libs/logical/q_res/chips/chips.prt';

PART_NAME
 PR2514 'Q_RES_0402LF-10,1%,1/16W,CHIP,CS01002FB07':
 ROOM='HSC BOM2';

SECTION_NUMBER 1
 '@T6G_MB_LIB.T6G(SCH_1):PAGE302_I82@PURE_QUANTA.Q_RES(CHIPS)':
 C_PATH='@t6g_mb_lib.t6g(sch_1):page302_i82@pure_quanta.q_res(chips)',
 P_PATH='@t6g_mb_lib.t6g(sch_1):page266_i82@pure_quanta.q_res(chips)',
 PATH='I82',
 DRAWING='@T6G_MB_LIB.T6G(SCH_1):PAGE302',
 WATTAGE='1/16W',
 TOLERANCE='1%',
 MATERIAL='CHIP',
 PHYS_PAGE='266',
 XY='(-8275,4275)',
 ROT='0',
 VER='1',
 PACK_TYPE='0402LF',
 LOCATION='PR2514',
 CDS_LIB='pure_quanta',
 CDS_PART_NAME='Q_RES_0402LF-10,1%,1/16W,CHIP,CS01002FB07',
 ROOM='HSC BOM2',
 PART_NUMBER='CS01002FB07',
 VALUE='10',
 PRIM_FILE='./archive_libs/logical/q_res/chips/chips.prt';

PART_NAME
 PR2515 'Q_RES_0402LF-10,1%,1/16W,CHIP,CS01002FB07':
 ROOM='HSC BOM2';

SECTION_NUMBER 1
 '@T6G_MB_LIB.T6G(SCH_1):PAGE302_I83@PURE_QUANTA.Q_RES(CHIPS)':
 C_PATH='@t6g_mb_lib.t6g(sch_1):page302_i83@pure_quanta.q_res(chips)',
 P_PATH='@t6g_mb_lib.t6g(sch_1):page266_i83@pure_quanta.q_res(chips)',
 PATH='I83',
 DRAWING='@T6G_MB_LIB.T6G(SCH_1):PAGE302',
 WATTAGE='1/16W',
 TOLERANCE='1%',
 MATERIAL='CHIP',
 PHYS_PAGE='266',
 XY='(-8250,3925)',
 ROT='0',
 VER='1',
 PACK_TYPE='0402LF',
 LOCATION='PR2515',
 CDS_LIB='pure_quanta',
 CDS_PART_NAME='Q_RES_0402LF-10,1%,1/16W,CHIP,CS01002FB07',
 ROOM='HSC BOM2',
 PART_NUMBER='CS01002FB07',
 VALUE='10',
 PRIM_FILE='./archive_libs/logical/q_res/chips/chips.prt';

PART_NAME
 PR2516 'Q_RES_0402LF-10,1%,1/16W,CHIP,CS01002FB07':
 ROOM='HSC BOM2';

SECTION_NUMBER 1
 '@T6G_MB_LIB.T6G(SCH_1):PAGE302_I84@PURE_QUANTA.Q_RES(CHIPS)':
 C_PATH='@t6g_mb_lib.t6g(sch_1):page302_i84@pure_quanta.q_res(chips)',
 P_PATH='@t6g_mb_lib.t6g(sch_1):page266_i84@pure_quanta.q_res(chips)',
 PATH='I84',
 DRAWING='@T6G_MB_LIB.T6G(SCH_1):PAGE302',
 WATTAGE='1/16W',
 TOLERANCE='1%',
 MATERIAL='CHIP',
 PHYS_PAGE='266',
 XY='(-8250,3825)',
 ROT='0',
 VER='1',
 PACK_TYPE='0402LF',
 LOCATION='PR2516',
 CDS_LIB='pure_quanta',
 CDS_PART_NAME='Q_RES_0402LF-10,1%,1/16W,CHIP,CS01002FB07',
 ROOM='HSC BOM2',
 PART_NUMBER='CS01002FB07',
 VALUE='10',
 PRIM_FILE='./archive_libs/logical/q_res/chips/chips.prt';

PART_NAME
 PR2517 'Q_RES_0402LF-10,1%,1/16W,CHIP,CS01002FB07':
 ROOM='HSC BOM2';

SECTION_NUMBER 1
 '@T6G_MB_LIB.T6G(SCH_1):PAGE302_I85@PURE_QUANTA.Q_RES(CHIPS)':
 C_PATH='@t6g_mb_lib.t6g(sch_1):page302_i85@pure_quanta.q_res(chips)',
 P_PATH='@t6g_mb_lib.t6g(sch_1):page266_i85@pure_quanta.q_res(chips)',
 PATH='I85',
 DRAWING='@T6G_MB_LIB.T6G(SCH_1):PAGE302',
 WATTAGE='1/16W',
 TOLERANCE='1%',
 MATERIAL='CHIP',
 PHYS_PAGE='266',
 XY='(-8250,3725)',
 ROT='0',
 VER='1',
 PACK_TYPE='0402LF',
 LOCATION='PR2517',
 CDS_LIB='pure_quanta',
 CDS_PART_NAME='Q_RES_0402LF-10,1%,1/16W,CHIP,CS01002FB07',
 ROOM='HSC BOM2',
 PART_NUMBER='CS01002FB07',
 VALUE='10',
 PRIM_FILE='./archive_libs/logical/q_res/chips/chips.prt';

PART_NAME
 PR2518 'Q_RES_0402LF-10,1%,1/16W,CHIP,CS01002FB07':
 ROOM='HSC BOM2';

SECTION_NUMBER 1
 '@T6G_MB_LIB.T6G(SCH_1):PAGE302_I86@PURE_QUANTA.Q_RES(CHIPS)':
 C_PATH='@t6g_mb_lib.t6g(sch_1):page302_i86@pure_quanta.q_res(chips)',
 P_PATH='@t6g_mb_lib.t6g(sch_1):page266_i86@pure_quanta.q_res(chips)',
 PATH='I86',
 DRAWING='@T6G_MB_LIB.T6G(SCH_1):PAGE302',
 WATTAGE='1/16W',
 TOLERANCE='1%',
 MATERIAL='CHIP',
 PHYS_PAGE='266',
 XY='(-8250,3625)',
 ROT='0',
 VER='1',
 PACK_TYPE='0402LF',
 LOCATION='PR2518',
 CDS_LIB='pure_quanta',
 CDS_PART_NAME='Q_RES_0402LF-10,1%,1/16W,CHIP,CS01002FB07',
 ROOM='HSC BOM2',
 PART_NUMBER='CS01002FB07',
 VALUE='10',
 PRIM_FILE='./archive_libs/logical/q_res/chips/chips.prt';

PART_NAME
 PR2519 'Q_RES_0402LF-100,1%,1/16W,CHIP,CS11002FB07':
 ROOM='HSC BOM2';

SECTION_NUMBER 1
 '@T6G_MB_LIB.T6G(SCH_1):PAGE302_I87@PURE_QUANTA.Q_RES(CHIPS)':
 C_PATH='@t6g_mb_lib.t6g(sch_1):page302_i87@pure_quanta.q_res(chips)',
 P_PATH='@t6g_mb_lib.t6g(sch_1):page266_i87@pure_quanta.q_res(chips)',
 PATH='I87',
 DRAWING='@T6G_MB_LIB.T6G(SCH_1):PAGE302',
 WATTAGE='1/16W',
 TOLERANCE='1%',
 MATERIAL='CHIP',
 PHYS_PAGE='266',
 XY='(-8250,3525)',
 ROT='0',
 VER='1',
 PACK_TYPE='0402LF',
 LOCATION='PR2519',
 CDS_LIB='pure_quanta',
 CDS_PART_NAME='Q_RES_0402LF-100,1%,1/16W,CHIP,CS11002FB07',
 ROOM='HSC BOM2',
 PART_NUMBER='CS11002FB07',
 VALUE='100',
 PRIM_FILE='./archive_libs/logical/q_res/chips/chips.prt';

PART_NAME
 PR2520 'Q_RES_0402LF-1,1%,1/16W,CHIP,CS-1002FB04':
 ROOM='HSC BOM2';

SECTION_NUMBER 1
 '@T6G_MB_LIB.T6G(SCH_1):PAGE302_I8@PURE_QUANTA.Q_RES(CHIPS)':
 C_PATH='@t6g_mb_lib.t6g(sch_1):page302_i8@pure_quanta.q_res(chips)',
 P_PATH='@t6g_mb_lib.t6g(sch_1):page266_i8@pure_quanta.q_res(chips)',
 PATH='I8',
 DRAWING='@T6G_MB_LIB.T6G(SCH_1):PAGE302',
 WATTAGE='1/16W',
 TOLERANCE='1%',
 MATERIAL='CHIP',
 PHYS_PAGE='266',
 XY='(-8250,3150)',
 ROT='0',
 VER='1',
 PACK_TYPE='0402LF',
 LOCATION='PR2520',
 CDS_LIB='pure_quanta',
 CDS_PART_NAME='Q_RES_0402LF-1,1%,1/16W,CHIP,CS-1002FB04',
 ROOM='HSC BOM2',
 PART_NUMBER='CS-1002FB04',
 VALUE='1',
 PRIM_FILE='./archive_libs/logical/q_res/chips/chips.prt';

PART_NAME
 PR2521 'Q_RES_0402LF-1,1%,1/16W,CHIP,CS-1002FB04':
 ROOM='HSC BOM2';

SECTION_NUMBER 1
 '@T6G_MB_LIB.T6G(SCH_1):PAGE302_I6@PURE_QUANTA.Q_RES(CHIPS)':
 C_PATH='@t6g_mb_lib.t6g(sch_1):page302_i6@pure_quanta.q_res(chips)',
 P_PATH='@t6g_mb_lib.t6g(sch_1):page266_i6@pure_quanta.q_res(chips)',
 PATH='I6',
 DRAWING='@T6G_MB_LIB.T6G(SCH_1):PAGE302',
 WATTAGE='1/16W',
 TOLERANCE='1%',
 MATERIAL='CHIP',
 PHYS_PAGE='266',
 XY='(-8250,3050)',
 ROT='0',
 VER='1',
 PACK_TYPE='0402LF',
 LOCATION='PR2521',
 CDS_LIB='pure_quanta',
 CDS_PART_NAME='Q_RES_0402LF-1,1%,1/16W,CHIP,CS-1002FB04',
 ROOM='HSC BOM2',
 PART_NUMBER='CS-1002FB04',
 VALUE='1',
 PRIM_FILE='./archive_libs/logical/q_res/chips/chips.prt';

PART_NAME
 PR2522 'Q_RES_0402LF-1,1%,1/16W,CHIP,CS-1002FB04':
 ROOM='HSC BOM2';

SECTION_NUMBER 1
 '@T6G_MB_LIB.T6G(SCH_1):PAGE302_I7@PURE_QUANTA.Q_RES(CHIPS)':
 C_PATH='@t6g_mb_lib.t6g(sch_1):page302_i7@pure_quanta.q_res(chips)',
 P_PATH='@t6g_mb_lib.t6g(sch_1):page266_i7@pure_quanta.q_res(chips)',
 PATH='I7',
 DRAWING='@T6G_MB_LIB.T6G(SCH_1):PAGE302',
 WATTAGE='1/16W',
 TOLERANCE='1%',
 MATERIAL='CHIP',
 PHYS_PAGE='266',
 XY='(-8250,2950)',
 ROT='0',
 VER='1',
 PACK_TYPE='0402LF',
 LOCATION='PR2522',
 CDS_LIB='pure_quanta',
 CDS_PART_NAME='Q_RES_0402LF-1,1%,1/16W,CHIP,CS-1002FB04',
 ROOM='HSC BOM2',
 PART_NUMBER='CS-1002FB04',
 VALUE='1',
 PRIM_FILE='./archive_libs/logical/q_res/chips/chips.prt';

PART_NAME
 PR2523 'Q_RES_0402LF-1,1%,1/16W,CHIP,CS-1002FB04':
 ROOM='HSC BOM2';

SECTION_NUMBER 1
 '@T6G_MB_LIB.T6G(SCH_1):PAGE302_I5@PURE_QUANTA.Q_RES(CHIPS)':
 C_PATH='@t6g_mb_lib.t6g(sch_1):page302_i5@pure_quanta.q_res(chips)',
 P_PATH='@t6g_mb_lib.t6g(sch_1):page266_i5@pure_quanta.q_res(chips)',
 PATH='I5',
 DRAWING='@T6G_MB_LIB.T6G(SCH_1):PAGE302',
 WATTAGE='1/16W',
 TOLERANCE='1%',
 MATERIAL='CHIP',
 PHYS_PAGE='266',
 XY='(-8250,2850)',
 ROT='0',
 VER='1',
 PACK_TYPE='0402LF',
 LOCATION='PR2523',
 CDS_LIB='pure_quanta',
 CDS_PART_NAME='Q_RES_0402LF-1,1%,1/16W,CHIP,CS-1002FB04',
 ROOM='HSC BOM2',
 PART_NUMBER='CS-1002FB04',
 VALUE='1',
 PRIM_FILE='./archive_libs/logical/q_res/chips/chips.prt';

PART_NAME
 PR2524 'Q_RES_0402LF-10,1%,1/16W,CHIP,CS01002FB07':
 ROOM='HSC BOM2';

SECTION_NUMBER 1
 '@T6G_MB_LIB.T6G(SCH_1):PAGE302_I88@PURE_QUANTA.Q_RES(CHIPS)':
 C_PATH='@t6g_mb_lib.t6g(sch_1):page302_i88@pure_quanta.q_res(chips)',
 P_PATH='@t6g_mb_lib.t6g(sch_1):page266_i88@pure_quanta.q_res(chips)',
 PATH='I88',
 DRAWING='@T6G_MB_LIB.T6G(SCH_1):PAGE302',
 WATTAGE='1/16W',
 TOLERANCE='1%',
 MATERIAL='CHIP',
 PHYS_PAGE='266',
 XY='(-8225,2400)',
 ROT='0',
 VER='1',
 PACK_TYPE='0402LF',
 LOCATION='PR2524',
 CDS_LIB='pure_quanta',
 CDS_PART_NAME='Q_RES_0402LF-10,1%,1/16W,CHIP,CS01002FB07',
 ROOM='HSC BOM2',
 PART_NUMBER='CS01002FB07',
 VALUE='10',
 PRIM_FILE='./archive_libs/logical/q_res/chips/chips.prt';

PART_NAME
 PR2525 'Q_RES_0402LF-10,1%,1/16W,CHIP,CS01002FB07':
 ROOM='HSC BOM2';

SECTION_NUMBER 1
 '@T6G_MB_LIB.T6G(SCH_1):PAGE302_I89@PURE_QUANTA.Q_RES(CHIPS)':
 C_PATH='@t6g_mb_lib.t6g(sch_1):page302_i89@pure_quanta.q_res(chips)',
 P_PATH='@t6g_mb_lib.t6g(sch_1):page266_i89@pure_quanta.q_res(chips)',
 PATH='I89',
 DRAWING='@T6G_MB_LIB.T6G(SCH_1):PAGE302',
 WATTAGE='1/16W',
 TOLERANCE='1%',
 MATERIAL='CHIP',
 PHYS_PAGE='266',
 XY='(-8225,2300)',
 ROT='0',
 VER='1',
 PACK_TYPE='0402LF',
 LOCATION='PR2525',
 CDS_LIB='pure_quanta',
 CDS_PART_NAME='Q_RES_0402LF-10,1%,1/16W,CHIP,CS01002FB07',
 ROOM='HSC BOM2',
 PART_NUMBER='CS01002FB07',
 VALUE='10',
 PRIM_FILE='./archive_libs/logical/q_res/chips/chips.prt';

PART_NAME
 PR2526 'Q_RES_0402LF-10,1%,1/16W,CHIP,CS01002FB07':
 ROOM='HSC BOM2';

SECTION_NUMBER 1
 '@T6G_MB_LIB.T6G(SCH_1):PAGE302_I90@PURE_QUANTA.Q_RES(CHIPS)':
 C_PATH='@t6g_mb_lib.t6g(sch_1):page302_i90@pure_quanta.q_res(chips)',
 P_PATH='@t6g_mb_lib.t6g(sch_1):page266_i90@pure_quanta.q_res(chips)',
 PATH='I90',
 DRAWING='@T6G_MB_LIB.T6G(SCH_1):PAGE302',
 WATTAGE='1/16W',
 TOLERANCE='1%',
 MATERIAL='CHIP',
 PHYS_PAGE='266',
 XY='(-8225,2200)',
 ROT='0',
 VER='1',
 PACK_TYPE='0402LF',
 LOCATION='PR2526',
 CDS_LIB='pure_quanta',
 CDS_PART_NAME='Q_RES_0402LF-10,1%,1/16W,CHIP,CS01002FB07',
 ROOM='HSC BOM2',
 PART_NUMBER='CS01002FB07',
 VALUE='10',
 PRIM_FILE='./archive_libs/logical/q_res/chips/chips.prt';

PART_NAME
 PR2527 'Q_RES_0402LF-10,1%,1/16W,CHIP,CS01002FB07':
 ROOM='HSC BOM2';

SECTION_NUMBER 1
 '@T6G_MB_LIB.T6G(SCH_1):PAGE302_I91@PURE_QUANTA.Q_RES(CHIPS)':
 C_PATH='@t6g_mb_lib.t6g(sch_1):page302_i91@pure_quanta.q_res(chips)',
 P_PATH='@t6g_mb_lib.t6g(sch_1):page266_i91@pure_quanta.q_res(chips)',
 PATH='I91',
 DRAWING='@T6G_MB_LIB.T6G(SCH_1):PAGE302',
 WATTAGE='1/16W',
 TOLERANCE='1%',
 MATERIAL='CHIP',
 PHYS_PAGE='266',
 XY='(-8225,2100)',
 ROT='0',
 VER='1',
 PACK_TYPE='0402LF',
 LOCATION='PR2527',
 CDS_LIB='pure_quanta',
 CDS_PART_NAME='Q_RES_0402LF-10,1%,1/16W,CHIP,CS01002FB07',
 ROOM='HSC BOM2',
 PART_NUMBER='CS01002FB07',
 VALUE='10',
 PRIM_FILE='./archive_libs/logical/q_res/chips/chips.prt';

PART_NAME
 PR2528 'Q_RES_0402LF-10,1%,1/16W,CHIP,CS01002FB07':
 ROOM='HSC BOM2';

SECTION_NUMBER 1
 '@T6G_MB_LIB.T6G(SCH_1):PAGE302_I27@PURE_QUANTA.Q_RES(CHIPS)':
 C_PATH='@t6g_mb_lib.t6g(sch_1):page302_i27@pure_quanta.q_res(chips)',
 P_PATH='@t6g_mb_lib.t6g(sch_1):page266_i27@pure_quanta.q_res(chips)',
 PATH='I27',
 DRAWING='@T6G_MB_LIB.T6G(SCH_1):PAGE302',
 WATTAGE='1/16W',
 TOLERANCE='1%',
 MATERIAL='CHIP',
 PHYS_PAGE='266',
 XY='(-6550,1575)',
 ROT='0',
 VER='2',
 PACK_TYPE='0402LF',
 LOCATION='PR2528',
 CDS_LIB='pure_quanta',
 CDS_PART_NAME='Q_RES_0402LF-10,1%,1/16W,CHIP,CS01002FB07',
 ROOM='HSC BOM2',
 PART_NUMBER='CS01002FB07',
 VALUE='10',
 PRIM_FILE='./archive_libs/logical/q_res/chips/chips.prt';

PART_NAME
 PR2529 'Q_RES_0402LF-10,1%,1/16W,CHIP,CS01002FB07':
 ROOM='HSC BOM2';

SECTION_NUMBER 1
 '@T6G_MB_LIB.T6G(SCH_1):PAGE302_I28@PURE_QUANTA.Q_RES(CHIPS)':
 C_PATH='@t6g_mb_lib.t6g(sch_1):page302_i28@pure_quanta.q_res(chips)',
 P_PATH='@t6g_mb_lib.t6g(sch_1):page266_i28@pure_quanta.q_res(chips)',
 PATH='I28',
 DRAWING='@T6G_MB_LIB.T6G(SCH_1):PAGE302',
 WATTAGE='1/16W',
 TOLERANCE='1%',
 MATERIAL='CHIP',
 PHYS_PAGE='266',
 XY='(-5675,1575)',
 ROT='0',
 VER='2',
 PACK_TYPE='0402LF',
 LOCATION='PR2529',
 CDS_LIB='pure_quanta',
 CDS_PART_NAME='Q_RES_0402LF-10,1%,1/16W,CHIP,CS01002FB07',
 ROOM='HSC BOM2',
 PART_NUMBER='CS01002FB07',
 VALUE='10',
 PRIM_FILE='./archive_libs/logical/q_res/chips/chips.prt';

PART_NAME
 PR2530 'Q_RES_0402LF-10,1%,1/16W,CHIP,CS01002FB07':
 ROOM='HSC BOM2';

SECTION_NUMBER 1
 '@T6G_MB_LIB.T6G(SCH_1):PAGE302_I45@PURE_QUANTA.Q_RES(CHIPS)':
 C_PATH='@t6g_mb_lib.t6g(sch_1):page302_i45@pure_quanta.q_res(chips)',
 P_PATH='@t6g_mb_lib.t6g(sch_1):page266_i45@pure_quanta.q_res(chips)',
 PATH='I45',
 DRAWING='@T6G_MB_LIB.T6G(SCH_1):PAGE302',
 WATTAGE='1/16W',
 TOLERANCE='1%',
 MATERIAL='CHIP',
 PHYS_PAGE='266',
 XY='(-4825,1575)',
 ROT='0',
 VER='2',
 PACK_TYPE='0402LF',
 LOCATION='PR2530',
 CDS_LIB='pure_quanta',
 CDS_PART_NAME='Q_RES_0402LF-10,1%,1/16W,CHIP,CS01002FB07',
 ROOM='HSC BOM2',
 PART_NUMBER='CS01002FB07',
 VALUE='10',
 PRIM_FILE='./archive_libs/logical/q_res/chips/chips.prt';

PART_NAME
 PR2531 'Q_RES_0402LF-10,1%,1/16W,CHIP,CS01002FB07':
 ROOM='HSC BOM2';

SECTION_NUMBER 1
 '@T6G_MB_LIB.T6G(SCH_1):PAGE302_I47@PURE_QUANTA.Q_RES(CHIPS)':
 C_PATH='@t6g_mb_lib.t6g(sch_1):page302_i47@pure_quanta.q_res(chips)',
 P_PATH='@t6g_mb_lib.t6g(sch_1):page266_i47@pure_quanta.q_res(chips)',
 PATH='I47',
 DRAWING='@T6G_MB_LIB.T6G(SCH_1):PAGE302',
 WATTAGE='1/16W',
 TOLERANCE='1%',
 MATERIAL='CHIP',
 PHYS_PAGE='266',
 XY='(-3975,1575)',
 ROT='0',
 VER='2',
 PACK_TYPE='0402LF',
 LOCATION='PR2531',
 CDS_LIB='pure_quanta',
 CDS_PART_NAME='Q_RES_0402LF-10,1%,1/16W,CHIP,CS01002FB07',
 ROOM='HSC BOM2',
 PART_NUMBER='CS01002FB07',
 VALUE='10',
 PRIM_FILE='./archive_libs/logical/q_res/chips/chips.prt';

PART_NAME
 PR2532 'Q_SP_RES4P-0.0003,1%,4W,SMLF,CHIP,SP_CS0000FFT09':
 ROOM='HSC BOM2';

SECTION_NUMBER 1
 '@T6G_MB_LIB.T6G(SCH_1):PAGE302_I54@PURE_QUANTA.Q_SP_RES4P(CHIPS)':
 C_PATH='@t6g_mb_lib.t6g(sch_1):page302_i54@pure_quanta.q_sp_res4p(chips)',
 P_PATH='@t6g_mb_lib.t6g(sch_1):page266_i54@pure_quanta.q_sp_res4p(chips)',
 PATH='I54',
 DRAWING='@T6G_MB_LIB.T6G(SCH_1):PAGE302',
 WATTAGE='4W',
 TOLERANCE='1%',
 PART_TYPE='SMLF',
 MATERIAL='CHIP',
 PHYS_PAGE='266',
 XY='(-3525,4400)',
 ROT='0',
 VER='1',
 LOCATION='PR2532',
 CDS_LIB='pure_quanta',
 CDS_PART_NAME='Q_SP_RES4P-0.0003,1%,4W,SMLF,CHIP,SP_CS0000FFT09',
 ROOM='HSC BOM2',
 PART_NUMBER='SP_CS0000FFT09',
 VALUE='0.0003',
 PRIM_FILE='./archive_libs/logical/q_sp_res4p/chips/chips.prt';

PART_NAME
 PR2533 'Q_SP_RES4P-0.0003,1%,4W,SMLF,CHIP,SP_CS0000FFT09':
 ROOM='HSC BOM2';

SECTION_NUMBER 1
 '@T6G_MB_LIB.T6G(SCH_1):PAGE302_I53@PURE_QUANTA.Q_SP_RES4P(CHIPS)':
 C_PATH='@t6g_mb_lib.t6g(sch_1):page302_i53@pure_quanta.q_sp_res4p(chips)',
 P_PATH='@t6g_mb_lib.t6g(sch_1):page266_i53@pure_quanta.q_sp_res4p(chips)',
 PATH='I53',
 DRAWING='@T6G_MB_LIB.T6G(SCH_1):PAGE302',
 WATTAGE='4W',
 TOLERANCE='1%',
 PART_TYPE='SMLF',
 MATERIAL='CHIP',
 PHYS_PAGE='266',
 XY='(-3525,3825)',
 ROT='0',
 VER='1',
 LOCATION='PR2533',
 CDS_LIB='pure_quanta',
 CDS_PART_NAME='Q_SP_RES4P-0.0003,1%,4W,SMLF,CHIP,SP_CS0000FFT09',
 ROOM='HSC BOM2',
 PART_NUMBER='SP_CS0000FFT09',
 VALUE='0.0003',
 PRIM_FILE='./archive_libs/logical/q_sp_res4p/chips/chips.prt';

PART_NAME
 PR2534 'Q_SP_RES4P-0.0003,1%,4W,SMLF,CHIP,SP_CS0000FFT09':
 ROOM='HSC BOM2';

SECTION_NUMBER 1
 '@T6G_MB_LIB.T6G(SCH_1):PAGE302_I52@PURE_QUANTA.Q_SP_RES4P(CHIPS)':
 C_PATH='@t6g_mb_lib.t6g(sch_1):page302_i52@pure_quanta.q_sp_res4p(chips)',
 P_PATH='@t6g_mb_lib.t6g(sch_1):page266_i52@pure_quanta.q_sp_res4p(chips)',
 PATH='I52',
 DRAWING='@T6G_MB_LIB.T6G(SCH_1):PAGE302',
 WATTAGE='4W',
 TOLERANCE='1%',
 PART_TYPE='SMLF',
 MATERIAL='CHIP',
 PHYS_PAGE='266',
 XY='(-3525,3225)',
 ROT='0',
 VER='1',
 LOCATION='PR2534',
 CDS_LIB='pure_quanta',
 CDS_PART_NAME='Q_SP_RES4P-0.0003,1%,4W,SMLF,CHIP,SP_CS0000FFT09',
 ROOM='HSC BOM2',
 PART_NUMBER='SP_CS0000FFT09',
 VALUE='0.0003',
 PRIM_FILE='./archive_libs/logical/q_sp_res4p/chips/chips.prt';

PART_NAME
 PR2535 'Q_RES_0402LF-10,1%,1/16W,CHIP,CS01002FB07':
 ROOM='HSC BOM2';

SECTION_NUMBER 1
 '@T6G_MB_LIB.T6G(SCH_1):PAGE302_I60@PURE_QUANTA.Q_RES(CHIPS)':
 C_PATH='@t6g_mb_lib.t6g(sch_1):page302_i60@pure_quanta.q_res(chips)',
 P_PATH='@t6g_mb_lib.t6g(sch_1):page266_i60@pure_quanta.q_res(chips)',
 PATH='I60',
 DRAWING='@T6G_MB_LIB.T6G(SCH_1):PAGE302',
 WATTAGE='1/16W',
 TOLERANCE='1%',
 MATERIAL='CHIP',
 PHYS_PAGE='266',
 XY='(-3125,1575)',
 ROT='0',
 VER='2',
 PACK_TYPE='0402LF',
 LOCATION='PR2535',
 CDS_LIB='pure_quanta',
 CDS_PART_NAME='Q_RES_0402LF-10,1%,1/16W,CHIP,CS01002FB07',
 ROOM='HSC BOM2',
 PART_NUMBER='CS01002FB07',
 VALUE='10',
 PRIM_FILE='./archive_libs/logical/q_res/chips/chips.prt';

PART_NAME
 PR2536 'Q_RES_0402LF-10,1%,1/16W,CHIP,CS01002FB07':
 ROOM='HSC BOM2';

SECTION_NUMBER 1
 '@T6G_MB_LIB.T6G(SCH_1):PAGE302_I62@PURE_QUANTA.Q_RES(CHIPS)':
 C_PATH='@t6g_mb_lib.t6g(sch_1):page302_i62@pure_quanta.q_res(chips)',
 P_PATH='@t6g_mb_lib.t6g(sch_1):page266_i62@pure_quanta.q_res(chips)',
 PATH='I62',
 DRAWING='@T6G_MB_LIB.T6G(SCH_1):PAGE302',
 WATTAGE='1/16W',
 TOLERANCE='1%',
 MATERIAL='CHIP',
 PHYS_PAGE='266',
 XY='(-2250,1575)',
 ROT='0',
 VER='2',
 PACK_TYPE='0402LF',
 LOCATION='PR2536',
 CDS_LIB='pure_quanta',
 CDS_PART_NAME='Q_RES_0402LF-10,1%,1/16W,CHIP,CS01002FB07',
 ROOM='HSC BOM2',
 PART_NUMBER='CS01002FB07',
 VALUE='10',
 PRIM_FILE='./archive_libs/logical/q_res/chips/chips.prt';

PART_NAME
 PR2537 'Q_RES_0402LF-10,1%,1/16W,EMPTY,CS01002FB07':
 ROOM='HSC BOM2';

SECTION_NUMBER 1
 '@T6G_MB_LIB.T6G(SCH_1):PAGE302_I71@PURE_QUANTA.Q_RES(CHIPS)':
 C_PATH='@t6g_mb_lib.t6g(sch_1):page302_i71@pure_quanta.q_res(chips)',
 P_PATH='@t6g_mb_lib.t6g(sch_1):page266_i71@pure_quanta.q_res(chips)',
 PATH='I71',
 DRAWING='@T6G_MB_LIB.T6G(SCH_1):PAGE302',
 WATTAGE='1/16W',
 TOLERANCE='1%',
 MATERIAL='EMPTY',
 PHYS_PAGE='266',
 XY='(-1175,1600)',
 ROT='0',
 VER='2',
 PACK_TYPE='0402LF',
 LOCATION='PR2537',
 CDS_LIB='pure_quanta',
 CDS_PART_NAME='Q_RES_0402LF-10,1%,1/16W,EMPTY,CS01002FB07',
 ROOM='HSC BOM2',
 PART_NUMBER='CS01002FB07',
 VALUE='10',
 PRIM_FILE='./archive_libs/logical/q_res/chips/chips.prt';

PART_NAME
 PR2538 'Q_RES_0402LF-10,1%,1/16W,CHIP,CS01002FB07':
 ROOM='HSC BOM2';

SECTION_NUMBER 1
 '@T6G_MB_LIB.T6G(SCH_1):PAGE302_I74@PURE_QUANTA.Q_RES(CHIPS)':
 C_PATH='@t6g_mb_lib.t6g(sch_1):page302_i74@pure_quanta.q_res(chips)',
 P_PATH='@t6g_mb_lib.t6g(sch_1):page266_i74@pure_quanta.q_res(chips)',
 PATH='I74',
 DRAWING='@T6G_MB_LIB.T6G(SCH_1):PAGE302',
 WATTAGE='1/16W',
 TOLERANCE='1%',
 MATERIAL='CHIP',
 PHYS_PAGE='266',
 XY='(-875,3025)',
 ROT='0',
 VER='2',
 PACK_TYPE='0402LF',
 LOCATION='PR2538',
 CDS_LIB='pure_quanta',
 CDS_PART_NAME='Q_RES_0402LF-10,1%,1/16W,CHIP,CS01002FB07',
 ROOM='HSC BOM2',
 PART_NUMBER='CS01002FB07',
 VALUE='10',
 PRIM_FILE='./archive_libs/logical/q_res/chips/chips.prt';

PART_NAME
 PR3002 'Q_RES_0402LF-0,5%,1/16W,CHIP,CS00002JB13':;

SECTION_NUMBER 1
 '@T6G_MB_LIB.T6G(SCH_1):PAGE372_I27@PURE_QUANTA.Q_RES(CHIPS)':
 C_PATH='@t6g_mb_lib.t6g(sch_1):page372_i27@pure_quanta.q_res(chips)',
 P_PATH='@t6g_mb_lib.t6g(sch_1):page268_i27@pure_quanta.q_res(chips)',
 PATH='I27',
 DRAWING='@T6G_MB_LIB.T6G(SCH_1):PAGE372',
 WATTAGE='1/16W',
 TOLERANCE='5%',
 MATERIAL='CHIP',
 PHYS_PAGE='268',
 XY='(-8400,4900)',
 ROT='0',
 VER='1',
 PACK_TYPE='0402LF',
 LOCATION='PR3002',
 CDS_LIB='pure_quanta',
 CDS_PART_NAME='Q_RES_0402LF-0,5%,1/16W,CHIP,CS00002JB13',
 PART_NUMBER='CS00002JB13',
 VALUE='0',
 PRIM_FILE='./archive_libs/logical/q_res/chips/chips.prt';

PART_NAME
 PR3337 'Q_RES_0402LF-0,5%,1/16W,CHIP,CS00002JB13':;

SECTION_NUMBER 1
 '@T6G_MB_LIB.T6G(SCH_1):PAGE244_I37@PURE_QUANTA.Q_RES(CHIPS)':
 C_PATH='@t6g_mb_lib.t6g(sch_1):page244_i37@pure_quanta.q_res(chips)',
 P_PATH='@t6g_mb_lib.t6g(sch_1):page189_i37@pure_quanta.q_res(chips)',
 PATH='I37',
 DRAWING='@T6G_MB_LIB.T6G(SCH_1):PAGE244',
 WATTAGE='1/16W',
 TOLERANCE='5%',
 MATERIAL='CHIP',
 PHYS_PAGE='189',
 XY='(-5975,7450)',
 ROT='0',
 VER='1',
 PACK_TYPE='0402LF',
 LOCATION='PR3337',
 CDS_LIB='pure_quanta',
 CDS_PART_NAME='Q_RES_0402LF-0,5%,1/16W,CHIP,CS00002JB13',
 PART_NUMBER='CS00002JB13',
 VALUE='0',
 PRIM_FILE='./archive_libs/logical/q_res/chips/chips.prt';

PART_NAME
 PR3780 'Q_RES_0402LF-5.36K,1%,1/16W,CHIP,CS25362FB02':
 ROOM='NIC_P3V3_BOM1';

SECTION_NUMBER 1
 '@T6G_MB_LIB.T6G(SCH_1):PAGE338_I111@PURE_QUANTA.Q_RES(CHIPS)':
 C_PATH='@t6g_mb_lib.t6g(sch_1):page338_i111@pure_quanta.q_res(chips)',
 P_PATH='@t6g_mb_lib.t6g(sch_1):page134_i111@pure_quanta.q_res(chips)',
 PATH='I111',
 DRAWING='@T6G_MB_LIB.T6G(SCH_1):PAGE338',
 WATTAGE='1/16W',
 TOLERANCE='1%',
 MATERIAL='CHIP',
 PHYS_PAGE='134',
 XY='(7100,12275)',
 ROT='0',
 VER='2',
 PACK_TYPE='0402LF',
 LOCATION='PR3780',
 CDS_LIB='pure_quanta',
 CDS_PART_NAME='Q_RES_0402LF-5.36K,1%,1/16W,CHIP,CS25362FB02',
 ROOM='NIC_P3V3_BOM1',
 PART_NUMBER='CS25362FB02',
 VALUE='5.36K',
 PRIM_FILE='./archive_libs/logical/q_res/chips/chips.prt';

PART_NAME
 PR3781 'Q_RES_0402LF-845,1%,1/16W,CHIP,CS18452FB01':
 ROOM='NIC_P12V_MAM_TIC_BOM1';

SECTION_NUMBER 1
 '@T6G_MB_LIB.T6G(SCH_1):PAGE338_I73@PURE_QUANTA.Q_RES(CHIPS)':
 C_PATH='@t6g_mb_lib.t6g(sch_1):page338_i73@pure_quanta.q_res(chips)',
 P_PATH='@t6g_mb_lib.t6g(sch_1):page134_i73@pure_quanta.q_res(chips)',
 PATH='I73',
 DRAWING='@T6G_MB_LIB.T6G(SCH_1):PAGE338',
 WATTAGE='1/16W',
 TOLERANCE='1%',
 MATERIAL='CHIP',
 PHYS_PAGE='134',
 XY='(8475,10325)',
 ROT='0',
 VER='2',
 PACK_TYPE='0402LF',
 LOCATION='PR3781',
 CDS_LIB='pure_quanta',
 CDS_PART_NAME='Q_RES_0402LF-845,1%,1/16W,CHIP,CS18452FB01',
 ROOM='NIC_P12V_MAM_TIC_BOM1',
 PART_NUMBER='CS18452FB01',
 VALUE='845',
 PRIM_FILE='./archive_libs/logical/q_res/chips/chips.prt';

PART_NAME
 PR3782 'Q_RES_0402LF-10,1%,1/16W,CHIP,CS01002FB07':
 ROOM='NIC_P3V3_BOM1';

SECTION_NUMBER 1
 '@T6G_MB_LIB.T6G(SCH_1):PAGE343_I91@PURE_QUANTA.Q_RES(CHIPS)':
 C_PATH='@t6g_mb_lib.t6g(sch_1):page343_i91@pure_quanta.q_res(chips)',
 P_PATH='@t6g_mb_lib.t6g(sch_1):page140_i91@pure_quanta.q_res(chips)',
 PATH='I91',
 DRAWING='@T6G_MB_LIB.T6G(SCH_1):PAGE343',
 WATTAGE='1/16W',
 TOLERANCE='1%',
 MATERIAL='CHIP',
 PHYS_PAGE='140',
 XY='(300,9350)',
 ROT='0',
 VER='2',
 PACK_TYPE='0402LF',
 LOCATION='PR3782',
 CDS_LIB='pure_quanta',
 CDS_PART_NAME='Q_RES_0402LF-10,1%,1/16W,CHIP,CS01002FB07',
 ROOM='NIC_P3V3_BOM1',
 PART_NUMBER='CS01002FB07',
 VALUE='10',
 PRIM_FILE='./archive_libs/logical/q_res/chips/chips.prt';

PART_NAME
 PR3786 'Q_RES_0402LF-160K,1%,1/16W,CHIP,CS41602FB05':
 ROOM='NIC_P12V_MAM_TIC_BOM1';

SECTION_NUMBER 1
 '@T6G_MB_LIB.T6G(SCH_1):PAGE338_I43@PURE_QUANTA.Q_RES(CHIPS)':
 C_PATH='@t6g_mb_lib.t6g(sch_1):page338_i43@pure_quanta.q_res(chips)',
 P_PATH='@t6g_mb_lib.t6g(sch_1):page134_i43@pure_quanta.q_res(chips)',
 PATH='I43',
 DRAWING='@T6G_MB_LIB.T6G(SCH_1):PAGE338',
 WATTAGE='1/16W',
 TOLERANCE='1%',
 MATERIAL='CHIP',
 PHYS_PAGE='134',
 XY='(6025,11150)',
 ROT='0',
 VER='2',
 PACK_TYPE='0402LF',
 LOCATION='PR3786',
 CDS_LIB='pure_quanta',
 CDS_PART_NAME='Q_RES_0402LF-160K,1%,1/16W,CHIP,CS41602FB05',
 ROOM='NIC_P12V_MAM_TIC_BOM1',
 PART_NUMBER='CS41602FB05',
 VALUE='160K',
 PRIM_FILE='./archive_libs/logical/q_res/chips/chips.prt';

PART_NAME
 PR3787 'Q_RES_0402LF-6.8K,1%,1/16W,CHIP,CS26802FB02':
 ROOM='NIC_P12V_MAM_TIC_BOM1';

SECTION_NUMBER 1
 '@T6G_MB_LIB.T6G(SCH_1):PAGE338_I42@PURE_QUANTA.Q_RES(CHIPS)':
 C_PATH='@t6g_mb_lib.t6g(sch_1):page338_i42@pure_quanta.q_res(chips)',
 P_PATH='@t6g_mb_lib.t6g(sch_1):page134_i42@pure_quanta.q_res(chips)',
 PATH='I42',
 DRAWING='@T6G_MB_LIB.T6G(SCH_1):PAGE338',
 WATTAGE='1/16W',
 TOLERANCE='1%',
 MATERIAL='CHIP',
 PHYS_PAGE='134',
 XY='(6025,10475)',
 ROT='0',
 VER='2',
 PACK_TYPE='0402LF',
 LOCATION='PR3787',
 CDS_LIB='pure_quanta',
 CDS_PART_NAME='Q_RES_0402LF-6.8K,1%,1/16W,CHIP,CS26802FB02',
 ROOM='NIC_P12V_MAM_TIC_BOM1',
 PART_NUMBER='CS26802FB02',
 VALUE='6.8K',
 PRIM_FILE='./archive_libs/logical/q_res/chips/chips.prt';

PART_NAME
 PR3788 'Q_RES_0402LF-15K,1%,1/16W,CHIP,CS31502FB05':
 ROOM='NIC_P12V_MAM_TIC_BOM1';

SECTION_NUMBER 1
 '@T6G_MB_LIB.T6G(SCH_1):PAGE338_I36@PURE_QUANTA.Q_RES(CHIPS)':
 C_PATH='@t6g_mb_lib.t6g(sch_1):page338_i36@pure_quanta.q_res(chips)',
 P_PATH='@t6g_mb_lib.t6g(sch_1):page134_i36@pure_quanta.q_res(chips)',
 PATH='I36',
 DRAWING='@T6G_MB_LIB.T6G(SCH_1):PAGE338',
 WATTAGE='1/16W',
 TOLERANCE='1%',
 MATERIAL='CHIP',
 PHYS_PAGE='134',
 XY='(6025,10200)',
 ROT='0',
 VER='2',
 PACK_TYPE='0402LF',
 LOCATION='PR3788',
 CDS_LIB='pure_quanta',
 CDS_PART_NAME='Q_RES_0402LF-15K,1%,1/16W,CHIP,CS31502FB05',
 ROOM='NIC_P12V_MAM_TIC_BOM1',
 PART_NUMBER='CS31502FB05',
 VALUE='15K',
 PRIM_FILE='./archive_libs/logical/q_res/chips/chips.prt';

PART_NAME
 PR3789 'Q_RES_0402LF-25.5K,1%,1/16W,CHIP,CS32552FB06':
 ROOM='NIC_P3V3_BOM1';

SECTION_NUMBER 1
 '@T6G_MB_LIB.T6G(SCH_1):PAGE338_I66@PURE_QUANTA.Q_RES(CHIPS)':
 C_PATH='@t6g_mb_lib.t6g(sch_1):page338_i66@pure_quanta.q_res(chips)',
 P_PATH='@t6g_mb_lib.t6g(sch_1):page134_i66@pure_quanta.q_res(chips)',
 PATH='I66',
 DRAWING='@T6G_MB_LIB.T6G(SCH_1):PAGE338',
 WATTAGE='1/16W',
 TOLERANCE='1%',
 MATERIAL='CHIP',
 PHYS_PAGE='134',
 XY='(6250,13250)',
 ROT='0',
 VER='2',
 PACK_TYPE='0402LF',
 LOCATION='PR3789',
 CDS_LIB='pure_quanta',
 CDS_PART_NAME='Q_RES_0402LF-25.5K,1%,1/16W,CHIP,CS32552FB06',
 ROOM='NIC_P3V3_BOM1',
 PART_NUMBER='CS32552FB06',
 VALUE='25.5K',
 PRIM_FILE='./archive_libs/logical/q_res/chips/chips.prt';

PART_NAME
 PR3790 'Q_RES_0402LF-7.15K,1%,1/16W,CHIP,CS27152FB03':
 ROOM='NIC_P3V3_BOM1';

SECTION_NUMBER 1
 '@T6G_MB_LIB.T6G(SCH_1):PAGE338_I64@PURE_QUANTA.Q_RES(CHIPS)':
 C_PATH='@t6g_mb_lib.t6g(sch_1):page338_i64@pure_quanta.q_res(chips)',
 P_PATH='@t6g_mb_lib.t6g(sch_1):page134_i64@pure_quanta.q_res(chips)',
 PATH='I64',
 DRAWING='@T6G_MB_LIB.T6G(SCH_1):PAGE338',
 WATTAGE='1/16W',
 TOLERANCE='1%',
 MATERIAL='CHIP',
 PHYS_PAGE='134',
 XY='(6250,12525)',
 ROT='0',
 VER='2',
 PACK_TYPE='0402LF',
 LOCATION='PR3790',
 CDS_LIB='pure_quanta',
 CDS_PART_NAME='Q_RES_0402LF-7.15K,1%,1/16W,CHIP,CS27152FB03',
 ROOM='NIC_P3V3_BOM1',
 PART_NUMBER='CS27152FB03',
 VALUE='7.15K',
 PRIM_FILE='./archive_libs/logical/q_res/chips/chips.prt';

PART_NAME
 PR3791 'Q_RES_0402LF-15K,1%,1/16W,CHIP,CS31502FB05':
 ROOM='NIC_P3V3_BOM1';

SECTION_NUMBER 1
 '@T6G_MB_LIB.T6G(SCH_1):PAGE338_I114@PURE_QUANTA.Q_RES(CHIPS)':
 C_PATH='@t6g_mb_lib.t6g(sch_1):page338_i114@pure_quanta.q_res(chips)',
 P_PATH='@t6g_mb_lib.t6g(sch_1):page134_i114@pure_quanta.q_res(chips)',
 PATH='I114',
 DRAWING='@T6G_MB_LIB.T6G(SCH_1):PAGE338',
 WATTAGE='1/16W',
 TOLERANCE='1%',
 MATERIAL='CHIP',
 PHYS_PAGE='134',
 XY='(6250,12250)',
 ROT='0',
 VER='2',
 PACK_TYPE='0402LF',
 LOCATION='PR3791',
 CDS_LIB='pure_quanta',
 CDS_PART_NAME='Q_RES_0402LF-15K,1%,1/16W,CHIP,CS31502FB05',
 ROOM='NIC_P3V3_BOM1',
 PART_NUMBER='CS31502FB05',
 VALUE='15K',
 PRIM_FILE='./archive_libs/logical/q_res/chips/chips.prt';

PART_NAME
 PR3792 'Q_RES_0402LF-10,1%,1/16W,CHIP,CS01002FB07':
 ROOM='NIC_P12V_MAM_TIC_BOM1';

SECTION_NUMBER 1
 '@T6G_MB_LIB.T6G(SCH_1):PAGE338_I56@PURE_QUANTA.Q_RES(CHIPS)':
 C_PATH='@t6g_mb_lib.t6g(sch_1):page338_i56@pure_quanta.q_res(chips)',
 P_PATH='@t6g_mb_lib.t6g(sch_1):page134_i56@pure_quanta.q_res(chips)',
 PATH='I56',
 DRAWING='@T6G_MB_LIB.T6G(SCH_1):PAGE338',
 WATTAGE='1/16W',
 TOLERANCE='1%',
 MATERIAL='CHIP',
 PHYS_PAGE='134',
 XY='(6350,11450)',
 ROT='0',
 VER='2',
 PACK_TYPE='0402LF',
 LOCATION='PR3792',
 CDS_LIB='pure_quanta',
 CDS_PART_NAME='Q_RES_0402LF-10,1%,1/16W,CHIP,CS01002FB07',
 ROOM='NIC_P12V_MAM_TIC_BOM1',
 PART_NUMBER='CS01002FB07',
 VALUE='10',
 PRIM_FILE='./archive_libs/logical/q_res/chips/chips.prt';

PART_NAME
 PR3795 'Q_RES_0402LF-25.5K,1%,1/16W,CHIP,CS32552FB06':
 ROOM='NIC_P3V3_BOM1';

SECTION_NUMBER 1
 '@T6G_MB_LIB.T6G(SCH_1):PAGE343_I56@PURE_QUANTA.Q_RES(CHIPS)':
 C_PATH='@t6g_mb_lib.t6g(sch_1):page343_i56@pure_quanta.q_res(chips)',
 P_PATH='@t6g_mb_lib.t6g(sch_1):page140_i56@pure_quanta.q_res(chips)',
 PATH='I56',
 DRAWING='@T6G_MB_LIB.T6G(SCH_1):PAGE343',
 WATTAGE='1/16W',
 TOLERANCE='1%',
 MATERIAL='CHIP',
 PHYS_PAGE='140',
 XY='(-25,9100)',
 ROT='0',
 VER='2',
 PACK_TYPE='0402LF',
 LOCATION='PR3795',
 CDS_LIB='pure_quanta',
 CDS_PART_NAME='Q_RES_0402LF-25.5K,1%,1/16W,CHIP,CS32552FB06',
 ROOM='NIC_P3V3_BOM1',
 PART_NUMBER='CS32552FB06',
 VALUE='25.5K',
 PRIM_FILE='./archive_libs/logical/q_res/chips/chips.prt';

PART_NAME
 PR3798 'Q_RES_0402LF-10,1%,1/16W,CHIP,CS01002FB07':
 ROOM='NIC_P3V3_BOM1';

SECTION_NUMBER 1
 '@T6G_MB_LIB.T6G(SCH_1):PAGE338_I68@PURE_QUANTA.Q_RES(CHIPS)':
 C_PATH='@t6g_mb_lib.t6g(sch_1):page338_i68@pure_quanta.q_res(chips)',
 P_PATH='@t6g_mb_lib.t6g(sch_1):page134_i68@pure_quanta.q_res(chips)',
 PATH='I68',
 DRAWING='@T6G_MB_LIB.T6G(SCH_1):PAGE338',
 WATTAGE='1/16W',
 TOLERANCE='1%',
 MATERIAL='CHIP',
 PHYS_PAGE='134',
 XY='(6575,13500)',
 ROT='0',
 VER='2',
 PACK_TYPE='0402LF',
 LOCATION='PR3798',
 CDS_LIB='pure_quanta',
 CDS_PART_NAME='Q_RES_0402LF-10,1%,1/16W,CHIP,CS01002FB07',
 ROOM='NIC_P3V3_BOM1',
 PART_NUMBER='CS01002FB07',
 VALUE='10',
 PRIM_FILE='./archive_libs/logical/q_res/chips/chips.prt';

PART_NAME
 PR3805 'Q_RES_0402LF-160K,1%,1/16W,CHIP,CS41602FB05':
 ROOM='NIC_P12V_MAM_TIC_BOM1';

SECTION_NUMBER 1
 '@T6G_MB_LIB.T6G(SCH_1):PAGE343_I36@PURE_QUANTA.Q_RES(CHIPS)':
 C_PATH='@t6g_mb_lib.t6g(sch_1):page343_i36@pure_quanta.q_res(chips)',
 P_PATH='@t6g_mb_lib.t6g(sch_1):page140_i36@pure_quanta.q_res(chips)',
 PATH='I36',
 DRAWING='@T6G_MB_LIB.T6G(SCH_1):PAGE343',
 WATTAGE='1/16W',
 TOLERANCE='1%',
 MATERIAL='CHIP',
 PHYS_PAGE='140',
 XY='(-150,6725)',
 ROT='0',
 VER='2',
 PACK_TYPE='0402LF',
 LOCATION='PR3805',
 CDS_LIB='pure_quanta',
 CDS_PART_NAME='Q_RES_0402LF-160K,1%,1/16W,CHIP,CS41602FB05',
 ROOM='NIC_P12V_MAM_TIC_BOM1',
 PART_NUMBER='CS41602FB05',
 VALUE='160K',
 PRIM_FILE='./archive_libs/logical/q_res/chips/chips.prt';

PART_NAME
 PR3806 'Q_RES_0402LF-6.8K,1%,1/16W,CHIP,CS26802FB02':
 ROOM='NIC_P12V_MAM_TIC_BOM1';

SECTION_NUMBER 1
 '@T6G_MB_LIB.T6G(SCH_1):PAGE343_I35@PURE_QUANTA.Q_RES(CHIPS)':
 C_PATH='@t6g_mb_lib.t6g(sch_1):page343_i35@pure_quanta.q_res(chips)',
 P_PATH='@t6g_mb_lib.t6g(sch_1):page140_i35@pure_quanta.q_res(chips)',
 PATH='I35',
 DRAWING='@T6G_MB_LIB.T6G(SCH_1):PAGE343',
 WATTAGE='1/16W',
 TOLERANCE='1%',
 MATERIAL='CHIP',
 PHYS_PAGE='140',
 XY='(-150,6050)',
 ROT='0',
 VER='2',
 PACK_TYPE='0402LF',
 LOCATION='PR3806',
 CDS_LIB='pure_quanta',
 CDS_PART_NAME='Q_RES_0402LF-6.8K,1%,1/16W,CHIP,CS26802FB02',
 ROOM='NIC_P12V_MAM_TIC_BOM1',
 PART_NUMBER='CS26802FB02',
 VALUE='6.8K',
 PRIM_FILE='./archive_libs/logical/q_res/chips/chips.prt';

PART_NAME
 PR3812 'Q_RES_0402LF-15K,1%,1/16W,CHIP,CS31502FB05':
 ROOM='NIC_P3V3_BOM1';

SECTION_NUMBER 1
 '@T6G_MB_LIB.T6G(SCH_1):PAGE343_I51@PURE_QUANTA.Q_RES(CHIPS)':
 C_PATH='@t6g_mb_lib.t6g(sch_1):page343_i51@pure_quanta.q_res(chips)',
 P_PATH='@t6g_mb_lib.t6g(sch_1):page140_i51@pure_quanta.q_res(chips)',
 PATH='I51',
 DRAWING='@T6G_MB_LIB.T6G(SCH_1):PAGE343',
 WATTAGE='1/16W',
 TOLERANCE='1%',
 MATERIAL='CHIP',
 PHYS_PAGE='140',
 XY='(-25,8100)',
 ROT='0',
 VER='2',
 PACK_TYPE='0402LF',
 LOCATION='PR3812',
 CDS_LIB='pure_quanta',
 CDS_PART_NAME='Q_RES_0402LF-15K,1%,1/16W,CHIP,CS31502FB05',
 ROOM='NIC_P3V3_BOM1',
 PART_NUMBER='CS31502FB05',
 VALUE='15K',
 PRIM_FILE='./archive_libs/logical/q_res/chips/chips.prt';

PART_NAME
 PR3821 'Q_RES_0402LF-30.1K,1%,1/16W,CHIP,CS33012FB03':
 ROOM='NIC_P12V_MAM_TIC_BOM1';

SECTION_NUMBER 1
 '@T6G_MB_LIB.T6G(SCH_1):PAGE343_I63@PURE_QUANTA.Q_RES(CHIPS)':
 C_PATH='@t6g_mb_lib.t6g(sch_1):page343_i63@pure_quanta.q_res(chips)',
 P_PATH='@t6g_mb_lib.t6g(sch_1):page140_i63@pure_quanta.q_res(chips)',
 PATH='I63',
 DRAWING='@T6G_MB_LIB.T6G(SCH_1):PAGE343',
 WATTAGE='1/16W',
 TOLERANCE='1%',
 MATERIAL='CHIP',
 PHYS_PAGE='140',
 XY='(700,5800)',
 ROT='0',
 VER='2',
 PACK_TYPE='0402LF',
 LOCATION='PR3821',
 CDS_LIB='pure_quanta',
 CDS_PART_NAME='Q_RES_0402LF-30.1K,1%,1/16W,CHIP,CS33012FB03',
 ROOM='NIC_P12V_MAM_TIC_BOM1',
 PART_NUMBER='CS33012FB03',
 VALUE='30.1K',
 PRIM_FILE='./archive_libs/logical/q_res/chips/chips.prt';

PART_NAME
 PR3822 'Q_RES_0402LF-5.36K,1%,1/16W,CHIP,CS25362FB02':
 ROOM='NIC_P3V3_BOM1';

SECTION_NUMBER 1
 '@T6G_MB_LIB.T6G(SCH_1):PAGE343_I88@PURE_QUANTA.Q_RES(CHIPS)':
 C_PATH='@t6g_mb_lib.t6g(sch_1):page343_i88@pure_quanta.q_res(chips)',
 P_PATH='@t6g_mb_lib.t6g(sch_1):page140_i88@pure_quanta.q_res(chips)',
 PATH='I88',
 DRAWING='@T6G_MB_LIB.T6G(SCH_1):PAGE343',
 WATTAGE='1/16W',
 TOLERANCE='1%',
 MATERIAL='CHIP',
 PHYS_PAGE='140',
 XY='(825,8125)',
 ROT='0',
 VER='2',
 PACK_TYPE='0402LF',
 LOCATION='PR3822',
 CDS_LIB='pure_quanta',
 CDS_PART_NAME='Q_RES_0402LF-5.36K,1%,1/16W,CHIP,CS25362FB02',
 ROOM='NIC_P3V3_BOM1',
 PART_NUMBER='CS25362FB02',
 VALUE='5.36K',
 PRIM_FILE='./archive_libs/logical/q_res/chips/chips.prt';

PART_NAME
 PR3823 'Q_RES_0402LF-845,1%,1/16W,CHIP,CS18452FB01':
 ROOM='NIC_P12V_MAM_TIC_BOM1';

SECTION_NUMBER 1
 '@T6G_MB_LIB.T6G(SCH_1):PAGE343_I71@PURE_QUANTA.Q_RES(CHIPS)':
 C_PATH='@t6g_mb_lib.t6g(sch_1):page343_i71@pure_quanta.q_res(chips)',
 P_PATH='@t6g_mb_lib.t6g(sch_1):page140_i71@pure_quanta.q_res(chips)',
 PATH='I71',
 DRAWING='@T6G_MB_LIB.T6G(SCH_1):PAGE343',
 WATTAGE='1/16W',
 TOLERANCE='1%',
 MATERIAL='CHIP',
 PHYS_PAGE='140',
 XY='(2300,5925)',
 ROT='0',
 VER='2',
 PACK_TYPE='0402LF',
 LOCATION='PR3823',
 CDS_LIB='pure_quanta',
 CDS_PART_NAME='Q_RES_0402LF-845,1%,1/16W,CHIP,CS18452FB01',
 ROOM='NIC_P12V_MAM_TIC_BOM1',
 PART_NUMBER='CS18452FB01',
 VALUE='845',
 PRIM_FILE='./archive_libs/logical/q_res/chips/chips.prt';

PART_NAME
 PR3824 'Q_RES_0402LF-4.53K,1%,1/16W,CHIP,CS24532FB03':
 ROOM='NIC_P3V3_BOM1';

SECTION_NUMBER 1
 '@T6G_MB_LIB.T6G(SCH_1):PAGE343_I94@PURE_QUANTA.Q_RES(CHIPS)':
 C_PATH='@t6g_mb_lib.t6g(sch_1):page343_i94@pure_quanta.q_res(chips)',
 P_PATH='@t6g_mb_lib.t6g(sch_1):page140_i94@pure_quanta.q_res(chips)',
 PATH='I94',
 DRAWING='@T6G_MB_LIB.T6G(SCH_1):PAGE343',
 WATTAGE='1/16W',
 TOLERANCE='1%',
 MATERIAL='CHIP',
 PHYS_PAGE='140',
 XY='(2425,8275)',
 ROT='0',
 VER='2',
 PACK_TYPE='0402LF',
 LOCATION='PR3824',
 CDS_LIB='pure_quanta',
 CDS_PART_NAME='Q_RES_0402LF-4.53K,1%,1/16W,CHIP,CS24532FB03',
 ROOM='NIC_P3V3_BOM1',
 PART_NUMBER='CS24532FB03',
 VALUE='4.53K',
 PRIM_FILE='./archive_libs/logical/q_res/chips/chips.prt';

PART_NAME
 PR3828 'Q_RES_0402LF-15K,1%,1/16W,CHIP,CS31502FB05':
 ROOM='NIC_P12V_MAM_TIC_BOM1';

SECTION_NUMBER 1
 '@T6G_MB_LIB.T6G(SCH_1):PAGE343_I31@PURE_QUANTA.Q_RES(CHIPS)':
 C_PATH='@t6g_mb_lib.t6g(sch_1):page343_i31@pure_quanta.q_res(chips)',
 P_PATH='@t6g_mb_lib.t6g(sch_1):page140_i31@pure_quanta.q_res(chips)',
 PATH='I31',
 DRAWING='@T6G_MB_LIB.T6G(SCH_1):PAGE343',
 WATTAGE='1/16W',
 TOLERANCE='1%',
 MATERIAL='CHIP',
 PHYS_PAGE='140',
 XY='(-150,5775)',
 ROT='0',
 VER='2',
 PACK_TYPE='0402LF',
 LOCATION='PR3828',
 CDS_LIB='pure_quanta',
 CDS_PART_NAME='Q_RES_0402LF-15K,1%,1/16W,CHIP,CS31502FB05',
 ROOM='NIC_P12V_MAM_TIC_BOM1',
 PART_NUMBER='CS31502FB05',
 VALUE='15K',
 PRIM_FILE='./archive_libs/logical/q_res/chips/chips.prt';

PART_NAME
 PR3829 'Q_RES_0402LF-7.15K,1%,1/16W,CHIP,CS27152FB03':
 ROOM='NIC_P3V3_BOM1';

SECTION_NUMBER 1
 '@T6G_MB_LIB.T6G(SCH_1):PAGE343_I53@PURE_QUANTA.Q_RES(CHIPS)':
 C_PATH='@t6g_mb_lib.t6g(sch_1):page343_i53@pure_quanta.q_res(chips)',
 P_PATH='@t6g_mb_lib.t6g(sch_1):page140_i53@pure_quanta.q_res(chips)',
 PATH='I53',
 DRAWING='@T6G_MB_LIB.T6G(SCH_1):PAGE343',
 WATTAGE='1/16W',
 TOLERANCE='1%',
 MATERIAL='CHIP',
 PHYS_PAGE='140',
 XY='(-25,8375)',
 ROT='0',
 VER='2',
 PACK_TYPE='0402LF',
 LOCATION='PR3829',
 CDS_LIB='pure_quanta',
 CDS_PART_NAME='Q_RES_0402LF-7.15K,1%,1/16W,CHIP,CS27152FB03',
 ROOM='NIC_P3V3_BOM1',
 PART_NUMBER='CS27152FB03',
 VALUE='7.15K',
 PRIM_FILE='./archive_libs/logical/q_res/chips/chips.prt';

PART_NAME
 PR3830 'Q_RES_0402LF-10,1%,1/16W,CHIP,CS01002FB07':
 ROOM='NIC_P12V_MAM_TIC_BOM1';

SECTION_NUMBER 1
 '@T6G_MB_LIB.T6G(SCH_1):PAGE343_I84@PURE_QUANTA.Q_RES(CHIPS)':
 C_PATH='@t6g_mb_lib.t6g(sch_1):page343_i84@pure_quanta.q_res(chips)',
 P_PATH='@t6g_mb_lib.t6g(sch_1):page140_i84@pure_quanta.q_res(chips)',
 PATH='I84',
 DRAWING='@T6G_MB_LIB.T6G(SCH_1):PAGE343',
 WATTAGE='1/16W',
 TOLERANCE='1%',
 MATERIAL='CHIP',
 PHYS_PAGE='140',
 XY='(175,7025)',
 ROT='0',
 VER='2',
 PACK_TYPE='0402LF',
 LOCATION='PR3830',
 CDS_LIB='pure_quanta',
 CDS_PART_NAME='Q_RES_0402LF-10,1%,1/16W,CHIP,CS01002FB07',
 ROOM='NIC_P12V_MAM_TIC_BOM1',
 PART_NUMBER='CS01002FB07',
 VALUE='10',
 PRIM_FILE='./archive_libs/logical/q_res/chips/chips.prt';

PART_NAME
 PR3835 'Q_RES_0402LF-14.3K,1%,1/16W,CHIP,CS31432FB02':
 ROOM='NIC_P12V_MPS_MAM_BOM2';

SECTION_NUMBER 1
 '@T6G_MB_LIB.T6G(SCH_1):PAGE339_I63@PURE_QUANTA.Q_RES(CHIPS)':
 C_PATH='@t6g_mb_lib.t6g(sch_1):page339_i63@pure_quanta.q_res(chips)',
 P_PATH='@t6g_mb_lib.t6g(sch_1):page135_i63@pure_quanta.q_res(chips)',
 PATH='I63',
 DRAWING='@T6G_MB_LIB.T6G(SCH_1):PAGE339',
 WATTAGE='1/16W',
 TOLERANCE='1%',
 MATERIAL='CHIP',
 PHYS_PAGE='135',
 XY='(-7600,9025)',
 ROT='0',
 VER='2',
 PACK_TYPE='0402LF',
 LOCATION='PR3835',
 CDS_LIB='pure_quanta',
 CDS_PART_NAME='Q_RES_0402LF-14.3K,1%,1/16W,CHIP,CS31432FB02',
 ROOM='NIC_P12V_MPS_MAM_BOM2',
 PART_NUMBER='CS31432FB02',
 VALUE='14.3K',
 PRIM_FILE='./archive_libs/logical/q_res/chips/chips.prt';

PART_NAME
 PR3837 'Q_RES_0402LF-17.4K,1%,1/16W,CHIP,CS31742FB04':
 ROOM='NIC_P12V_MPS_MAM_BOM2';

SECTION_NUMBER 1
 '@T6G_MB_LIB.T6G(SCH_1):PAGE339_I71@PURE_QUANTA.Q_RES(CHIPS)':
 C_PATH='@t6g_mb_lib.t6g(sch_1):page339_i71@pure_quanta.q_res(chips)',
 P_PATH='@t6g_mb_lib.t6g(sch_1):page135_i71@pure_quanta.q_res(chips)',
 PATH='I71',
 DRAWING='@T6G_MB_LIB.T6G(SCH_1):PAGE339',
 WATTAGE='1/16W',
 TOLERANCE='1%',
 MATERIAL='CHIP',
 PHYS_PAGE='135',
 XY='(-5775,8725)',
 ROT='0',
 VER='2',
 PACK_TYPE='0402LF',
 LOCATION='PR3837',
 CDS_LIB='pure_quanta',
 CDS_PART_NAME='Q_RES_0402LF-17.4K,1%,1/16W,CHIP,CS31742FB04',
 ROOM='NIC_P12V_MPS_MAM_BOM2',
 PART_NUMBER='CS31742FB04',
 VALUE='17.4K',
 PRIM_FILE='./archive_libs/logical/q_res/chips/chips.prt';

PART_NAME
 PR3838 'Q_RES_0402LF-100,1%,1/16W,EMPTY,CS11002FB07':
 ROOM='NIC_P12V_MPS_MAM_BOM2';

SECTION_NUMBER 1
 '@T6G_MB_LIB.T6G(SCH_1):PAGE339_I76@PURE_QUANTA.Q_RES(CHIPS)':
 C_PATH='@t6g_mb_lib.t6g(sch_1):page339_i76@pure_quanta.q_res(chips)',
 P_PATH='@t6g_mb_lib.t6g(sch_1):page135_i76@pure_quanta.q_res(chips)',
 PATH='I76',
 DRAWING='@T6G_MB_LIB.T6G(SCH_1):PAGE339',
 WATTAGE='1/16W',
 TOLERANCE='1%',
 MATERIAL='EMPTY',
 PHYS_PAGE='135',
 XY='(-5400,9575)',
 ROT='0',
 VER='2',
 PACK_TYPE='0402LF',
 LOCATION='PR3838',
 CDS_LIB='pure_quanta',
 CDS_PART_NAME='Q_RES_0402LF-100,1%,1/16W,EMPTY,CS11002FB07',
 ROOM='NIC_P12V_MPS_MAM_BOM2',
 PART_NUMBER='CS11002FB07',
 VALUE='100',
 PRIM_FILE='./archive_libs/logical/q_res/chips/chips.prt';

PART_NAME
 PR3839 'Q_RES_0402LF-10K,1%,1/16W,CHIP,CS31002FB08':
 ROOM='NIC_P12V_MPS_MAM_BOM2';

SECTION_NUMBER 1
 '@T6G_MB_LIB.T6G(SCH_1):PAGE339_I74@PURE_QUANTA.Q_RES(CHIPS)':
 C_PATH='@t6g_mb_lib.t6g(sch_1):page339_i74@pure_quanta.q_res(chips)',
 P_PATH='@t6g_mb_lib.t6g(sch_1):page135_i74@pure_quanta.q_res(chips)',
 PATH='I74',
 DRAWING='@T6G_MB_LIB.T6G(SCH_1):PAGE339',
 WATTAGE='1/16W',
 TOLERANCE='1%',
 MATERIAL='CHIP',
 PHYS_PAGE='135',
 XY='(-5400,9100)',
 ROT='0',
 VER='1',
 PACK_TYPE='0402LF',
 LOCATION='PR3839',
 CDS_LIB='pure_quanta',
 CDS_PART_NAME='Q_RES_0402LF-10K,1%,1/16W,CHIP,CS31002FB08',
 ROOM='NIC_P12V_MPS_MAM_BOM2',
 PART_NUMBER='CS31002FB08',
 VALUE='10K',
 PRIM_FILE='./archive_libs/logical/q_res/chips/chips.prt';

PART_NAME
 PR3840 'Q_RES_0402LF-71.5K,1%,1/16W,EMPTY,CS37152FB05':
 ROOM='NIC_P12V_MPS_MAM_BOM2';

SECTION_NUMBER 1
 '@T6G_MB_LIB.T6G(SCH_1):PAGE339_I81@PURE_QUANTA.Q_RES(CHIPS)':
 C_PATH='@t6g_mb_lib.t6g(sch_1):page339_i81@pure_quanta.q_res(chips)',
 P_PATH='@t6g_mb_lib.t6g(sch_1):page135_i81@pure_quanta.q_res(chips)',
 PATH='I81',
 DRAWING='@T6G_MB_LIB.T6G(SCH_1):PAGE339',
 WATTAGE='1/16W',
 TOLERANCE='1%',
 MATERIAL='EMPTY',
 PHYS_PAGE='135',
 XY='(-4800,9575)',
 ROT='0',
 VER='2',
 PACK_TYPE='0402LF',
 LOCATION='PR3840',
 CDS_LIB='pure_quanta',
 CDS_PART_NAME='Q_RES_0402LF-71.5K,1%,1/16W,EMPTY,CS37152FB05',
 ROOM='NIC_P12V_MPS_MAM_BOM2',
 PART_NUMBER='CS37152FB05',
 VALUE='71.5K',
 PRIM_FILE='./archive_libs/logical/q_res/chips/chips.prt';

PART_NAME
 PR3841 'Q_RES_0402LF-120K,1%,1/16W,CHIP,CS41202FB05':
 ROOM='NIC_P12V_MPS_MAM_BOM2';

SECTION_NUMBER 1
 '@T6G_MB_LIB.T6G(SCH_1):PAGE339_I82@PURE_QUANTA.Q_RES(CHIPS)':
 C_PATH='@t6g_mb_lib.t6g(sch_1):page339_i82@pure_quanta.q_res(chips)',
 P_PATH='@t6g_mb_lib.t6g(sch_1):page135_i82@pure_quanta.q_res(chips)',
 PATH='I82',
 DRAWING='@T6G_MB_LIB.T6G(SCH_1):PAGE339',
 WATTAGE='1/16W',
 TOLERANCE='1%',
 MATERIAL='CHIP',
 PHYS_PAGE='135',
 XY='(-4400,9500)',
 ROT='0',
 VER='2',
 PACK_TYPE='0402LF',
 LOCATION='PR3841',
 CDS_LIB='pure_quanta',
 CDS_PART_NAME='Q_RES_0402LF-120K,1%,1/16W,CHIP,CS41202FB05',
 ROOM='NIC_P12V_MPS_MAM_BOM2',
 PART_NUMBER='CS41202FB05',
 VALUE='120K',
 PRIM_FILE='./archive_libs/logical/q_res/chips/chips.prt';

PART_NAME
 PR3842 'Q_RES_0402LF-10K,1%,1/16W,CHIP,CS31002FB08':
 ROOM='NIC_P12V_MPS_MAM_BOM2';

SECTION_NUMBER 1
 '@T6G_MB_LIB.T6G(SCH_1):PAGE339_I80@PURE_QUANTA.Q_RES(CHIPS)':
 C_PATH='@t6g_mb_lib.t6g(sch_1):page339_i80@pure_quanta.q_res(chips)',
 P_PATH='@t6g_mb_lib.t6g(sch_1):page135_i80@pure_quanta.q_res(chips)',
 PATH='I80',
 DRAWING='@T6G_MB_LIB.T6G(SCH_1):PAGE339',
 WATTAGE='1/16W',
 TOLERANCE='1%',
 MATERIAL='CHIP',
 PHYS_PAGE='135',
 XY='(-4400,9075)',
 ROT='0',
 VER='2',
 PACK_TYPE='0402LF',
 LOCATION='PR3842',
 CDS_LIB='pure_quanta',
 CDS_PART_NAME='Q_RES_0402LF-10K,1%,1/16W,CHIP,CS31002FB08',
 ROOM='NIC_P12V_MPS_MAM_BOM2',
 PART_NUMBER='CS31002FB08',
 VALUE='10K',
 PRIM_FILE='./archive_libs/logical/q_res/chips/chips.prt';

PART_NAME
 PR3843 'Q_RES_0603LF-49.9,1%,1/10W,CHIP,CS04993F909':
 ROOM='NIC_P12V_MPS_MAM_BOM2';

SECTION_NUMBER 1
 '@T6G_MB_LIB.T6G(SCH_1):PAGE339_I88@PURE_QUANTA.Q_RES(CHIPS)':
 C_PATH='@t6g_mb_lib.t6g(sch_1):page339_i88@pure_quanta.q_res(chips)',
 P_PATH='@t6g_mb_lib.t6g(sch_1):page135_i88@pure_quanta.q_res(chips)',
 PATH='I88',
 DRAWING='@T6G_MB_LIB.T6G(SCH_1):PAGE339',
 WATTAGE='1/10W',
 TOLERANCE='1%',
 MATERIAL='CHIP',
 PHYS_PAGE='135',
 XY='(-3875,9500)',
 ROT='0',
 VER='2',
 PACK_TYPE='0603LF',
 LOCATION='PR3843',
 CDS_LIB='pure_quanta',
 CDS_PART_NAME='Q_RES_0603LF-49.9,1%,1/10W,CHIP,CS04993F909',
 ROOM='NIC_P12V_MPS_MAM_BOM2',
 PART_NUMBER='CS04993F909',
 VALUE='49.9',
 PRIM_FILE='./archive_libs/logical/q_res/chips/chips.prt';

PART_NAME
 PR3844 'Q_RES_0402LF-71.5K,1%,1/16W,CHIP,CS37152FB05':
 ROOM='NIC_P3V3_BOM2';

SECTION_NUMBER 1
 '@T6G_MB_LIB.T6G(SCH_1):PAGE339_I100@PURE_QUANTA.Q_RES(CHIPS)':
 C_PATH='@t6g_mb_lib.t6g(sch_1):page339_i100@pure_quanta.q_res(chips)',
 P_PATH='@t6g_mb_lib.t6g(sch_1):page135_i100@pure_quanta.q_res(chips)',
 PATH='I100',
 DRAWING='@T6G_MB_LIB.T6G(SCH_1):PAGE339',
 WATTAGE='1/16W',
 TOLERANCE='1%',
 MATERIAL='CHIP',
 PHYS_PAGE='135',
 XY='(-4025,12275)',
 ROT='0',
 VER='2',
 PACK_TYPE='0402LF',
 LOCATION='PR3844',
 CDS_LIB='pure_quanta',
 CDS_PART_NAME='Q_RES_0402LF-71.5K,1%,1/16W,CHIP,CS37152FB05',
 ROOM='NIC_P3V3_BOM2',
 PART_NUMBER='CS37152FB05',
 VALUE='71.5K',
 PRIM_FILE='./archive_libs/logical/q_res/chips/chips.prt';

PART_NAME
 PR3846 'Q_RES_0402LF-1.33K,1%,1/16W,CHIP,CS21332FB05':
 ROOM='NIC_P3V3_BOM2';

SECTION_NUMBER 1
 '@T6G_MB_LIB.T6G(SCH_1):PAGE339_I102@PURE_QUANTA.Q_RES(CHIPS)':
 C_PATH='@t6g_mb_lib.t6g(sch_1):page339_i102@pure_quanta.q_res(chips)',
 P_PATH='@t6g_mb_lib.t6g(sch_1):page135_i102@pure_quanta.q_res(chips)',
 PATH='I102',
 DRAWING='@T6G_MB_LIB.T6G(SCH_1):PAGE339',
 WATTAGE='1/16W',
 TOLERANCE='1%',
 MATERIAL='CHIP',
 PHYS_PAGE='135',
 XY='(-3600,12225)',
 ROT='1',
 VER='1',
 PACK_TYPE='0402LF',
 LOCATION='PR3846',
 CDS_LIB='pure_quanta',
 CDS_PART_NAME='Q_RES_0402LF-1.33K,1%,1/16W,CHIP,CS21332FB05',
 ROOM='NIC_P3V3_BOM2',
 PART_NUMBER='CS21332FB05',
 VALUE='1.33K',
 PRIM_FILE='./archive_libs/logical/q_res/chips/chips.prt';

PART_NAME
 PR3847 'Q_RES_0402LF-14.3K,1%,1/16W,CHIP,CS31432FB02':
 ROOM='NIC_P12V_MPS_MAM_BOM2';

SECTION_NUMBER 1
 '@T6G_MB_LIB.T6G(SCH_1):PAGE344_I4@PURE_QUANTA.Q_RES(CHIPS)':
 C_PATH='@t6g_mb_lib.t6g(sch_1):page344_i4@pure_quanta.q_res(chips)',
 P_PATH='@t6g_mb_lib.t6g(sch_1):page141_i4@pure_quanta.q_res(chips)',
 PATH='I4',
 DRAWING='@T6G_MB_LIB.T6G(SCH_1):PAGE344',
 WATTAGE='1/16W',
 TOLERANCE='1%',
 MATERIAL='CHIP',
 PHYS_PAGE='141',
 XY='(-3175,2450)',
 ROT='0',
 VER='2',
 PACK_TYPE='0402LF',
 LOCATION='PR3847',
 CDS_LIB='pure_quanta',
 CDS_PART_NAME='Q_RES_0402LF-14.3K,1%,1/16W,CHIP,CS31432FB02',
 ROOM='NIC_P12V_MPS_MAM_BOM2',
 PART_NUMBER='CS31432FB02',
 VALUE='14.3K',
 PRIM_FILE='./archive_libs/logical/q_res/chips/chips.prt';

PART_NAME
 PR3849 'Q_RES_0402LF-17.4K,1%,1/16W,CHIP,CS31742FB04':
 ROOM='NIC_P12V_MPS_MAM_BOM2';

SECTION_NUMBER 1
 '@T6G_MB_LIB.T6G(SCH_1):PAGE344_I15@PURE_QUANTA.Q_RES(CHIPS)':
 C_PATH='@t6g_mb_lib.t6g(sch_1):page344_i15@pure_quanta.q_res(chips)',
 P_PATH='@t6g_mb_lib.t6g(sch_1):page141_i15@pure_quanta.q_res(chips)',
 PATH='I15',
 DRAWING='@T6G_MB_LIB.T6G(SCH_1):PAGE344',
 WATTAGE='1/16W',
 TOLERANCE='1%',
 MATERIAL='CHIP',
 PHYS_PAGE='141',
 XY='(-1425,2200)',
 ROT='0',
 VER='2',
 PACK_TYPE='0402LF',
 LOCATION='PR3849',
 CDS_LIB='pure_quanta',
 CDS_PART_NAME='Q_RES_0402LF-17.4K,1%,1/16W,CHIP,CS31742FB04',
 ROOM='NIC_P12V_MPS_MAM_BOM2',
 PART_NUMBER='CS31742FB04',
 VALUE='17.4K',
 PRIM_FILE='./archive_libs/logical/q_res/chips/chips.prt';

PART_NAME
 PR3850 'Q_RES_0402LF-100,1%,1/16W,EMPTY,CS11002FB07':
 ROOM='NIC_P12V_MPS_MAM_BOM2';

SECTION_NUMBER 1
 '@T6G_MB_LIB.T6G(SCH_1):PAGE344_I30@PURE_QUANTA.Q_RES(CHIPS)':
 C_PATH='@t6g_mb_lib.t6g(sch_1):page344_i30@pure_quanta.q_res(chips)',
 P_PATH='@t6g_mb_lib.t6g(sch_1):page141_i30@pure_quanta.q_res(chips)',
 PATH='I30',
 DRAWING='@T6G_MB_LIB.T6G(SCH_1):PAGE344',
 WATTAGE='1/16W',
 TOLERANCE='1%',
 MATERIAL='EMPTY',
 PHYS_PAGE='141',
 XY='(-925,3025)',
 ROT='0',
 VER='2',
 PACK_TYPE='0402LF',
 LOCATION='PR3850',
 CDS_LIB='pure_quanta',
 CDS_PART_NAME='Q_RES_0402LF-100,1%,1/16W,EMPTY,CS11002FB07',
 ROOM='NIC_P12V_MPS_MAM_BOM2',
 PART_NUMBER='CS11002FB07',
 VALUE='100',
 PRIM_FILE='./archive_libs/logical/q_res/chips/chips.prt';

PART_NAME
 PR3851 'Q_RES_0402LF-10K,1%,1/16W,CHIP,CS31002FB08':
 ROOM='NIC_P12V_MPS_MAM_BOM2';

SECTION_NUMBER 1
 '@T6G_MB_LIB.T6G(SCH_1):PAGE344_I18@PURE_QUANTA.Q_RES(CHIPS)':
 C_PATH='@t6g_mb_lib.t6g(sch_1):page344_i18@pure_quanta.q_res(chips)',
 P_PATH='@t6g_mb_lib.t6g(sch_1):page141_i18@pure_quanta.q_res(chips)',
 PATH='I18',
 DRAWING='@T6G_MB_LIB.T6G(SCH_1):PAGE344',
 WATTAGE='1/16W',
 TOLERANCE='1%',
 MATERIAL='CHIP',
 PHYS_PAGE='141',
 XY='(-850,2550)',
 ROT='0',
 VER='1',
 PACK_TYPE='0402LF',
 LOCATION='PR3851',
 CDS_LIB='pure_quanta',
 CDS_PART_NAME='Q_RES_0402LF-10K,1%,1/16W,CHIP,CS31002FB08',
 ROOM='NIC_P12V_MPS_MAM_BOM2',
 PART_NUMBER='CS31002FB08',
 VALUE='10K',
 PRIM_FILE='./archive_libs/logical/q_res/chips/chips.prt';

PART_NAME
 PR3852 'Q_RES_0402LF-71.5K,1%,1/16W,EMPTY,CS37152FB05':
 ROOM='NIC_P12V_MPS_MAM_BOM2';

SECTION_NUMBER 1
 '@T6G_MB_LIB.T6G(SCH_1):PAGE344_I31@PURE_QUANTA.Q_RES(CHIPS)':
 C_PATH='@t6g_mb_lib.t6g(sch_1):page344_i31@pure_quanta.q_res(chips)',
 P_PATH='@t6g_mb_lib.t6g(sch_1):page141_i31@pure_quanta.q_res(chips)',
 PATH='I31',
 DRAWING='@T6G_MB_LIB.T6G(SCH_1):PAGE344',
 WATTAGE='1/16W',
 TOLERANCE='1%',
 MATERIAL='EMPTY',
 PHYS_PAGE='141',
 XY='(-375,3025)',
 ROT='0',
 VER='2',
 PACK_TYPE='0402LF',
 LOCATION='PR3852',
 CDS_LIB='pure_quanta',
 CDS_PART_NAME='Q_RES_0402LF-71.5K,1%,1/16W,EMPTY,CS37152FB05',
 ROOM='NIC_P12V_MPS_MAM_BOM2',
 PART_NUMBER='CS37152FB05',
 VALUE='71.5K',
 PRIM_FILE='./archive_libs/logical/q_res/chips/chips.prt';

PART_NAME
 PR3853 'Q_RES_0402LF-120K,1%,1/16W,CHIP,CS41202FB05':
 ROOM='NIC_P12V_MPS_MAM_BOM2';

SECTION_NUMBER 1
 '@T6G_MB_LIB.T6G(SCH_1):PAGE344_I36@PURE_QUANTA.Q_RES(CHIPS)':
 C_PATH='@t6g_mb_lib.t6g(sch_1):page344_i36@pure_quanta.q_res(chips)',
 P_PATH='@t6g_mb_lib.t6g(sch_1):page141_i36@pure_quanta.q_res(chips)',
 PATH='I36',
 DRAWING='@T6G_MB_LIB.T6G(SCH_1):PAGE344',
 WATTAGE='1/16W',
 TOLERANCE='1%',
 MATERIAL='CHIP',
 PHYS_PAGE='141',
 XY='(20,2958)',
 ROT='0',
 VER='2',
 PACK_TYPE='0402LF',
 LOCATION='PR3853',
 CDS_LIB='pure_quanta',
 CDS_PART_NAME='Q_RES_0402LF-120K,1%,1/16W,CHIP,CS41202FB05',
 ROOM='NIC_P12V_MPS_MAM_BOM2',
 PART_NUMBER='CS41202FB05',
 VALUE='120K',
 PRIM_FILE='./archive_libs/logical/q_res/chips/chips.prt';

PART_NAME
 PR3854 'Q_RES_0402LF-10K,1%,1/16W,CHIP,CS31002FB08':
 ROOM='NIC_P12V_MPS_MAM_BOM2';

SECTION_NUMBER 1
 '@T6G_MB_LIB.T6G(SCH_1):PAGE344_I20@PURE_QUANTA.Q_RES(CHIPS)':
 C_PATH='@t6g_mb_lib.t6g(sch_1):page344_i20@pure_quanta.q_res(chips)',
 P_PATH='@t6g_mb_lib.t6g(sch_1):page141_i20@pure_quanta.q_res(chips)',
 PATH='I20',
 DRAWING='@T6G_MB_LIB.T6G(SCH_1):PAGE344',
 WATTAGE='1/16W',
 TOLERANCE='1%',
 MATERIAL='CHIP',
 PHYS_PAGE='141',
 XY='(20,2533)',
 ROT='0',
 VER='2',
 PACK_TYPE='0402LF',
 LOCATION='PR3854',
 CDS_LIB='pure_quanta',
 CDS_PART_NAME='Q_RES_0402LF-10K,1%,1/16W,CHIP,CS31002FB08',
 ROOM='NIC_P12V_MPS_MAM_BOM2',
 PART_NUMBER='CS31002FB08',
 VALUE='10K',
 PRIM_FILE='./archive_libs/logical/q_res/chips/chips.prt';

PART_NAME
 PR3855 'Q_RES_0402LF-71.5K,1%,1/16W,CHIP,CS37152FB05':
 ROOM='NIC_P3V3_BOM2';

SECTION_NUMBER 1
 '@T6G_MB_LIB.T6G(SCH_1):PAGE344_I43@PURE_QUANTA.Q_RES(CHIPS)':
 C_PATH='@t6g_mb_lib.t6g(sch_1):page344_i43@pure_quanta.q_res(chips)',
 P_PATH='@t6g_mb_lib.t6g(sch_1):page141_i43@pure_quanta.q_res(chips)',
 PATH='I43',
 DRAWING='@T6G_MB_LIB.T6G(SCH_1):PAGE344',
 WATTAGE='1/16W',
 TOLERANCE='1%',
 MATERIAL='CHIP',
 PHYS_PAGE='141',
 XY='(150,6175)',
 ROT='0',
 VER='2',
 PACK_TYPE='0402LF',
 LOCATION='PR3855',
 CDS_LIB='pure_quanta',
 CDS_PART_NAME='Q_RES_0402LF-71.5K,1%,1/16W,CHIP,CS37152FB05',
 ROOM='NIC_P3V3_BOM2',
 PART_NUMBER='CS37152FB05',
 VALUE='71.5K',
 PRIM_FILE='./archive_libs/logical/q_res/chips/chips.prt';

PART_NAME
 PR3856 'Q_RES_0402LF-1.33K,1%,1/16W,CHIP,CS21332FB05':
 ROOM='NIC_P3V3_BOM2';

SECTION_NUMBER 1
 '@T6G_MB_LIB.T6G(SCH_1):PAGE344_I46@PURE_QUANTA.Q_RES(CHIPS)':
 C_PATH='@t6g_mb_lib.t6g(sch_1):page344_i46@pure_quanta.q_res(chips)',
 P_PATH='@t6g_mb_lib.t6g(sch_1):page141_i46@pure_quanta.q_res(chips)',
 PATH='I46',
 DRAWING='@T6G_MB_LIB.T6G(SCH_1):PAGE344',
 WATTAGE='1/16W',
 TOLERANCE='1%',
 MATERIAL='CHIP',
 PHYS_PAGE='141',
 XY='(495,6158)',
 ROT='1',
 VER='1',
 PACK_TYPE='0402LF',
 LOCATION='PR3856',
 CDS_LIB='pure_quanta',
 CDS_PART_NAME='Q_RES_0402LF-1.33K,1%,1/16W,CHIP,CS21332FB05',
 ROOM='NIC_P3V3_BOM2',
 PART_NUMBER='CS21332FB05',
 VALUE='1.33K',
 PRIM_FILE='./archive_libs/logical/q_res/chips/chips.prt';

PART_NAME
 PR3857 'Q_RES_0603LF-49.9,1%,1/10W,CHIP,CS04993F909':
 ROOM='NIC_P12V_MPS_MAM_BOM2';

SECTION_NUMBER 1
 '@T6G_MB_LIB.T6G(SCH_1):PAGE344_I37@PURE_QUANTA.Q_RES(CHIPS)':
 C_PATH='@t6g_mb_lib.t6g(sch_1):page344_i37@pure_quanta.q_res(chips)',
 P_PATH='@t6g_mb_lib.t6g(sch_1):page141_i37@pure_quanta.q_res(chips)',
 PATH='I37',
 DRAWING='@T6G_MB_LIB.T6G(SCH_1):PAGE344',
 WATTAGE='1/10W',
 TOLERANCE='1%',
 MATERIAL='CHIP',
 PHYS_PAGE='141',
 XY='(550,2950)',
 ROT='0',
 VER='2',
 PACK_TYPE='0603LF',
 LOCATION='PR3857',
 CDS_LIB='pure_quanta',
 CDS_PART_NAME='Q_RES_0603LF-49.9,1%,1/10W,CHIP,CS04993F909',
 ROOM='NIC_P12V_MPS_MAM_BOM2',
 PART_NUMBER='CS04993F909',
 VALUE='49.9',
 PRIM_FILE='./archive_libs/logical/q_res/chips/chips.prt';

PART_NAME
 PR3910 'Q_RES_0402LF-0,5%,1/16W,CHIP,CS00002JB13':
 ROOM='HSC BOM1';

SECTION_NUMBER 1
 '@T6G_MB_LIB.T6G(SCH_1):PAGE301_I21@PURE_QUANTA.Q_RES(CHIPS)':
 C_PATH='@t6g_mb_lib.t6g(sch_1):page301_i21@pure_quanta.q_res(chips)',
 P_PATH='@t6g_mb_lib.t6g(sch_1):page263_i21@pure_quanta.q_res(chips)',
 PATH='I21',
 DRAWING='@T6G_MB_LIB.T6G(SCH_1):PAGE301',
 WATTAGE='1/16W',
 TOLERANCE='5%',
 MATERIAL='CHIP',
 PHYS_PAGE='263',
 XY='(-3450,1850)',
 ROT='1',
 VER='1',
 PACK_TYPE='0402LF',
 LOCATION='PR3910',
 CDS_LIB='pure_quanta',
 CDS_PART_NAME='Q_RES_0402LF-0,5%,1/16W,CHIP,CS00002JB13',
 ROOM='HSC BOM1',
 PART_NUMBER='CS00002JB13',
 VALUE='0',
 PRIM_FILE='./archive_libs/logical/q_res/chips/chips.prt';

PART_NAME
 PR3911 'Q_RES_0402LF-0,5%,1/16W,CHIP,CS00002JB13':
 ROOM='HSC BOM1';

SECTION_NUMBER 1
 '@T6G_MB_LIB.T6G(SCH_1):PAGE301_I5@PURE_QUANTA.Q_RES(CHIPS)':
 C_PATH='@t6g_mb_lib.t6g(sch_1):page301_i5@pure_quanta.q_res(chips)',
 P_PATH='@t6g_mb_lib.t6g(sch_1):page263_i5@pure_quanta.q_res(chips)',
 PATH='I5',
 DRAWING='@T6G_MB_LIB.T6G(SCH_1):PAGE301',
 WATTAGE='1/16W',
 TOLERANCE='5%',
 MATERIAL='CHIP',
 PHYS_PAGE='263',
 XY='(-3475,-950)',
 ROT='1',
 VER='1',
 PACK_TYPE='0402LF',
 LOCATION='PR3911',
 CDS_LIB='pure_quanta',
 CDS_PART_NAME='Q_RES_0402LF-0,5%,1/16W,CHIP,CS00002JB13',
 ROOM='HSC BOM1',
 PART_NUMBER='CS00002JB13',
 VALUE='0',
 PRIM_FILE='./archive_libs/logical/q_res/chips/chips.prt';

PART_NAME
 PR3912 'Q_RES_0402LF-120K,1%,1/16W,CHIP,CS41202FB05':
 ROOM='HSC BOM1';

SECTION_NUMBER 1
 '@T6G_MB_LIB.T6G(SCH_1):PAGE301_I11@PURE_QUANTA.Q_RES(CHIPS)':
 C_PATH='@t6g_mb_lib.t6g(sch_1):page301_i11@pure_quanta.q_res(chips)',
 P_PATH='@t6g_mb_lib.t6g(sch_1):page263_i11@pure_quanta.q_res(chips)',
 PATH='I11',
 DRAWING='@T6G_MB_LIB.T6G(SCH_1):PAGE301',
 WATTAGE='1/16W',
 TOLERANCE='1%',
 MATERIAL='CHIP',
 PHYS_PAGE='263',
 XY='(-1925,-1250)',
 ROT='0',
 VER='1',
 PACK_TYPE='0402LF',
 LOCATION='PR3912',
 CDS_LIB='pure_quanta',
 CDS_PART_NAME='Q_RES_0402LF-120K,1%,1/16W,CHIP,CS41202FB05',
 ROOM='HSC BOM1',
 PART_NUMBER='CS41202FB05',
 VALUE='120K',
 PRIM_FILE='./archive_libs/logical/q_res/chips/chips.prt';

PART_NAME
 PR3914 'Q_RES_0402LF-2K,0.1%,1/16W,CHIP,CS22002BB07':
 ROOM='HSC BOM1';

SECTION_NUMBER 1
 '@T6G_MB_LIB.T6G(SCH_1):PAGE301_I31@PURE_QUANTA.Q_RES(CHIPS)':
 C_PATH='@t6g_mb_lib.t6g(sch_1):page301_i31@pure_quanta.q_res(chips)',
 P_PATH='@t6g_mb_lib.t6g(sch_1):page263_i31@pure_quanta.q_res(chips)',
 PATH='I31',
 DRAWING='@T6G_MB_LIB.T6G(SCH_1):PAGE301',
 WATTAGE='1/16W',
 TOLERANCE='0.1%',
 MATERIAL='CHIP',
 PHYS_PAGE='263',
 XY='(-1500,725)',
 ROT='0',
 VER='2',
 PACK_TYPE='0402LF',
 LOCATION='PR3914',
 CDS_LIB='pure_quanta',
 CDS_PART_NAME='Q_RES_0402LF-2K,0.1%,1/16W,CHIP,CS22002BB07',
 ROOM='HSC BOM1',
 PART_NUMBER='CS22002BB07',
 VALUE='2K',
 PRIM_FILE='./archive_libs/logical/q_res/chips/chips.prt';

PART_NAME
 PR3915 'Q_RES_0402LF-2K,0.1%,1/16W,CHIP,CS22002BB07':
 ROOM='HSC BOM1';

SECTION_NUMBER 1
 '@T6G_MB_LIB.T6G(SCH_1):PAGE301_I13@PURE_QUANTA.Q_RES(CHIPS)':
 C_PATH='@t6g_mb_lib.t6g(sch_1):page301_i13@pure_quanta.q_res(chips)',
 P_PATH='@t6g_mb_lib.t6g(sch_1):page263_i13@pure_quanta.q_res(chips)',
 PATH='I13',
 DRAWING='@T6G_MB_LIB.T6G(SCH_1):PAGE301',
 WATTAGE='1/16W',
 TOLERANCE='0.1%',
 MATERIAL='CHIP',
 PHYS_PAGE='263',
 XY='(-1500,-2075)',
 ROT='0',
 VER='2',
 PACK_TYPE='0402LF',
 LOCATION='PR3915',
 CDS_LIB='pure_quanta',
 CDS_PART_NAME='Q_RES_0402LF-2K,0.1%,1/16W,CHIP,CS22002BB07',
 ROOM='HSC BOM1',
 PART_NUMBER='CS22002BB07',
 VALUE='2K',
 PRIM_FILE='./archive_libs/logical/q_res/chips/chips.prt';

PART_NAME
 PR3916 'Q_RES_0402LF-0,5%,1/16W,CHIP,CS00002JB13':
 ROOM='HSC BOM1';

SECTION_NUMBER 1
 '@T6G_MB_LIB.T6G(SCH_1):PAGE301_I33@PURE_QUANTA.Q_RES(CHIPS)':
 C_PATH='@t6g_mb_lib.t6g(sch_1):page301_i33@pure_quanta.q_res(chips)',
 P_PATH='@t6g_mb_lib.t6g(sch_1):page263_i33@pure_quanta.q_res(chips)',
 PATH='I33',
 DRAWING='@T6G_MB_LIB.T6G(SCH_1):PAGE301',
 WATTAGE='1/16W',
 TOLERANCE='5%',
 MATERIAL='CHIP',
 PHYS_PAGE='263',
 XY='(-1350,1375)',
 ROT='0',
 VER='1',
 PACK_TYPE='0402LF',
 LOCATION='PR3916',
 CDS_LIB='pure_quanta',
 CDS_PART_NAME='Q_RES_0402LF-0,5%,1/16W,CHIP,CS00002JB13',
 ROOM='HSC BOM1',
 PART_NUMBER='CS00002JB13',
 VALUE='0',
 PRIM_FILE='./archive_libs/logical/q_res/chips/chips.prt';

PART_NAME
 PR3917 'Q_RES_0402LF-0,5%,1/16W,CHIP,CS00002JB13':
 ROOM='HSC BOM1';

SECTION_NUMBER 1
 '@T6G_MB_LIB.T6G(SCH_1):PAGE301_I17@PURE_QUANTA.Q_RES(CHIPS)':
 C_PATH='@t6g_mb_lib.t6g(sch_1):page301_i17@pure_quanta.q_res(chips)',
 P_PATH='@t6g_mb_lib.t6g(sch_1):page263_i17@pure_quanta.q_res(chips)',
 PATH='I17',
 DRAWING='@T6G_MB_LIB.T6G(SCH_1):PAGE301',
 WATTAGE='1/16W',
 TOLERANCE='5%',
 MATERIAL='CHIP',
 PHYS_PAGE='263',
 XY='(-1325,-1425)',
 ROT='0',
 VER='1',
 PACK_TYPE='0402LF',
 LOCATION='PR3917',
 CDS_LIB='pure_quanta',
 CDS_PART_NAME='Q_RES_0402LF-0,5%,1/16W,CHIP,CS00002JB13',
 ROOM='HSC BOM1',
 PART_NUMBER='CS00002JB13',
 VALUE='0',
 PRIM_FILE='./archive_libs/logical/q_res/chips/chips.prt';

PART_NAME
 PR3918 'Q_RES_0402LF-2K,0.1%,1/16W,CHIP,CS22002BB07':
 ROOM='HSC BOM1';

SECTION_NUMBER 1
 '@T6G_MB_LIB.T6G(SCH_1):PAGE301_I34@PURE_QUANTA.Q_RES(CHIPS)':
 C_PATH='@t6g_mb_lib.t6g(sch_1):page301_i34@pure_quanta.q_res(chips)',
 P_PATH='@t6g_mb_lib.t6g(sch_1):page263_i34@pure_quanta.q_res(chips)',
 PATH='I34',
 DRAWING='@T6G_MB_LIB.T6G(SCH_1):PAGE301',
 WATTAGE='1/16W',
 TOLERANCE='0.1%',
 MATERIAL='CHIP',
 PHYS_PAGE='263',
 XY='(-975,725)',
 ROT='0',
 VER='2',
 PACK_TYPE='0402LF',
 LOCATION='PR3918',
 CDS_LIB='pure_quanta',
 CDS_PART_NAME='Q_RES_0402LF-2K,0.1%,1/16W,CHIP,CS22002BB07',
 ROOM='HSC BOM1',
 PART_NUMBER='CS22002BB07',
 VALUE='2K',
 PRIM_FILE='./archive_libs/logical/q_res/chips/chips.prt';

PART_NAME
 PR3919 'Q_RES_0402LF-0,5%,1/16W,CHIP,CS00002JB13':
 ROOM='HSC BOM1';

SECTION_NUMBER 1
 '@T6G_MB_LIB.T6G(SCH_1):PAGE301_I50@PURE_QUANTA.Q_RES(CHIPS)':
 C_PATH='@t6g_mb_lib.t6g(sch_1):page301_i50@pure_quanta.q_res(chips)',
 P_PATH='@t6g_mb_lib.t6g(sch_1):page263_i50@pure_quanta.q_res(chips)',
 PATH='I50',
 DRAWING='@T6G_MB_LIB.T6G(SCH_1):PAGE301',
 WATTAGE='1/16W',
 TOLERANCE='5%',
 MATERIAL='CHIP',
 PHYS_PAGE='263',
 XY='(1475,1475)',
 ROT='0',
 VER='1',
 PACK_TYPE='0402LF',
 LOCATION='PR3919',
 CDS_LIB='pure_quanta',
 CDS_PART_NAME='Q_RES_0402LF-0,5%,1/16W,CHIP,CS00002JB13',
 ROOM='HSC BOM1',
 PART_NUMBER='CS00002JB13',
 VALUE='0',
 PRIM_FILE='./archive_libs/logical/q_res/chips/chips.prt';

PART_NAME
 PR3920 'Q_RES_0402LF-0,5%,1/16W,CHIP,CS00002JB13':
 ROOM='HSC BOM1';

SECTION_NUMBER 1
 '@T6G_MB_LIB.T6G(SCH_1):PAGE301_I49@PURE_QUANTA.Q_RES(CHIPS)':
 C_PATH='@t6g_mb_lib.t6g(sch_1):page301_i49@pure_quanta.q_res(chips)',
 P_PATH='@t6g_mb_lib.t6g(sch_1):page263_i49@pure_quanta.q_res(chips)',
 PATH='I49',
 DRAWING='@T6G_MB_LIB.T6G(SCH_1):PAGE301',
 WATTAGE='1/16W',
 TOLERANCE='5%',
 MATERIAL='CHIP',
 PHYS_PAGE='263',
 XY='(1475,1300)',
 ROT='0',
 VER='1',
 PACK_TYPE='0402LF',
 LOCATION='PR3920',
 CDS_LIB='pure_quanta',
 CDS_PART_NAME='Q_RES_0402LF-0,5%,1/16W,CHIP,CS00002JB13',
 ROOM='HSC BOM1',
 PART_NUMBER='CS00002JB13',
 VALUE='0',
 PRIM_FILE='./archive_libs/logical/q_res/chips/chips.prt';

PART_NAME
 PR3921 'Q_RES_0402LF-0,5%,1/16W,CHIP,CS00002JB13':
 ROOM='HSC BOM1';

SECTION_NUMBER 1
 '@T6G_MB_LIB.T6G(SCH_1):PAGE301_I40@PURE_QUANTA.Q_RES(CHIPS)':
 C_PATH='@t6g_mb_lib.t6g(sch_1):page301_i40@pure_quanta.q_res(chips)',
 P_PATH='@t6g_mb_lib.t6g(sch_1):page263_i40@pure_quanta.q_res(chips)',
 PATH='I40',
 DRAWING='@T6G_MB_LIB.T6G(SCH_1):PAGE301',
 WATTAGE='1/16W',
 TOLERANCE='5%',
 MATERIAL='CHIP',
 PHYS_PAGE='263',
 XY='(1475,-1325)',
 ROT='0',
 VER='1',
 PACK_TYPE='0402LF',
 LOCATION='PR3921',
 CDS_LIB='pure_quanta',
 CDS_PART_NAME='Q_RES_0402LF-0,5%,1/16W,CHIP,CS00002JB13',
 ROOM='HSC BOM1',
 PART_NUMBER='CS00002JB13',
 VALUE='0',
 PRIM_FILE='./archive_libs/logical/q_res/chips/chips.prt';

PART_NAME
 PR3922 'Q_RES_0402LF-0,5%,1/16W,CHIP,CS00002JB13':
 ROOM='HSC BOM1';

SECTION_NUMBER 1
 '@T6G_MB_LIB.T6G(SCH_1):PAGE301_I39@PURE_QUANTA.Q_RES(CHIPS)':
 C_PATH='@t6g_mb_lib.t6g(sch_1):page301_i39@pure_quanta.q_res(chips)',
 P_PATH='@t6g_mb_lib.t6g(sch_1):page263_i39@pure_quanta.q_res(chips)',
 PATH='I39',
 DRAWING='@T6G_MB_LIB.T6G(SCH_1):PAGE301',
 WATTAGE='1/16W',
 TOLERANCE='5%',
 MATERIAL='CHIP',
 PHYS_PAGE='263',
 XY='(1475,-1500)',
 ROT='0',
 VER='1',
 PACK_TYPE='0402LF',
 LOCATION='PR3922',
 CDS_LIB='pure_quanta',
 CDS_PART_NAME='Q_RES_0402LF-0,5%,1/16W,CHIP,CS00002JB13',
 ROOM='HSC BOM1',
 PART_NUMBER='CS00002JB13',
 VALUE='0',
 PRIM_FILE='./archive_libs/logical/q_res/chips/chips.prt';

PART_NAME
 PR3926 'Q_RES_0402LF-75K,0.1%,1/16W,CHIP,CS37502BB01':
 ROOM='HSC BOM1';

SECTION_NUMBER 1
 '@T6G_MB_LIB.T6G(SCH_1):PAGE267_I48@PURE_QUANTA.Q_RES(CHIPS)':
 C_PATH='@t6g_mb_lib.t6g(sch_1):page267_i48@pure_quanta.q_res(chips)',
 P_PATH='@t6g_mb_lib.t6g(sch_1):page262_i48@pure_quanta.q_res(chips)',
 PATH='I48',
 DRAWING='@T6G_MB_LIB.T6G(SCH_1):PAGE267',
 WATTAGE='1/16W',
 TOLERANCE='0.1%',
 MATERIAL='CHIP',
 PHYS_PAGE='262',
 XY='(-13700,4350)',
 ROT='0',
 VER='2',
 PACK_TYPE='0402LF',
 LOCATION='PR3926',
 CDS_LIB='pure_quanta',
 CDS_PART_NAME='Q_RES_0402LF-75K,0.1%,1/16W,CHIP,CS37502BB01',
 ROOM='HSC BOM1',
 PART_NUMBER='CS37502BB01',
 VALUE='75K',
 PRIM_FILE='./archive_libs/logical/q_res/chips/chips.prt';

PART_NAME
 PR3927 'Q_RES_0402LF-4.99K,0.1%,1/16W,CHIP,CS24992BB04':
 ROOM='HSC BOM1';

SECTION_NUMBER 1
 '@T6G_MB_LIB.T6G(SCH_1):PAGE267_I47@PURE_QUANTA.Q_RES(CHIPS)':
 C_PATH='@t6g_mb_lib.t6g(sch_1):page267_i47@pure_quanta.q_res(chips)',
 P_PATH='@t6g_mb_lib.t6g(sch_1):page262_i47@pure_quanta.q_res(chips)',
 PATH='I47',
 DRAWING='@T6G_MB_LIB.T6G(SCH_1):PAGE267',
 WATTAGE='1/16W',
 TOLERANCE='0.1%',
 MATERIAL='CHIP',
 PHYS_PAGE='262',
 XY='(-13700,3900)',
 ROT='0',
 VER='2',
 PACK_TYPE='0402LF',
 LOCATION='PR3927',
 CDS_LIB='pure_quanta',
 CDS_PART_NAME='Q_RES_0402LF-4.99K,0.1%,1/16W,CHIP,CS24992BB04',
 ROOM='HSC BOM1',
 PART_NUMBER='CS24992BB04',
 VALUE='4.99K',
 PRIM_FILE='./archive_libs/logical/q_res/chips/chips.prt';

PART_NAME
 PR3928 'Q_RES_0402LF-0,5%,1/16W,CHIP,CS00002JB13':
 ROOM='HSC BOM1';

SECTION_NUMBER 1
 '@T6G_MB_LIB.T6G(SCH_1):PAGE267_I51@PURE_QUANTA.Q_RES(CHIPS)':
 C_PATH='@t6g_mb_lib.t6g(sch_1):page267_i51@pure_quanta.q_res(chips)',
 P_PATH='@t6g_mb_lib.t6g(sch_1):page262_i51@pure_quanta.q_res(chips)',
 PATH='I51',
 DRAWING='@T6G_MB_LIB.T6G(SCH_1):PAGE267',
 WATTAGE='1/16W',
 TOLERANCE='5%',
 MATERIAL='CHIP',
 PHYS_PAGE='262',
 XY='(-13100,2525)',
 ROT='0',
 VER='1',
 PACK_TYPE='0402LF',
 LOCATION='PR3928',
 CDS_LIB='pure_quanta',
 CDS_PART_NAME='Q_RES_0402LF-0,5%,1/16W,CHIP,CS00002JB13',
 ROOM='HSC BOM1',
 PART_NUMBER='CS00002JB13',
 VALUE='0',
 PRIM_FILE='./archive_libs/logical/q_res/chips/chips.prt';

PART_NAME
 PR3929 'Q_RES_0402LF-1K,1%,1/16W,EMPTY,CS21002FB06':
 ROOM='HSC BOM1';

SECTION_NUMBER 1
 '@T6G_MB_LIB.T6G(SCH_1):PAGE267_I53@PURE_QUANTA.Q_RES(CHIPS)':
 C_PATH='@t6g_mb_lib.t6g(sch_1):page267_i53@pure_quanta.q_res(chips)',
 P_PATH='@t6g_mb_lib.t6g(sch_1):page262_i53@pure_quanta.q_res(chips)',
 PATH='I53',
 DRAWING='@T6G_MB_LIB.T6G(SCH_1):PAGE267',
 WATTAGE='1/16W',
 TOLERANCE='1%',
 MATERIAL='EMPTY',
 PHYS_PAGE='262',
 XY='(-12850,2150)',
 ROT='1',
 VER='1',
 PACK_TYPE='0402LF',
 LOCATION='PR3929',
 CDS_LIB='pure_quanta',
 CDS_PART_NAME='Q_RES_0402LF-1K,1%,1/16W,EMPTY,CS21002FB06',
 ROOM='HSC BOM1',
 PART_NUMBER='CS21002FB06',
 VALUE='1K',
 PRIM_FILE='./archive_libs/logical/q_res/chips/chips.prt';

PART_NAME
 PR3930 'Q_RES_0402LF-0,5%,1/16W,CHIP,CS00002JB13':
 ROOM='HSC BOM1';

SECTION_NUMBER 1
 '@T6G_MB_LIB.T6G(SCH_1):PAGE267_I52@PURE_QUANTA.Q_RES(CHIPS)':
 C_PATH='@t6g_mb_lib.t6g(sch_1):page267_i52@pure_quanta.q_res(chips)',
 P_PATH='@t6g_mb_lib.t6g(sch_1):page262_i52@pure_quanta.q_res(chips)',
 PATH='I52',
 DRAWING='@T6G_MB_LIB.T6G(SCH_1):PAGE267',
 WATTAGE='1/16W',
 TOLERANCE='5%',
 MATERIAL='CHIP',
 PHYS_PAGE='262',
 XY='(-12850,1750)',
 ROT='1',
 VER='1',
 PACK_TYPE='0402LF',
 LOCATION='PR3930',
 CDS_LIB='pure_quanta',
 CDS_PART_NAME='Q_RES_0402LF-0,5%,1/16W,CHIP,CS00002JB13',
 ROOM='HSC BOM1',
 PART_NUMBER='CS00002JB13',
 VALUE='0',
 PRIM_FILE='./archive_libs/logical/q_res/chips/chips.prt';

PART_NAME
 PR3931 'Q_RES_0402LF-75K,0.1%,1/16W,CHIP,CS37502BB01':
 ROOM='HSC BOM1';

SECTION_NUMBER 1
 '@T6G_MB_LIB.T6G(SCH_1):PAGE267_I71@PURE_QUANTA.Q_RES(CHIPS)':
 C_PATH='@t6g_mb_lib.t6g(sch_1):page267_i71@pure_quanta.q_res(chips)',
 P_PATH='@t6g_mb_lib.t6g(sch_1):page262_i71@pure_quanta.q_res(chips)',
 PATH='I71',
 DRAWING='@T6G_MB_LIB.T6G(SCH_1):PAGE267',
 WATTAGE='1/16W',
 TOLERANCE='0.1%',
 MATERIAL='CHIP',
 PHYS_PAGE='262',
 XY='(-10325,4425)',
 ROT='0',
 VER='2',
 PACK_TYPE='0402LF',
 LOCATION='PR3931',
 CDS_LIB='pure_quanta',
 CDS_PART_NAME='Q_RES_0402LF-75K,0.1%,1/16W,CHIP,CS37502BB01',
 ROOM='HSC BOM1',
 PART_NUMBER='CS37502BB01',
 VALUE='75K',
 PRIM_FILE='./archive_libs/logical/q_res/chips/chips.prt';

PART_NAME
 PR3932 'Q_RES_0402LF-4.99K,0.1%,1/16W,CHIP,CS24992BB04':
 ROOM='HSC BOM1';

SECTION_NUMBER 1
 '@T6G_MB_LIB.T6G(SCH_1):PAGE267_I70@PURE_QUANTA.Q_RES(CHIPS)':
 C_PATH='@t6g_mb_lib.t6g(sch_1):page267_i70@pure_quanta.q_res(chips)',
 P_PATH='@t6g_mb_lib.t6g(sch_1):page262_i70@pure_quanta.q_res(chips)',
 PATH='I70',
 DRAWING='@T6G_MB_LIB.T6G(SCH_1):PAGE267',
 WATTAGE='1/16W',
 TOLERANCE='0.1%',
 MATERIAL='CHIP',
 PHYS_PAGE='262',
 XY='(-10250,3975)',
 ROT='0',
 VER='2',
 PACK_TYPE='0402LF',
 LOCATION='PR3932',
 CDS_LIB='pure_quanta',
 CDS_PART_NAME='Q_RES_0402LF-4.99K,0.1%,1/16W,CHIP,CS24992BB04',
 ROOM='HSC BOM1',
 PART_NUMBER='CS24992BB04',
 VALUE='4.99K',
 PRIM_FILE='./archive_libs/logical/q_res/chips/chips.prt';

PART_NAME
 PR3935 'Q_RES_0402LF-10K,1%,1/16W,CHIP,CS31002FB08':
 ROOM='HSC BOM1';

SECTION_NUMBER 1
 '@T6G_MB_LIB.T6G(SCH_1):PAGE267_I81@PURE_QUANTA.Q_RES(CHIPS)':
 C_PATH='@t6g_mb_lib.t6g(sch_1):page267_i81@pure_quanta.q_res(chips)',
 P_PATH='@t6g_mb_lib.t6g(sch_1):page262_i81@pure_quanta.q_res(chips)',
 PATH='I81',
 DRAWING='@T6G_MB_LIB.T6G(SCH_1):PAGE267',
 WATTAGE='1/16W',
 TOLERANCE='1%',
 MATERIAL='CHIP',
 PHYS_PAGE='262',
 XY='(-8450,2450)',
 ROT='0',
 VER='2',
 PACK_TYPE='0402LF',
 LOCATION='PR3935',
 CDS_LIB='pure_quanta',
 CDS_PART_NAME='Q_RES_0402LF-10K,1%,1/16W,CHIP,CS31002FB08',
 ROOM='HSC BOM1',
 PART_NUMBER='CS31002FB08',
 VALUE='10K',
 PRIM_FILE='./archive_libs/logical/q_res/chips/chips.prt';

PART_NAME
 PR3937 'Q_RES_0402LF-120K,1%,1/16W,CHIP,CS41202FB05':
 ROOM='HSC BOM1';

SECTION_NUMBER 1
 '@T6G_MB_LIB.T6G(SCH_1):PAGE267_I85@PURE_QUANTA.Q_RES(CHIPS)':
 C_PATH='@t6g_mb_lib.t6g(sch_1):page267_i85@pure_quanta.q_res(chips)',
 P_PATH='@t6g_mb_lib.t6g(sch_1):page262_i85@pure_quanta.q_res(chips)',
 PATH='I85',
 DRAWING='@T6G_MB_LIB.T6G(SCH_1):PAGE267',
 WATTAGE='1/16W',
 TOLERANCE='1%',
 MATERIAL='CHIP',
 PHYS_PAGE='262',
 XY='(-8125,3275)',
 ROT='0',
 VER='1',
 PACK_TYPE='0402LF',
 LOCATION='PR3937',
 CDS_LIB='pure_quanta',
 CDS_PART_NAME='Q_RES_0402LF-120K,1%,1/16W,CHIP,CS41202FB05',
 ROOM='HSC BOM1',
 PART_NUMBER='CS41202FB05',
 VALUE='120K',
 PRIM_FILE='./archive_libs/logical/q_res/chips/chips.prt';

PART_NAME
 PR3944 'Q_RES_0402LF-46.4K,1%,1/16W,CHIP,CS34642FB02':
 ROOM='E1S_P12V_MPS_MAM_BOM2';

SECTION_NUMBER 1
 '@T6G_MB_LIB.T6G(SCH_1):PAGE323_I15@PURE_QUANTA.Q_RES(CHIPS)':
 C_PATH='@t6g_mb_lib.t6g(sch_1):page323_i15@pure_quanta.q_res(chips)',
 P_PATH='@t6g_mb_lib.t6g(sch_1):page147_i15@pure_quanta.q_res(chips)',
 PATH='I15',
 DRAWING='@T6G_MB_LIB.T6G(SCH_1):PAGE323',
 WATTAGE='1/16W',
 TOLERANCE='1%',
 MATERIAL='CHIP',
 PHYS_PAGE='147',
 XY='(-1625,850)',
 ROT='0',
 VER='2',
 PACK_TYPE='0402LF',
 LOCATION='PR3944',
 CDS_LIB='pure_quanta',
 CDS_PART_NAME='Q_RES_0402LF-46.4K,1%,1/16W,CHIP,CS34642FB02',
 ROOM='E1S_P12V_MPS_MAM_BOM2',
 PART_NUMBER='CS34642FB02',
 VALUE='46.4K',
 PRIM_FILE='./archive_libs/logical/q_res/chips/chips.prt';

PART_NAME
 PR3945 'Q_RES_0402LF-71.5K,1%,1/16W,CHIP,CS37152FB05':
 ROOM='E1S_P3V3_BOM2';

SECTION_NUMBER 1
 '@T6G_MB_LIB.T6G(SCH_1):PAGE323_I4@PURE_QUANTA.Q_RES(CHIPS)':
 C_PATH='@t6g_mb_lib.t6g(sch_1):page323_i4@pure_quanta.q_res(chips)',
 P_PATH='@t6g_mb_lib.t6g(sch_1):page147_i4@pure_quanta.q_res(chips)',
 PATH='I4',
 DRAWING='@T6G_MB_LIB.T6G(SCH_1):PAGE323',
 WATTAGE='1/16W',
 TOLERANCE='1%',
 MATERIAL='CHIP',
 PHYS_PAGE='147',
 XY='(675,-1650)',
 ROT='0',
 VER='2',
 PACK_TYPE='0402LF',
 LOCATION='PR3945',
 CDS_LIB='pure_quanta',
 CDS_PART_NAME='Q_RES_0402LF-71.5K,1%,1/16W,CHIP,CS37152FB05',
 ROOM='E1S_P3V3_BOM2',
 PART_NUMBER='CS37152FB05',
 VALUE='71.5K',
 PRIM_FILE='./archive_libs/logical/q_res/chips/chips.prt';

PART_NAME
 PR3947 'Q_RES_0402LF-2.8K,1%,1/16W,CHIP,CS22802FB04':
 ROOM='E1S_P3V3_BOM2';

SECTION_NUMBER 1
 '@T6G_MB_LIB.T6G(SCH_1):PAGE323_I6@PURE_QUANTA.Q_RES(CHIPS)':
 C_PATH='@t6g_mb_lib.t6g(sch_1):page323_i6@pure_quanta.q_res(chips)',
 P_PATH='@t6g_mb_lib.t6g(sch_1):page147_i6@pure_quanta.q_res(chips)',
 PATH='I6',
 DRAWING='@T6G_MB_LIB.T6G(SCH_1):PAGE323',
 WATTAGE='1/16W',
 TOLERANCE='1%',
 MATERIAL='CHIP',
 PHYS_PAGE='147',
 XY='(1000,-1700)',
 ROT='1',
 VER='1',
 PACK_TYPE='0402LF',
 LOCATION='PR3947',
 CDS_LIB='pure_quanta',
 CDS_PART_NAME='Q_RES_0402LF-2.8K,1%,1/16W,CHIP,CS22802FB04',
 ROOM='E1S_P3V3_BOM2',
 PART_NUMBER='CS22802FB04',
 VALUE='2.8K',
 PRIM_FILE='./archive_libs/logical/q_res/chips/chips.prt';

PART_NAME
 PR3949 'Q_RES_0402LF-56K,1%,1/16W,CHIP,CS35602FB00':
 ROOM='E1S_P12V_MPS_MAM_BOM2';

SECTION_NUMBER 1
 '@T6G_MB_LIB.T6G(SCH_1):PAGE323_I36@PURE_QUANTA.Q_RES(CHIPS)':
 C_PATH='@t6g_mb_lib.t6g(sch_1):page323_i36@pure_quanta.q_res(chips)',
 P_PATH='@t6g_mb_lib.t6g(sch_1):page147_i36@pure_quanta.q_res(chips)',
 PATH='I36',
 DRAWING='@T6G_MB_LIB.T6G(SCH_1):PAGE323',
 WATTAGE='1/16W',
 TOLERANCE='1%',
 MATERIAL='CHIP',
 PHYS_PAGE='147',
 XY='(675,550)',
 ROT='0',
 VER='2',
 PACK_TYPE='0402LF',
 LOCATION='PR3949',
 CDS_LIB='pure_quanta',
 CDS_PART_NAME='Q_RES_0402LF-56K,1%,1/16W,CHIP,CS35602FB00',
 ROOM='E1S_P12V_MPS_MAM_BOM2',
 PART_NUMBER='CS35602FB00',
 VALUE='56K',
 PRIM_FILE='./archive_libs/logical/q_res/chips/chips.prt';

PART_NAME
 PR3950 'Q_RES_0402LF-100,1%,1/16W,EMPTY,CS11002FB07':
 ROOM='E1S_P12V_MPS_MAM_BOM2';

SECTION_NUMBER 1
 '@T6G_MB_LIB.T6G(SCH_1):PAGE323_I42@PURE_QUANTA.Q_RES(CHIPS)':
 C_PATH='@t6g_mb_lib.t6g(sch_1):page323_i42@pure_quanta.q_res(chips)',
 P_PATH='@t6g_mb_lib.t6g(sch_1):page147_i42@pure_quanta.q_res(chips)',
 PATH='I42',
 DRAWING='@T6G_MB_LIB.T6G(SCH_1):PAGE323',
 WATTAGE='1/16W',
 TOLERANCE='1%',
 MATERIAL='EMPTY',
 PHYS_PAGE='147',
 XY='(1050,1400)',
 ROT='0',
 VER='2',
 PACK_TYPE='0402LF',
 LOCATION='PR3950',
 CDS_LIB='pure_quanta',
 CDS_PART_NAME='Q_RES_0402LF-100,1%,1/16W,EMPTY,CS11002FB07',
 ROOM='E1S_P12V_MPS_MAM_BOM2',
 PART_NUMBER='CS11002FB07',
 VALUE='100',
 PRIM_FILE='./archive_libs/logical/q_res/chips/chips.prt';

PART_NAME
 PR3951 'Q_RES_0402LF-10K,1%,1/16W,CHIP,CS31002FB08':
 ROOM='E1S_P12V_MPS_MAM_BOM2';

SECTION_NUMBER 1
 '@T6G_MB_LIB.T6G(SCH_1):PAGE323_I40@PURE_QUANTA.Q_RES(CHIPS)':
 C_PATH='@t6g_mb_lib.t6g(sch_1):page323_i40@pure_quanta.q_res(chips)',
 P_PATH='@t6g_mb_lib.t6g(sch_1):page147_i40@pure_quanta.q_res(chips)',
 PATH='I40',
 DRAWING='@T6G_MB_LIB.T6G(SCH_1):PAGE323',
 WATTAGE='1/16W',
 TOLERANCE='1%',
 MATERIAL='CHIP',
 PHYS_PAGE='147',
 XY='(1100,925)',
 ROT='0',
 VER='1',
 PACK_TYPE='0402LF',
 LOCATION='PR3951',
 CDS_LIB='pure_quanta',
 CDS_PART_NAME='Q_RES_0402LF-10K,1%,1/16W,CHIP,CS31002FB08',
 ROOM='E1S_P12V_MPS_MAM_BOM2',
 PART_NUMBER='CS31002FB08',
 VALUE='10K',
 PRIM_FILE='./archive_libs/logical/q_res/chips/chips.prt';

PART_NAME
 PR3952 'Q_RES_0402LF-71.5K,1%,1/16W,EMPTY,CS37152FB05':
 ROOM='E1S_P12V_MPS_MAM_BOM2';

SECTION_NUMBER 1
 '@T6G_MB_LIB.T6G(SCH_1):PAGE323_I45@PURE_QUANTA.Q_RES(CHIPS)':
 C_PATH='@t6g_mb_lib.t6g(sch_1):page323_i45@pure_quanta.q_res(chips)',
 P_PATH='@t6g_mb_lib.t6g(sch_1):page147_i45@pure_quanta.q_res(chips)',
 PATH='I45',
 DRAWING='@T6G_MB_LIB.T6G(SCH_1):PAGE323',
 WATTAGE='1/16W',
 TOLERANCE='1%',
 MATERIAL='EMPTY',
 PHYS_PAGE='147',
 XY='(1650,1400)',
 ROT='0',
 VER='2',
 PACK_TYPE='0402LF',
 LOCATION='PR3952',
 CDS_LIB='pure_quanta',
 CDS_PART_NAME='Q_RES_0402LF-71.5K,1%,1/16W,EMPTY,CS37152FB05',
 ROOM='E1S_P12V_MPS_MAM_BOM2',
 PART_NUMBER='CS37152FB05',
 VALUE='71.5K',
 PRIM_FILE='./archive_libs/logical/q_res/chips/chips.prt';

PART_NAME
 PR3953 'Q_RES_0402LF-120K,1%,1/16W,CHIP,CS41202FB05':
 ROOM='E1S_P12V_MPS_MAM_BOM2';

SECTION_NUMBER 1
 '@T6G_MB_LIB.T6G(SCH_1):PAGE323_I52@PURE_QUANTA.Q_RES(CHIPS)':
 C_PATH='@t6g_mb_lib.t6g(sch_1):page323_i52@pure_quanta.q_res(chips)',
 P_PATH='@t6g_mb_lib.t6g(sch_1):page147_i52@pure_quanta.q_res(chips)',
 PATH='I52',
 DRAWING='@T6G_MB_LIB.T6G(SCH_1):PAGE323',
 WATTAGE='1/16W',
 TOLERANCE='1%',
 MATERIAL='CHIP',
 PHYS_PAGE='147',
 XY='(2050,1325)',
 ROT='0',
 VER='2',
 PACK_TYPE='0402LF',
 LOCATION='PR3953',
 CDS_LIB='pure_quanta',
 CDS_PART_NAME='Q_RES_0402LF-120K,1%,1/16W,CHIP,CS41202FB05',
 ROOM='E1S_P12V_MPS_MAM_BOM2',
 PART_NUMBER='CS41202FB05',
 VALUE='120K',
 PRIM_FILE='./archive_libs/logical/q_res/chips/chips.prt';

PART_NAME
 PR3954 'Q_RES_0402LF-10K,1%,1/16W,CHIP,CS31002FB08':
 ROOM='E1S_P12V_MPS_MAM_BOM2';

SECTION_NUMBER 1
 '@T6G_MB_LIB.T6G(SCH_1):PAGE323_I49@PURE_QUANTA.Q_RES(CHIPS)':
 C_PATH='@t6g_mb_lib.t6g(sch_1):page323_i49@pure_quanta.q_res(chips)',
 P_PATH='@t6g_mb_lib.t6g(sch_1):page147_i49@pure_quanta.q_res(chips)',
 PATH='I49',
 DRAWING='@T6G_MB_LIB.T6G(SCH_1):PAGE323',
 WATTAGE='1/16W',
 TOLERANCE='1%',
 MATERIAL='CHIP',
 PHYS_PAGE='147',
 XY='(2050,900)',
 ROT='0',
 VER='2',
 PACK_TYPE='0402LF',
 LOCATION='PR3954',
 CDS_LIB='pure_quanta',
 CDS_PART_NAME='Q_RES_0402LF-10K,1%,1/16W,CHIP,CS31002FB08',
 ROOM='E1S_P12V_MPS_MAM_BOM2',
 PART_NUMBER='CS31002FB08',
 VALUE='10K',
 PRIM_FILE='./archive_libs/logical/q_res/chips/chips.prt';

PART_NAME
 PR3957 'Q_RES_0603LF-49.9,1%,1/10W,CHIP,CS04993F909':
 ROOM='E1S_P12V_MPS_MAM_BOM2';

SECTION_NUMBER 1
 '@T6G_MB_LIB.T6G(SCH_1):PAGE323_I54@PURE_QUANTA.Q_RES(CHIPS)':
 C_PATH='@t6g_mb_lib.t6g(sch_1):page323_i54@pure_quanta.q_res(chips)',
 P_PATH='@t6g_mb_lib.t6g(sch_1):page147_i54@pure_quanta.q_res(chips)',
 PATH='I54',
 DRAWING='@T6G_MB_LIB.T6G(SCH_1):PAGE323',
 WATTAGE='1/10W',
 TOLERANCE='1%',
 MATERIAL='CHIP',
 PHYS_PAGE='147',
 XY='(2575,1325)',
 ROT='0',
 VER='2',
 PACK_TYPE='0603LF',
 LOCATION='PR3957',
 CDS_LIB='pure_quanta',
 CDS_PART_NAME='Q_RES_0603LF-49.9,1%,1/10W,CHIP,CS04993F909',
 ROOM='E1S_P12V_MPS_MAM_BOM2',
 PART_NUMBER='CS04993F909',
 VALUE='49.9',
 PRIM_FILE='./archive_libs/logical/q_res/chips/chips.prt';

PART_NAME
 PR3960 'Q_RES_0402LF-160K,1%,1/16W,CHIP,CS41602FB05':
 ROOM='E1S_P12V_MAM_TIC_BOM1';

SECTION_NUMBER 1
 '@T6G_MB_LIB.T6G(SCH_1):PAGE324_I37@PURE_QUANTA.Q_RES(CHIPS)':
 C_PATH='@t6g_mb_lib.t6g(sch_1):page324_i37@pure_quanta.q_res(chips)',
 P_PATH='@t6g_mb_lib.t6g(sch_1):page146_i37@pure_quanta.q_res(chips)',
 PATH='I37',
 DRAWING='@T6G_MB_LIB.T6G(SCH_1):PAGE324',
 WATTAGE='1/16W',
 TOLERANCE='1%',
 MATERIAL='CHIP',
 PHYS_PAGE='146',
 XY='(-125,1075)',
 ROT='0',
 VER='2',
 PACK_TYPE='0402LF',
 LOCATION='PR3960',
 CDS_LIB='pure_quanta',
 CDS_PART_NAME='Q_RES_0402LF-160K,1%,1/16W,CHIP,CS41602FB05',
 ROOM='E1S_P12V_MAM_TIC_BOM1',
 PART_NUMBER='CS41602FB05',
 VALUE='160K',
 PRIM_FILE='./archive_libs/logical/q_res/chips/chips.prt';

PART_NAME
 PR3961 'Q_RES_0402LF-6.8K,1%,1/16W,CHIP,CS26802FB02':
 ROOM='E1S_P12V_MAM_TIC_BOM1';

SECTION_NUMBER 1
 '@T6G_MB_LIB.T6G(SCH_1):PAGE324_I32@PURE_QUANTA.Q_RES(CHIPS)':
 C_PATH='@t6g_mb_lib.t6g(sch_1):page324_i32@pure_quanta.q_res(chips)',
 P_PATH='@t6g_mb_lib.t6g(sch_1):page146_i32@pure_quanta.q_res(chips)',
 PATH='I32',
 DRAWING='@T6G_MB_LIB.T6G(SCH_1):PAGE324',
 WATTAGE='1/16W',
 TOLERANCE='1%',
 MATERIAL='CHIP',
 PHYS_PAGE='146',
 XY='(-125,400)',
 ROT='0',
 VER='2',
 PACK_TYPE='0402LF',
 LOCATION='PR3961',
 CDS_LIB='pure_quanta',
 CDS_PART_NAME='Q_RES_0402LF-6.8K,1%,1/16W,CHIP,CS26802FB02',
 ROOM='E1S_P12V_MAM_TIC_BOM1',
 PART_NUMBER='CS26802FB02',
 VALUE='6.8K',
 PRIM_FILE='./archive_libs/logical/q_res/chips/chips.prt';

PART_NAME
 PR3962 'Q_RES_0402LF-15K,1%,1/16W,CHIP,CS31502FB05':
 ROOM='E1S_P12V_MAM_TIC_BOM1';

SECTION_NUMBER 1
 '@T6G_MB_LIB.T6G(SCH_1):PAGE324_I31@PURE_QUANTA.Q_RES(CHIPS)':
 C_PATH='@t6g_mb_lib.t6g(sch_1):page324_i31@pure_quanta.q_res(chips)',
 P_PATH='@t6g_mb_lib.t6g(sch_1):page146_i31@pure_quanta.q_res(chips)',
 PATH='I31',
 DRAWING='@T6G_MB_LIB.T6G(SCH_1):PAGE324',
 WATTAGE='1/16W',
 TOLERANCE='1%',
 MATERIAL='CHIP',
 PHYS_PAGE='146',
 XY='(-125,125)',
 ROT='0',
 VER='2',
 PACK_TYPE='0402LF',
 LOCATION='PR3962',
 CDS_LIB='pure_quanta',
 CDS_PART_NAME='Q_RES_0402LF-15K,1%,1/16W,CHIP,CS31502FB05',
 ROOM='E1S_P12V_MAM_TIC_BOM1',
 PART_NUMBER='CS31502FB05',
 VALUE='15K',
 PRIM_FILE='./archive_libs/logical/q_res/chips/chips.prt';

PART_NAME
 PR3963 'Q_RES_0402LF-25.5K,1%,1/16W,CHIP,CS32552FB06':
 ROOM='E1S_P3V3_BOM1';

SECTION_NUMBER 1
 '@T6G_MB_LIB.T6G(SCH_1):PAGE324_I21@PURE_QUANTA.Q_RES(CHIPS)':
 C_PATH='@t6g_mb_lib.t6g(sch_1):page324_i21@pure_quanta.q_res(chips)',
 P_PATH='@t6g_mb_lib.t6g(sch_1):page146_i21@pure_quanta.q_res(chips)',
 PATH='I21',
 DRAWING='@T6G_MB_LIB.T6G(SCH_1):PAGE324',
 WATTAGE='1/16W',
 TOLERANCE='1%',
 MATERIAL='CHIP',
 PHYS_PAGE='146',
 XY='(-125,-1575)',
 ROT='0',
 VER='2',
 PACK_TYPE='0402LF',
 LOCATION='PR3963',
 CDS_LIB='pure_quanta',
 CDS_PART_NAME='Q_RES_0402LF-25.5K,1%,1/16W,CHIP,CS32552FB06',
 ROOM='E1S_P3V3_BOM1',
 PART_NUMBER='CS32552FB06',
 VALUE='25.5K',
 PRIM_FILE='./archive_libs/logical/q_res/chips/chips.prt';

PART_NAME
 PR3964 'Q_RES_0402LF-7.15K,1%,1/16W,CHIP,CS27152FB03':
 ROOM='E1S_P3V3_BOM1';

SECTION_NUMBER 1
 '@T6G_MB_LIB.T6G(SCH_1):PAGE324_I17@PURE_QUANTA.Q_RES(CHIPS)':
 C_PATH='@t6g_mb_lib.t6g(sch_1):page324_i17@pure_quanta.q_res(chips)',
 P_PATH='@t6g_mb_lib.t6g(sch_1):page146_i17@pure_quanta.q_res(chips)',
 PATH='I17',
 DRAWING='@T6G_MB_LIB.T6G(SCH_1):PAGE324',
 WATTAGE='1/16W',
 TOLERANCE='1%',
 MATERIAL='CHIP',
 PHYS_PAGE='146',
 XY='(-125,-2300)',
 ROT='0',
 VER='2',
 PACK_TYPE='0402LF',
 LOCATION='PR3964',
 CDS_LIB='pure_quanta',
 CDS_PART_NAME='Q_RES_0402LF-7.15K,1%,1/16W,CHIP,CS27152FB03',
 ROOM='E1S_P3V3_BOM1',
 PART_NUMBER='CS27152FB03',
 VALUE='7.15K',
 PRIM_FILE='./archive_libs/logical/q_res/chips/chips.prt';

PART_NAME
 PR3965 'Q_RES_0402LF-15K,1%,1/16W,CHIP,CS31502FB05':
 ROOM='E1S_P3V3_BOM1';

SECTION_NUMBER 1
 '@T6G_MB_LIB.T6G(SCH_1):PAGE324_I16@PURE_QUANTA.Q_RES(CHIPS)':
 C_PATH='@t6g_mb_lib.t6g(sch_1):page324_i16@pure_quanta.q_res(chips)',
 P_PATH='@t6g_mb_lib.t6g(sch_1):page146_i16@pure_quanta.q_res(chips)',
 PATH='I16',
 DRAWING='@T6G_MB_LIB.T6G(SCH_1):PAGE324',
 WATTAGE='1/16W',
 TOLERANCE='1%',
 MATERIAL='CHIP',
 PHYS_PAGE='146',
 XY='(-125,-2575)',
 ROT='0',
 VER='2',
 PACK_TYPE='0402LF',
 LOCATION='PR3965',
 CDS_LIB='pure_quanta',
 CDS_PART_NAME='Q_RES_0402LF-15K,1%,1/16W,CHIP,CS31502FB05',
 ROOM='E1S_P3V3_BOM1',
 PART_NUMBER='CS31502FB05',
 VALUE='15K',
 PRIM_FILE='./archive_libs/logical/q_res/chips/chips.prt';

PART_NAME
 PR3966 'Q_RES_0402LF-10,1%,1/16W,CHIP,CS01002FB07':
 ROOM='E1S_P12V_MAM_TIC_BOM1';

SECTION_NUMBER 1
 '@T6G_MB_LIB.T6G(SCH_1):PAGE324_I65@PURE_QUANTA.Q_RES(CHIPS)':
 C_PATH='@t6g_mb_lib.t6g(sch_1):page324_i65@pure_quanta.q_res(chips)',
 P_PATH='@t6g_mb_lib.t6g(sch_1):page146_i65@pure_quanta.q_res(chips)',
 PATH='I65',
 DRAWING='@T6G_MB_LIB.T6G(SCH_1):PAGE324',
 WATTAGE='1/16W',
 TOLERANCE='1%',
 MATERIAL='CHIP',
 PHYS_PAGE='146',
 XY='(200,1375)',
 ROT='0',
 VER='2',
 PACK_TYPE='0402LF',
 LOCATION='PR3966',
 CDS_LIB='pure_quanta',
 CDS_PART_NAME='Q_RES_0402LF-10,1%,1/16W,CHIP,CS01002FB07',
 ROOM='E1S_P12V_MAM_TIC_BOM1',
 PART_NUMBER='CS01002FB07',
 VALUE='10',
 PRIM_FILE='./archive_libs/logical/q_res/chips/chips.prt';

PART_NAME
 PR3967 'Q_RES_0402LF-10,1%,1/16W,CHIP,CS01002FB07':
 ROOM='E1S_P3V3_BOM1';

SECTION_NUMBER 1
 '@T6G_MB_LIB.T6G(SCH_1):PAGE324_I43@PURE_QUANTA.Q_RES(CHIPS)':
 C_PATH='@t6g_mb_lib.t6g(sch_1):page324_i43@pure_quanta.q_res(chips)',
 P_PATH='@t6g_mb_lib.t6g(sch_1):page146_i43@pure_quanta.q_res(chips)',
 PATH='I43',
 DRAWING='@T6G_MB_LIB.T6G(SCH_1):PAGE324',
 WATTAGE='1/16W',
 TOLERANCE='1%',
 MATERIAL='CHIP',
 PHYS_PAGE='146',
 XY='(200,-1325)',
 ROT='0',
 VER='2',
 PACK_TYPE='0402LF',
 LOCATION='PR3967',
 CDS_LIB='pure_quanta',
 CDS_PART_NAME='Q_RES_0402LF-10,1%,1/16W,CHIP,CS01002FB07',
 ROOM='E1S_P3V3_BOM1',
 PART_NUMBER='CS01002FB07',
 VALUE='10',
 PRIM_FILE='./archive_libs/logical/q_res/chips/chips.prt';

PART_NAME
 PR3968 'Q_RES_0402LF-9.31K,1%,1/16W,CHIP,CS29312FB02':
 ROOM='E1S_P12V_MAM_TIC_BOM1';

SECTION_NUMBER 1
 '@T6G_MB_LIB.T6G(SCH_1):PAGE324_I63@PURE_QUANTA.Q_RES(CHIPS)':
 C_PATH='@t6g_mb_lib.t6g(sch_1):page324_i63@pure_quanta.q_res(chips)',
 P_PATH='@t6g_mb_lib.t6g(sch_1):page146_i63@pure_quanta.q_res(chips)',
 PATH='I63',
 DRAWING='@T6G_MB_LIB.T6G(SCH_1):PAGE324',
 WATTAGE='1/16W',
 TOLERANCE='1%',
 MATERIAL='CHIP',
 PHYS_PAGE='146',
 XY='(725,150)',
 ROT='0',
 VER='2',
 PACK_TYPE='0402LF',
 LOCATION='PR3968',
 CDS_LIB='pure_quanta',
 CDS_PART_NAME='Q_RES_0402LF-9.31K,1%,1/16W,CHIP,CS29312FB02',
 ROOM='E1S_P12V_MAM_TIC_BOM1',
 PART_NUMBER='CS29312FB02',
 VALUE='9.31K',
 PRIM_FILE='./archive_libs/logical/q_res/chips/chips.prt';

PART_NAME
 PR3969 'Q_RES_0402LF-2.49K,1%,1/16W,CHIP,CS22492FB05':
 ROOM='E1S_P3V3_BOM1';

SECTION_NUMBER 1
 '@T6G_MB_LIB.T6G(SCH_1):PAGE324_I39@PURE_QUANTA.Q_RES(CHIPS)':
 C_PATH='@t6g_mb_lib.t6g(sch_1):page324_i39@pure_quanta.q_res(chips)',
 P_PATH='@t6g_mb_lib.t6g(sch_1):page146_i39@pure_quanta.q_res(chips)',
 PATH='I39',
 DRAWING='@T6G_MB_LIB.T6G(SCH_1):PAGE324',
 WATTAGE='1/16W',
 TOLERANCE='1%',
 MATERIAL='CHIP',
 PHYS_PAGE='146',
 XY='(725,-2550)',
 ROT='0',
 VER='2',
 PACK_TYPE='0402LF',
 LOCATION='PR3969',
 CDS_LIB='pure_quanta',
 CDS_PART_NAME='Q_RES_0402LF-2.49K,1%,1/16W,CHIP,CS22492FB05',
 ROOM='E1S_P3V3_BOM1',
 PART_NUMBER='CS22492FB05',
 VALUE='2.49K',
 PRIM_FILE='./archive_libs/logical/q_res/chips/chips.prt';

PART_NAME
 PR3970 'Q_RES_0402LF-2.67K,1%,1/16W,CHIP,CS22672FB03':
 ROOM='E1S_P12V_MAM_TIC_BOM1';

SECTION_NUMBER 1
 '@T6G_MB_LIB.T6G(SCH_1):PAGE324_I68@PURE_QUANTA.Q_RES(CHIPS)':
 C_PATH='@t6g_mb_lib.t6g(sch_1):page324_i68@pure_quanta.q_res(chips)',
 P_PATH='@t6g_mb_lib.t6g(sch_1):page146_i68@pure_quanta.q_res(chips)',
 PATH='I68',
 DRAWING='@T6G_MB_LIB.T6G(SCH_1):PAGE324',
 WATTAGE='1/16W',
 TOLERANCE='1%',
 MATERIAL='CHIP',
 PHYS_PAGE='146',
 XY='(2325,275)',
 ROT='0',
 VER='2',
 PACK_TYPE='0402LF',
 LOCATION='PR3970',
 CDS_LIB='pure_quanta',
 CDS_PART_NAME='Q_RES_0402LF-2.67K,1%,1/16W,CHIP,CS22672FB03',
 ROOM='E1S_P12V_MAM_TIC_BOM1',
 PART_NUMBER='CS22672FB03',
 VALUE='2.67K',
 PRIM_FILE='./archive_libs/logical/q_res/chips/chips.prt';

PART_NAME
 PR3971 'Q_RES_0402LF-9.76K,1%,1/16W,CHIP,CS29762FB05':
 ROOM='E1S_P3V3_BOM1';

SECTION_NUMBER 1
 '@T6G_MB_LIB.T6G(SCH_1):PAGE324_I45@PURE_QUANTA.Q_RES(CHIPS)':
 C_PATH='@t6g_mb_lib.t6g(sch_1):page324_i45@pure_quanta.q_res(chips)',
 P_PATH='@t6g_mb_lib.t6g(sch_1):page146_i45@pure_quanta.q_res(chips)',
 PATH='I45',
 DRAWING='@T6G_MB_LIB.T6G(SCH_1):PAGE324',
 WATTAGE='1/16W',
 TOLERANCE='1%',
 MATERIAL='CHIP',
 PHYS_PAGE='146',
 XY='(2325,-2400)',
 ROT='0',
 VER='2',
 PACK_TYPE='0402LF',
 LOCATION='PR3971',
 CDS_LIB='pure_quanta',
 CDS_PART_NAME='Q_RES_0402LF-9.76K,1%,1/16W,CHIP,CS29762FB05',
 ROOM='E1S_P3V3_BOM1',
 PART_NUMBER='CS29762FB05',
 VALUE='9.76K',
 PRIM_FILE='./archive_libs/logical/q_res/chips/chips.prt';

PART_NAME
 PR3980 'Q_RES_0402LF-0,5%,1/16W,CHIP,CS00002JB13':
 ROOM='HSC BOM1';

SECTION_NUMBER 1
 '@T6G_MB_LIB.T6G(SCH_1):PAGE325_I21@PURE_QUANTA.Q_RES(CHIPS)':
 C_PATH='@t6g_mb_lib.t6g(sch_1):page325_i21@pure_quanta.q_res(chips)',
 P_PATH='@t6g_mb_lib.t6g(sch_1):page264_i21@pure_quanta.q_res(chips)',
 PATH='I21',
 DRAWING='@T6G_MB_LIB.T6G(SCH_1):PAGE325',
 WATTAGE='1/16W',
 TOLERANCE='5%',
 MATERIAL='CHIP',
 PHYS_PAGE='264',
 XY='(-3600,1950)',
 ROT='1',
 VER='1',
 PACK_TYPE='0402LF',
 LOCATION='PR3980',
 CDS_LIB='pure_quanta',
 CDS_PART_NAME='Q_RES_0402LF-0,5%,1/16W,CHIP,CS00002JB13',
 ROOM='HSC BOM1',
 PART_NUMBER='CS00002JB13',
 VALUE='0',
 PRIM_FILE='./archive_libs/logical/q_res/chips/chips.prt';

PART_NAME
 PR3981 'Q_RES_0402LF-0,5%,1/16W,CHIP,CS00002JB13':
 ROOM='HSC BOM1';

SECTION_NUMBER 1
 '@T6G_MB_LIB.T6G(SCH_1):PAGE325_I6@PURE_QUANTA.Q_RES(CHIPS)':
 C_PATH='@t6g_mb_lib.t6g(sch_1):page325_i6@pure_quanta.q_res(chips)',
 P_PATH='@t6g_mb_lib.t6g(sch_1):page264_i6@pure_quanta.q_res(chips)',
 PATH='I6',
 DRAWING='@T6G_MB_LIB.T6G(SCH_1):PAGE325',
 WATTAGE='1/16W',
 TOLERANCE='5%',
 MATERIAL='CHIP',
 PHYS_PAGE='264',
 XY='(-3575,-825)',
 ROT='1',
 VER='1',
 PACK_TYPE='0402LF',
 LOCATION='PR3981',
 CDS_LIB='pure_quanta',
 CDS_PART_NAME='Q_RES_0402LF-0,5%,1/16W,CHIP,CS00002JB13',
 ROOM='HSC BOM1',
 PART_NUMBER='CS00002JB13',
 VALUE='0',
 PRIM_FILE='./archive_libs/logical/q_res/chips/chips.prt';

PART_NAME
 PR3982 'Q_RES_0402LF-120K,1%,1/16W,CHIP,CS41202FB05':
 ROOM='HSC BOM1';

SECTION_NUMBER 1
 '@T6G_MB_LIB.T6G(SCH_1):PAGE325_I28@PURE_QUANTA.Q_RES(CHIPS)':
 C_PATH='@t6g_mb_lib.t6g(sch_1):page325_i28@pure_quanta.q_res(chips)',
 P_PATH='@t6g_mb_lib.t6g(sch_1):page264_i28@pure_quanta.q_res(chips)',
 PATH='I28',
 DRAWING='@T6G_MB_LIB.T6G(SCH_1):PAGE325',
 WATTAGE='1/16W',
 TOLERANCE='1%',
 MATERIAL='CHIP',
 PHYS_PAGE='264',
 XY='(-1900,1650)',
 ROT='0',
 VER='1',
 PACK_TYPE='0402LF',
 LOCATION='PR3982',
 CDS_LIB='pure_quanta',
 CDS_PART_NAME='Q_RES_0402LF-120K,1%,1/16W,CHIP,CS41202FB05',
 ROOM='HSC BOM1',
 PART_NUMBER='CS41202FB05',
 VALUE='120K',
 PRIM_FILE='./archive_libs/logical/q_res/chips/chips.prt';

PART_NAME
 PR3984 'Q_RES_0402LF-120K,1%,1/16W,CHIP,CS41202FB05':
 ROOM='HSC BOM1';

SECTION_NUMBER 1
 '@T6G_MB_LIB.T6G(SCH_1):PAGE325_I11@PURE_QUANTA.Q_RES(CHIPS)':
 C_PATH='@t6g_mb_lib.t6g(sch_1):page325_i11@pure_quanta.q_res(chips)',
 P_PATH='@t6g_mb_lib.t6g(sch_1):page264_i11@pure_quanta.q_res(chips)',
 PATH='I11',
 DRAWING='@T6G_MB_LIB.T6G(SCH_1):PAGE325',
 WATTAGE='1/16W',
 TOLERANCE='1%',
 MATERIAL='CHIP',
 PHYS_PAGE='264',
 XY='(-1900,-1125)',
 ROT='0',
 VER='1',
 PACK_TYPE='0402LF',
 LOCATION='PR3984',
 CDS_LIB='pure_quanta',
 CDS_PART_NAME='Q_RES_0402LF-120K,1%,1/16W,CHIP,CS41202FB05',
 ROOM='HSC BOM1',
 PART_NUMBER='CS41202FB05',
 VALUE='120K',
 PRIM_FILE='./archive_libs/logical/q_res/chips/chips.prt';

PART_NAME
 PR3986 'Q_RES_0402LF-2K,0.1%,1/16W,CHIP,CS22002BB07':
 ROOM='HSC BOM1';

SECTION_NUMBER 1
 '@T6G_MB_LIB.T6G(SCH_1):PAGE325_I31@PURE_QUANTA.Q_RES(CHIPS)':
 C_PATH='@t6g_mb_lib.t6g(sch_1):page325_i31@pure_quanta.q_res(chips)',
 P_PATH='@t6g_mb_lib.t6g(sch_1):page264_i31@pure_quanta.q_res(chips)',
 PATH='I31',
 DRAWING='@T6G_MB_LIB.T6G(SCH_1):PAGE325',
 WATTAGE='1/16W',
 TOLERANCE='0.1%',
 MATERIAL='CHIP',
 PHYS_PAGE='264',
 XY='(-1475,825)',
 ROT='0',
 VER='2',
 PACK_TYPE='0402LF',
 LOCATION='PR3986',
 CDS_LIB='pure_quanta',
 CDS_PART_NAME='Q_RES_0402LF-2K,0.1%,1/16W,CHIP,CS22002BB07',
 ROOM='HSC BOM1',
 PART_NUMBER='CS22002BB07',
 VALUE='2K',
 PRIM_FILE='./archive_libs/logical/q_res/chips/chips.prt';

PART_NAME
 PR3987 'Q_RES_0402LF-2K,0.1%,1/16W,CHIP,CS22002BB07':
 ROOM='HSC BOM1';

SECTION_NUMBER 1
 '@T6G_MB_LIB.T6G(SCH_1):PAGE325_I13@PURE_QUANTA.Q_RES(CHIPS)':
 C_PATH='@t6g_mb_lib.t6g(sch_1):page325_i13@pure_quanta.q_res(chips)',
 P_PATH='@t6g_mb_lib.t6g(sch_1):page264_i13@pure_quanta.q_res(chips)',
 PATH='I13',
 DRAWING='@T6G_MB_LIB.T6G(SCH_1):PAGE325',
 WATTAGE='1/16W',
 TOLERANCE='0.1%',
 MATERIAL='CHIP',
 PHYS_PAGE='264',
 XY='(-1475,-1950)',
 ROT='0',
 VER='2',
 PACK_TYPE='0402LF',
 LOCATION='PR3987',
 CDS_LIB='pure_quanta',
 CDS_PART_NAME='Q_RES_0402LF-2K,0.1%,1/16W,CHIP,CS22002BB07',
 ROOM='HSC BOM1',
 PART_NUMBER='CS22002BB07',
 VALUE='2K',
 PRIM_FILE='./archive_libs/logical/q_res/chips/chips.prt';

PART_NAME
 PR3988 'Q_RES_0402LF-0,5%,1/16W,CHIP,CS00002JB13':
 ROOM='HSC BOM1';

SECTION_NUMBER 1
 '@T6G_MB_LIB.T6G(SCH_1):PAGE325_I33@PURE_QUANTA.Q_RES(CHIPS)':
 C_PATH='@t6g_mb_lib.t6g(sch_1):page325_i33@pure_quanta.q_res(chips)',
 P_PATH='@t6g_mb_lib.t6g(sch_1):page264_i33@pure_quanta.q_res(chips)',
 PATH='I33',
 DRAWING='@T6G_MB_LIB.T6G(SCH_1):PAGE325',
 WATTAGE='1/16W',
 TOLERANCE='5%',
 MATERIAL='CHIP',
 PHYS_PAGE='264',
 XY='(-1325,1475)',
 ROT='0',
 VER='1',
 PACK_TYPE='0402LF',
 LOCATION='PR3988',
 CDS_LIB='pure_quanta',
 CDS_PART_NAME='Q_RES_0402LF-0,5%,1/16W,CHIP,CS00002JB13',
 ROOM='HSC BOM1',
 PART_NUMBER='CS00002JB13',
 VALUE='0',
 PRIM_FILE='./archive_libs/logical/q_res/chips/chips.prt';

PART_NAME
 PR3989 'Q_RES_0402LF-0,5%,1/16W,CHIP,CS00002JB13':
 ROOM='HSC BOM1';

SECTION_NUMBER 1
 '@T6G_MB_LIB.T6G(SCH_1):PAGE325_I16@PURE_QUANTA.Q_RES(CHIPS)':
 C_PATH='@t6g_mb_lib.t6g(sch_1):page325_i16@pure_quanta.q_res(chips)',
 P_PATH='@t6g_mb_lib.t6g(sch_1):page264_i16@pure_quanta.q_res(chips)',
 PATH='I16',
 DRAWING='@T6G_MB_LIB.T6G(SCH_1):PAGE325',
 WATTAGE='1/16W',
 TOLERANCE='5%',
 MATERIAL='CHIP',
 PHYS_PAGE='264',
 XY='(-1300,-1300)',
 ROT='0',
 VER='1',
 PACK_TYPE='0402LF',
 LOCATION='PR3989',
 CDS_LIB='pure_quanta',
 CDS_PART_NAME='Q_RES_0402LF-0,5%,1/16W,CHIP,CS00002JB13',
 ROOM='HSC BOM1',
 PART_NUMBER='CS00002JB13',
 VALUE='0',
 PRIM_FILE='./archive_libs/logical/q_res/chips/chips.prt';

PART_NAME
 PR3990 'Q_RES_0402LF-2K,0.1%,1/16W,CHIP,CS22002BB07':
 ROOM='HSC BOM1';

SECTION_NUMBER 1
 '@T6G_MB_LIB.T6G(SCH_1):PAGE325_I34@PURE_QUANTA.Q_RES(CHIPS)':
 C_PATH='@t6g_mb_lib.t6g(sch_1):page325_i34@pure_quanta.q_res(chips)',
 P_PATH='@t6g_mb_lib.t6g(sch_1):page264_i34@pure_quanta.q_res(chips)',
 PATH='I34',
 DRAWING='@T6G_MB_LIB.T6G(SCH_1):PAGE325',
 WATTAGE='1/16W',
 TOLERANCE='0.1%',
 MATERIAL='CHIP',
 PHYS_PAGE='264',
 XY='(-950,825)',
 ROT='0',
 VER='2',
 PACK_TYPE='0402LF',
 LOCATION='PR3990',
 CDS_LIB='pure_quanta',
 CDS_PART_NAME='Q_RES_0402LF-2K,0.1%,1/16W,CHIP,CS22002BB07',
 ROOM='HSC BOM1',
 PART_NUMBER='CS22002BB07',
 VALUE='2K',
 PRIM_FILE='./archive_libs/logical/q_res/chips/chips.prt';

PART_NAME
 PR3991 'Q_RES_0402LF-2K,0.1%,1/16W,CHIP,CS22002BB07':
 ROOM='HSC BOM1';

SECTION_NUMBER 1
 '@T6G_MB_LIB.T6G(SCH_1):PAGE325_I14@PURE_QUANTA.Q_RES(CHIPS)':
 C_PATH='@t6g_mb_lib.t6g(sch_1):page325_i14@pure_quanta.q_res(chips)',
 P_PATH='@t6g_mb_lib.t6g(sch_1):page264_i14@pure_quanta.q_res(chips)',
 PATH='I14',
 DRAWING='@T6G_MB_LIB.T6G(SCH_1):PAGE325',
 WATTAGE='1/16W',
 TOLERANCE='0.1%',
 MATERIAL='CHIP',
 PHYS_PAGE='264',
 XY='(-950,-1950)',
 ROT='0',
 VER='2',
 PACK_TYPE='0402LF',
 LOCATION='PR3991',
 CDS_LIB='pure_quanta',
 CDS_PART_NAME='Q_RES_0402LF-2K,0.1%,1/16W,CHIP,CS22002BB07',
 ROOM='HSC BOM1',
 PART_NUMBER='CS22002BB07',
 VALUE='2K',
 PRIM_FILE='./archive_libs/logical/q_res/chips/chips.prt';

PART_NAME
 PR3992 'Q_RES_0402LF-0,5%,1/16W,CHIP,CS00002JB13':
 ROOM='HSC BOM1';

SECTION_NUMBER 1
 '@T6G_MB_LIB.T6G(SCH_1):PAGE325_I50@PURE_QUANTA.Q_RES(CHIPS)':
 C_PATH='@t6g_mb_lib.t6g(sch_1):page325_i50@pure_quanta.q_res(chips)',
 P_PATH='@t6g_mb_lib.t6g(sch_1):page264_i50@pure_quanta.q_res(chips)',
 PATH='I50',
 DRAWING='@T6G_MB_LIB.T6G(SCH_1):PAGE325',
 WATTAGE='1/16W',
 TOLERANCE='5%',
 MATERIAL='CHIP',
 PHYS_PAGE='264',
 XY='(1500,1575)',
 ROT='0',
 VER='1',
 PACK_TYPE='0402LF',
 LOCATION='PR3992',
 CDS_LIB='pure_quanta',
 CDS_PART_NAME='Q_RES_0402LF-0,5%,1/16W,CHIP,CS00002JB13',
 ROOM='HSC BOM1',
 PART_NUMBER='CS00002JB13',
 VALUE='0',
 PRIM_FILE='./archive_libs/logical/q_res/chips/chips.prt';

PART_NAME
 PR3993 'Q_RES_0402LF-0,5%,1/16W,CHIP,CS00002JB13':
 ROOM='HSC BOM1';

SECTION_NUMBER 1
 '@T6G_MB_LIB.T6G(SCH_1):PAGE325_I49@PURE_QUANTA.Q_RES(CHIPS)':
 C_PATH='@t6g_mb_lib.t6g(sch_1):page325_i49@pure_quanta.q_res(chips)',
 P_PATH='@t6g_mb_lib.t6g(sch_1):page264_i49@pure_quanta.q_res(chips)',
 PATH='I49',
 DRAWING='@T6G_MB_LIB.T6G(SCH_1):PAGE325',
 WATTAGE='1/16W',
 TOLERANCE='5%',
 MATERIAL='CHIP',
 PHYS_PAGE='264',
 XY='(1500,1400)',
 ROT='0',
 VER='1',
 PACK_TYPE='0402LF',
 LOCATION='PR3993',
 CDS_LIB='pure_quanta',
 CDS_PART_NAME='Q_RES_0402LF-0,5%,1/16W,CHIP,CS00002JB13',
 ROOM='HSC BOM1',
 PART_NUMBER='CS00002JB13',
 VALUE='0',
 PRIM_FILE='./archive_libs/logical/q_res/chips/chips.prt';

PART_NAME
 PR3994 'Q_RES_0402LF-0,5%,1/16W,CHIP,CS00002JB13':
 ROOM='HSC BOM1';

SECTION_NUMBER 1
 '@T6G_MB_LIB.T6G(SCH_1):PAGE325_I40@PURE_QUANTA.Q_RES(CHIPS)':
 C_PATH='@t6g_mb_lib.t6g(sch_1):page325_i40@pure_quanta.q_res(chips)',
 P_PATH='@t6g_mb_lib.t6g(sch_1):page264_i40@pure_quanta.q_res(chips)',
 PATH='I40',
 DRAWING='@T6G_MB_LIB.T6G(SCH_1):PAGE325',
 WATTAGE='1/16W',
 TOLERANCE='5%',
 MATERIAL='CHIP',
 PHYS_PAGE='264',
 XY='(1500,-1200)',
 ROT='0',
 VER='1',
 PACK_TYPE='0402LF',
 LOCATION='PR3994',
 CDS_LIB='pure_quanta',
 CDS_PART_NAME='Q_RES_0402LF-0,5%,1/16W,CHIP,CS00002JB13',
 ROOM='HSC BOM1',
 PART_NUMBER='CS00002JB13',
 VALUE='0',
 PRIM_FILE='./archive_libs/logical/q_res/chips/chips.prt';

PART_NAME
 PR3995 'Q_RES_0402LF-0,5%,1/16W,CHIP,CS00002JB13':
 ROOM='HSC BOM1';

SECTION_NUMBER 1
 '@T6G_MB_LIB.T6G(SCH_1):PAGE325_I39@PURE_QUANTA.Q_RES(CHIPS)':
 C_PATH='@t6g_mb_lib.t6g(sch_1):page325_i39@pure_quanta.q_res(chips)',
 P_PATH='@t6g_mb_lib.t6g(sch_1):page264_i39@pure_quanta.q_res(chips)',
 PATH='I39',
 DRAWING='@T6G_MB_LIB.T6G(SCH_1):PAGE325',
 WATTAGE='1/16W',
 TOLERANCE='5%',
 MATERIAL='CHIP',
 PHYS_PAGE='264',
 XY='(1500,-1375)',
 ROT='0',
 VER='1',
 PACK_TYPE='0402LF',
 LOCATION='PR3995',
 CDS_LIB='pure_quanta',
 CDS_PART_NAME='Q_RES_0402LF-0,5%,1/16W,CHIP,CS00002JB13',
 ROOM='HSC BOM1',
 PART_NUMBER='CS00002JB13',
 VALUE='0',
 PRIM_FILE='./archive_libs/logical/q_res/chips/chips.prt';

PART_NAME
 PR3999 'Q_RES_0402LF-24.3K,1%,1/16W,CHIP,CS32432FB03':
 ROOM='SCM_P12V_MPS_BOM2';

SECTION_NUMBER 1
 '@T6G_MB_LIB.T6G(SCH_1):PAGE350_I11@PURE_QUANTA.Q_RES(CHIPS)':
 C_PATH='@t6g_mb_lib.t6g(sch_1):page350_i11@pure_quanta.q_res(chips)',
 P_PATH='@t6g_mb_lib.t6g(sch_1):page152_i11@pure_quanta.q_res(chips)',
 PATH='I11',
 DRAWING='@T6G_MB_LIB.T6G(SCH_1):PAGE350',
 WATTAGE='1/16W',
 TOLERANCE='1%',
 MATERIAL='CHIP',
 PHYS_PAGE='152',
 XY='(-75,11575)',
 ROT='0',
 VER='2',
 PACK_TYPE='0402LF',
 LOCATION='PR3999',
 CDS_LIB='pure_quanta',
 CDS_PART_NAME='Q_RES_0402LF-24.3K,1%,1/16W,CHIP,CS32432FB03',
 ROOM='SCM_P12V_MPS_BOM2',
 PART_NUMBER='CS32432FB03',
 VALUE='24.3K',
 PRIM_FILE='./archive_libs/logical/q_res/chips/chips.prt';

PART_NAME
 PR4000 'Q_RES_0402LF-160K,1%,1/16W,CHIP,CS41602FB05':
 ROOM='SCM_P12V_MAM_BOM1';

SECTION_NUMBER 1
 '@T6G_MB_LIB.T6G(SCH_1):PAGE350_I65@PURE_QUANTA.Q_RES(CHIPS)':
 C_PATH='@t6g_mb_lib.t6g(sch_1):page350_i65@pure_quanta.q_res(chips)',
 P_PATH='@t6g_mb_lib.t6g(sch_1):page152_i65@pure_quanta.q_res(chips)',
 PATH='I65',
 DRAWING='@T6G_MB_LIB.T6G(SCH_1):PAGE350',
 WATTAGE='1/16W',
 TOLERANCE='1%',
 MATERIAL='CHIP',
 PHYS_PAGE='152',
 XY='(675,15325)',
 ROT='0',
 VER='2',
 PACK_TYPE='0402LF',
 LOCATION='PR4000',
 CDS_LIB='pure_quanta',
 CDS_PART_NAME='Q_RES_0402LF-160K,1%,1/16W,CHIP,CS41602FB05',
 ROOM='SCM_P12V_MAM_BOM1',
 PART_NUMBER='CS41602FB05',
 VALUE='160K',
 PRIM_FILE='./archive_libs/logical/q_res/chips/chips.prt';

PART_NAME
 PR4001 'Q_RES_0402LF-6.8K,1%,1/16W,CHIP,CS26802FB02':
 ROOM='SCM_P12V_MAM_BOM1';

SECTION_NUMBER 1
 '@T6G_MB_LIB.T6G(SCH_1):PAGE350_I63@PURE_QUANTA.Q_RES(CHIPS)':
 C_PATH='@t6g_mb_lib.t6g(sch_1):page350_i63@pure_quanta.q_res(chips)',
 P_PATH='@t6g_mb_lib.t6g(sch_1):page152_i63@pure_quanta.q_res(chips)',
 PATH='I63',
 DRAWING='@T6G_MB_LIB.T6G(SCH_1):PAGE350',
 WATTAGE='1/16W',
 TOLERANCE='1%',
 MATERIAL='CHIP',
 PHYS_PAGE='152',
 XY='(675,14650)',
 ROT='0',
 VER='2',
 PACK_TYPE='0402LF',
 LOCATION='PR4001',
 CDS_LIB='pure_quanta',
 CDS_PART_NAME='Q_RES_0402LF-6.8K,1%,1/16W,CHIP,CS26802FB02',
 ROOM='SCM_P12V_MAM_BOM1',
 PART_NUMBER='CS26802FB02',
 VALUE='6.8K',
 PRIM_FILE='./archive_libs/logical/q_res/chips/chips.prt';

PART_NAME
 PR4002 'Q_RES_0402LF-15K,1%,1/16W,CHIP,CS31502FB05':
 ROOM='SCM_P12V_MAM_BOM1';

SECTION_NUMBER 1
 '@T6G_MB_LIB.T6G(SCH_1):PAGE350_I60@PURE_QUANTA.Q_RES(CHIPS)':
 C_PATH='@t6g_mb_lib.t6g(sch_1):page350_i60@pure_quanta.q_res(chips)',
 P_PATH='@t6g_mb_lib.t6g(sch_1):page152_i60@pure_quanta.q_res(chips)',
 PATH='I60',
 DRAWING='@T6G_MB_LIB.T6G(SCH_1):PAGE350',
 WATTAGE='1/16W',
 TOLERANCE='1%',
 MATERIAL='CHIP',
 PHYS_PAGE='152',
 XY='(675,14375)',
 ROT='0',
 VER='2',
 PACK_TYPE='0402LF',
 LOCATION='PR4002',
 CDS_LIB='pure_quanta',
 CDS_PART_NAME='Q_RES_0402LF-15K,1%,1/16W,CHIP,CS31502FB05',
 ROOM='SCM_P12V_MAM_BOM1',
 PART_NUMBER='CS31502FB05',
 VALUE='15K',
 PRIM_FILE='./archive_libs/logical/q_res/chips/chips.prt';

PART_NAME
 PR4003 'Q_RES_0402LF-10,1%,1/16W,CHIP,CS01002FB07':
 ROOM='SCM_P12V_MAM_BOM1';

SECTION_NUMBER 1
 '@T6G_MB_LIB.T6G(SCH_1):PAGE350_I68@PURE_QUANTA.Q_RES(CHIPS)':
 C_PATH='@t6g_mb_lib.t6g(sch_1):page350_i68@pure_quanta.q_res(chips)',
 P_PATH='@t6g_mb_lib.t6g(sch_1):page152_i68@pure_quanta.q_res(chips)',
 PATH='I68',
 DRAWING='@T6G_MB_LIB.T6G(SCH_1):PAGE350',
 WATTAGE='1/16W',
 TOLERANCE='1%',
 MATERIAL='CHIP',
 PHYS_PAGE='152',
 XY='(1000,15625)',
 ROT='0',
 VER='2',
 PACK_TYPE='0402LF',
 LOCATION='PR4003',
 CDS_LIB='pure_quanta',
 CDS_PART_NAME='Q_RES_0402LF-10,1%,1/16W,CHIP,CS01002FB07',
 ROOM='SCM_P12V_MAM_BOM1',
 PART_NUMBER='CS01002FB07',
 VALUE='10',
 PRIM_FILE='./archive_libs/logical/q_res/chips/chips.prt';

PART_NAME
 PR4004 'Q_RES_0402LF-17.8K,1%,1/16W,CHIP,CS31782FB04':
 ROOM='SCM_P12V_MAM_BOM1';

SECTION_NUMBER 1
 '@T6G_MB_LIB.T6G(SCH_1):PAGE350_I62@PURE_QUANTA.Q_RES(CHIPS)':
 C_PATH='@t6g_mb_lib.t6g(sch_1):page350_i62@pure_quanta.q_res(chips)',
 P_PATH='@t6g_mb_lib.t6g(sch_1):page152_i62@pure_quanta.q_res(chips)',
 PATH='I62',
 DRAWING='@T6G_MB_LIB.T6G(SCH_1):PAGE350',
 WATTAGE='1/16W',
 TOLERANCE='1%',
 MATERIAL='CHIP',
 PHYS_PAGE='152',
 XY='(1525,14375)',
 ROT='0',
 VER='2',
 PACK_TYPE='0402LF',
 LOCATION='PR4004',
 CDS_LIB='pure_quanta',
 CDS_PART_NAME='Q_RES_0402LF-17.8K,1%,1/16W,CHIP,CS31782FB04',
 ROOM='SCM_P12V_MAM_BOM1',
 PART_NUMBER='CS31782FB04',
 VALUE='17.8K',
 PRIM_FILE='./archive_libs/logical/q_res/chips/chips.prt';

PART_NAME
 PR4005 'Q_RES_0402LF-30.1K,1%,1/16W,CHIP,CS33012FB03':
 ROOM='SCM_P12V_MPS_BOM2';

SECTION_NUMBER 1
 '@T6G_MB_LIB.T6G(SCH_1):PAGE350_I35@PURE_QUANTA.Q_RES(CHIPS)':
 C_PATH='@t6g_mb_lib.t6g(sch_1):page350_i35@pure_quanta.q_res(chips)',
 P_PATH='@t6g_mb_lib.t6g(sch_1):page152_i35@pure_quanta.q_res(chips)',
 PATH='I35',
 DRAWING='@T6G_MB_LIB.T6G(SCH_1):PAGE350',
 WATTAGE='1/16W',
 TOLERANCE='1%',
 MATERIAL='CHIP',
 PHYS_PAGE='152',
 XY='(2250,11275)',
 ROT='0',
 VER='2',
 PACK_TYPE='0402LF',
 LOCATION='PR4005',
 CDS_LIB='pure_quanta',
 CDS_PART_NAME='Q_RES_0402LF-30.1K,1%,1/16W,CHIP,CS33012FB03',
 ROOM='SCM_P12V_MPS_BOM2',
 PART_NUMBER='CS33012FB03',
 VALUE='30.1K',
 PRIM_FILE='./archive_libs/logical/q_res/chips/chips.prt';

PART_NAME
 PR4006 'Q_RES_0402LF-100,1%,1/16W,EMPTY,CS11002FB07':
 ROOM='SCM_P12V_MPS_BOM2';

SECTION_NUMBER 1
 '@T6G_MB_LIB.T6G(SCH_1):PAGE350_I41@PURE_QUANTA.Q_RES(CHIPS)':
 C_PATH='@t6g_mb_lib.t6g(sch_1):page350_i41@pure_quanta.q_res(chips)',
 P_PATH='@t6g_mb_lib.t6g(sch_1):page152_i41@pure_quanta.q_res(chips)',
 PATH='I41',
 DRAWING='@T6G_MB_LIB.T6G(SCH_1):PAGE350',
 WATTAGE='1/16W',
 TOLERANCE='1%',
 MATERIAL='EMPTY',
 PHYS_PAGE='152',
 XY='(2625,12125)',
 ROT='0',
 VER='2',
 PACK_TYPE='0402LF',
 LOCATION='PR4006',
 CDS_LIB='pure_quanta',
 CDS_PART_NAME='Q_RES_0402LF-100,1%,1/16W,EMPTY,CS11002FB07',
 ROOM='SCM_P12V_MPS_BOM2',
 PART_NUMBER='CS11002FB07',
 VALUE='100',
 PRIM_FILE='./archive_libs/logical/q_res/chips/chips.prt';

PART_NAME
 PR4007 'Q_RES_0402LF-10K,1%,1/16W,CHIP,CS31002FB08':
 ROOM='SCM_P12V_MPS_BOM2';

SECTION_NUMBER 1
 '@T6G_MB_LIB.T6G(SCH_1):PAGE350_I40@PURE_QUANTA.Q_RES(CHIPS)':
 C_PATH='@t6g_mb_lib.t6g(sch_1):page350_i40@pure_quanta.q_res(chips)',
 P_PATH='@t6g_mb_lib.t6g(sch_1):page152_i40@pure_quanta.q_res(chips)',
 PATH='I40',
 DRAWING='@T6G_MB_LIB.T6G(SCH_1):PAGE350',
 WATTAGE='1/16W',
 TOLERANCE='1%',
 MATERIAL='CHIP',
 PHYS_PAGE='152',
 XY='(3150,11650)',
 ROT='0',
 VER='1',
 PACK_TYPE='0402LF',
 LOCATION='PR4007',
 CDS_LIB='pure_quanta',
 CDS_PART_NAME='Q_RES_0402LF-10K,1%,1/16W,CHIP,CS31002FB08',
 ROOM='SCM_P12V_MPS_BOM2',
 PART_NUMBER='CS31002FB08',
 VALUE='10K',
 PRIM_FILE='./archive_libs/logical/q_res/chips/chips.prt';

PART_NAME
 PR4008 'Q_RES_0402LF-1.33K,1%,1/16W,CHIP,CS21332FB05':
 ROOM='SCM_P12V_MAM_BOM1';

SECTION_NUMBER 1
 '@T6G_MB_LIB.T6G(SCH_1):PAGE350_I70@PURE_QUANTA.Q_RES(CHIPS)':
 C_PATH='@t6g_mb_lib.t6g(sch_1):page350_i70@pure_quanta.q_res(chips)',
 P_PATH='@t6g_mb_lib.t6g(sch_1):page152_i70@pure_quanta.q_res(chips)',
 PATH='I70',
 DRAWING='@T6G_MB_LIB.T6G(SCH_1):PAGE350',
 WATTAGE='1/16W',
 TOLERANCE='1%',
 MATERIAL='CHIP',
 PHYS_PAGE='152',
 XY='(3125,14525)',
 ROT='0',
 VER='2',
 PACK_TYPE='0402LF',
 LOCATION='PR4008',
 CDS_LIB='pure_quanta',
 CDS_PART_NAME='Q_RES_0402LF-1.33K,1%,1/16W,CHIP,CS21332FB05',
 ROOM='SCM_P12V_MAM_BOM1',
 PART_NUMBER='CS21332FB05',
 VALUE='1.33K',
 PRIM_FILE='./archive_libs/logical/q_res/chips/chips.prt';

PART_NAME
 PR4009 'Q_RES_0402LF-71.5K,1%,1/16W,EMPTY,CS37152FB05':
 ROOM='SCM_P12V_MPS_BOM2';

SECTION_NUMBER 1
 '@T6G_MB_LIB.T6G(SCH_1):PAGE350_I50@PURE_QUANTA.Q_RES(CHIPS)':
 C_PATH='@t6g_mb_lib.t6g(sch_1):page350_i50@pure_quanta.q_res(chips)',
 P_PATH='@t6g_mb_lib.t6g(sch_1):page152_i50@pure_quanta.q_res(chips)',
 PATH='I50',
 DRAWING='@T6G_MB_LIB.T6G(SCH_1):PAGE350',
 WATTAGE='1/16W',
 TOLERANCE='1%',
 MATERIAL='EMPTY',
 PHYS_PAGE='152',
 XY='(3225,12125)',
 ROT='0',
 VER='2',
 PACK_TYPE='0402LF',
 LOCATION='PR4009',
 CDS_LIB='pure_quanta',
 CDS_PART_NAME='Q_RES_0402LF-71.5K,1%,1/16W,EMPTY,CS37152FB05',
 ROOM='SCM_P12V_MPS_BOM2',
 PART_NUMBER='CS37152FB05',
 VALUE='71.5K',
 PRIM_FILE='./archive_libs/logical/q_res/chips/chips.prt';

PART_NAME
 PR4010 'Q_RES_0402LF-120K,1%,1/16W,CHIP,CS41202FB05':
 ROOM='SCM_P12V_MPS_BOM2';

SECTION_NUMBER 1
 '@T6G_MB_LIB.T6G(SCH_1):PAGE350_I51@PURE_QUANTA.Q_RES(CHIPS)':
 C_PATH='@t6g_mb_lib.t6g(sch_1):page350_i51@pure_quanta.q_res(chips)',
 P_PATH='@t6g_mb_lib.t6g(sch_1):page152_i51@pure_quanta.q_res(chips)',
 PATH='I51',
 DRAWING='@T6G_MB_LIB.T6G(SCH_1):PAGE350',
 WATTAGE='1/16W',
 TOLERANCE='1%',
 MATERIAL='CHIP',
 PHYS_PAGE='152',
 XY='(3625,12050)',
 ROT='0',
 VER='2',
 PACK_TYPE='0402LF',
 LOCATION='PR4010',
 CDS_LIB='pure_quanta',
 CDS_PART_NAME='Q_RES_0402LF-120K,1%,1/16W,CHIP,CS41202FB05',
 ROOM='SCM_P12V_MPS_BOM2',
 PART_NUMBER='CS41202FB05',
 VALUE='120K',
 PRIM_FILE='./archive_libs/logical/q_res/chips/chips.prt';

PART_NAME
 PR4011 'Q_RES_0402LF-10K,1%,1/16W,CHIP,CS31002FB08':
 ROOM='SCM_P12V_MPS_BOM2';

SECTION_NUMBER 1
 '@T6G_MB_LIB.T6G(SCH_1):PAGE350_I49@PURE_QUANTA.Q_RES(CHIPS)':
 C_PATH='@t6g_mb_lib.t6g(sch_1):page350_i49@pure_quanta.q_res(chips)',
 P_PATH='@t6g_mb_lib.t6g(sch_1):page152_i49@pure_quanta.q_res(chips)',
 PATH='I49',
 DRAWING='@T6G_MB_LIB.T6G(SCH_1):PAGE350',
 WATTAGE='1/16W',
 TOLERANCE='1%',
 MATERIAL='CHIP',
 PHYS_PAGE='152',
 XY='(3625,11625)',
 ROT='0',
 VER='2',
 PACK_TYPE='0402LF',
 LOCATION='PR4011',
 CDS_LIB='pure_quanta',
 CDS_PART_NAME='Q_RES_0402LF-10K,1%,1/16W,CHIP,CS31002FB08',
 ROOM='SCM_P12V_MPS_BOM2',
 PART_NUMBER='CS31002FB08',
 VALUE='10K',
 PRIM_FILE='./archive_libs/logical/q_res/chips/chips.prt';

PART_NAME
 PR4012 'Q_RES_0402LF-0,5%,1/16W,CHIP,CS00002JB13':
 ROOM='SCM_P12V_MAM_BOM1';

SECTION_NUMBER 1
 '@T6G_MB_LIB.T6G(SCH_1):PAGE350_I73@PURE_QUANTA.Q_RES(CHIPS)':
 C_PATH='@t6g_mb_lib.t6g(sch_1):page350_i73@pure_quanta.q_res(chips)',
 P_PATH='@t6g_mb_lib.t6g(sch_1):page152_i73@pure_quanta.q_res(chips)',
 PATH='I73',
 DRAWING='@T6G_MB_LIB.T6G(SCH_1):PAGE350',
 WATTAGE='1/16W',
 TOLERANCE='5%',
 MATERIAL='CHIP',
 PHYS_PAGE='152',
 XY='(3750,14900)',
 ROT='0',
 VER='1',
 PACK_TYPE='0402LF',
 LOCATION='PR4012',
 CDS_LIB='pure_quanta',
 CDS_PART_NAME='Q_RES_0402LF-0,5%,1/16W,CHIP,CS00002JB13',
 ROOM='SCM_P12V_MAM_BOM1',
 PART_NUMBER='CS00002JB13',
 VALUE='0',
 PRIM_FILE='./archive_libs/logical/q_res/chips/chips.prt';

PART_NAME
 PR4014 'Q_RES_0603LF-49.9,1%,1/10W,CHIP,CS04993F909':
 ROOM='SCM_P12V_MPS_BOM2';

SECTION_NUMBER 1
 '@T6G_MB_LIB.T6G(SCH_1):PAGE350_I53@PURE_QUANTA.Q_RES(CHIPS)':
 C_PATH='@t6g_mb_lib.t6g(sch_1):page350_i53@pure_quanta.q_res(chips)',
 P_PATH='@t6g_mb_lib.t6g(sch_1):page152_i53@pure_quanta.q_res(chips)',
 PATH='I53',
 DRAWING='@T6G_MB_LIB.T6G(SCH_1):PAGE350',
 WATTAGE='1/10W',
 TOLERANCE='1%',
 MATERIAL='CHIP',
 PHYS_PAGE='152',
 XY='(4150,12050)',
 ROT='0',
 VER='2',
 PACK_TYPE='0603LF',
 LOCATION='PR4014',
 CDS_LIB='pure_quanta',
 CDS_PART_NAME='Q_RES_0603LF-49.9,1%,1/10W,CHIP,CS04993F909',
 ROOM='SCM_P12V_MPS_BOM2',
 PART_NUMBER='CS04993F909',
 VALUE='49.9',
 PRIM_FILE='./archive_libs/logical/q_res/chips/chips.prt';

PART_NAME
 PR4522 'Q_RES_0402LF-10M,1%,1/16W,CHIP,CS61002FB02':
 ROOM='NIC_P12V_MAM_TIC_BOM1';

SECTION_NUMBER 1
 '@T6G_MB_LIB.T6G(SCH_1):PAGE343_I76@PURE_QUANTA.Q_RES(CHIPS)':
 C_PATH='@t6g_mb_lib.t6g(sch_1):page343_i76@pure_quanta.q_res(chips)',
 P_PATH='@t6g_mb_lib.t6g(sch_1):page140_i76@pure_quanta.q_res(chips)',
 PATH='I76',
 DRAWING='@T6G_MB_LIB.T6G(SCH_1):PAGE343',
 WATTAGE='1/16W',
 TOLERANCE='1%',
 MATERIAL='CHIP',
 PHYS_PAGE='140',
 XY='(2575,6625)',
 ROT='0',
 VER='2',
 PACK_TYPE='0402LF',
 LOCATION='PR4522',
 CDS_LIB='pure_quanta',
 CDS_PART_NAME='Q_RES_0402LF-10M,1%,1/16W,CHIP,CS61002FB02',
 ROOM='NIC_P12V_MAM_TIC_BOM1',
 PART_NUMBER='CS61002FB02',
 VALUE='10M',
 PRIM_FILE='./archive_libs/logical/q_res/chips/chips.prt';

PART_NAME
 PR4523 'Q_RES_0402LF-10M,1%,1/16W,CHIP,CS61002FB02':
 ROOM='NIC_P3V3_BOM1';

SECTION_NUMBER 1
 '@T6G_MB_LIB.T6G(SCH_1):PAGE343_I105@PURE_QUANTA.Q_RES(CHIPS)':
 C_PATH='@t6g_mb_lib.t6g(sch_1):page343_i105@pure_quanta.q_res(chips)',
 P_PATH='@t6g_mb_lib.t6g(sch_1):page140_i105@pure_quanta.q_res(chips)',
 PATH='I105',
 DRAWING='@T6G_MB_LIB.T6G(SCH_1):PAGE343',
 WATTAGE='1/16W',
 TOLERANCE='1%',
 MATERIAL='CHIP',
 PHYS_PAGE='140',
 XY='(2675,8975)',
 ROT='0',
 VER='2',
 PACK_TYPE='0402LF',
 LOCATION='PR4523',
 CDS_LIB='pure_quanta',
 CDS_PART_NAME='Q_RES_0402LF-10M,1%,1/16W,CHIP,CS61002FB02',
 ROOM='NIC_P3V3_BOM1',
 PART_NUMBER='CS61002FB02',
 VALUE='10M',
 PRIM_FILE='./archive_libs/logical/q_res/chips/chips.prt';

PART_NAME
 PR4524 'Q_RES_0402LF-10M,1%,1/16W,CHIP,CS61002FB02':
 ROOM='NIC_P12V_MAM_TIC_BOM1';

SECTION_NUMBER 1
 '@T6G_MB_LIB.T6G(SCH_1):PAGE338_I76@PURE_QUANTA.Q_RES(CHIPS)':
 C_PATH='@t6g_mb_lib.t6g(sch_1):page338_i76@pure_quanta.q_res(chips)',
 P_PATH='@t6g_mb_lib.t6g(sch_1):page134_i76@pure_quanta.q_res(chips)',
 PATH='I76',
 DRAWING='@T6G_MB_LIB.T6G(SCH_1):PAGE338',
 WATTAGE='1/16W',
 TOLERANCE='1%',
 MATERIAL='CHIP',
 PHYS_PAGE='134',
 XY='(8725,11050)',
 ROT='0',
 VER='2',
 PACK_TYPE='0402LF',
 LOCATION='PR4524',
 CDS_LIB='pure_quanta',
 CDS_PART_NAME='Q_RES_0402LF-10M,1%,1/16W,CHIP,CS61002FB02',
 ROOM='NIC_P12V_MAM_TIC_BOM1',
 PART_NUMBER='CS61002FB02',
 VALUE='10M',
 PRIM_FILE='./archive_libs/logical/q_res/chips/chips.prt';

PART_NAME
 PR4525 'Q_RES_0402LF-10M,1%,1/16W,CHIP,CS61002FB02':
 ROOM='NIC_P3V3_BOM1';

SECTION_NUMBER 1
 '@T6G_MB_LIB.T6G(SCH_1):PAGE338_I96@PURE_QUANTA.Q_RES(CHIPS)':
 C_PATH='@t6g_mb_lib.t6g(sch_1):page338_i96@pure_quanta.q_res(chips)',
 P_PATH='@t6g_mb_lib.t6g(sch_1):page134_i96@pure_quanta.q_res(chips)',
 PATH='I96',
 DRAWING='@T6G_MB_LIB.T6G(SCH_1):PAGE338',
 WATTAGE='1/16W',
 TOLERANCE='1%',
 MATERIAL='CHIP',
 PHYS_PAGE='134',
 XY='(8925,13100)',
 ROT='0',
 VER='2',
 PACK_TYPE='0402LF',
 LOCATION='PR4525',
 CDS_LIB='pure_quanta',
 CDS_PART_NAME='Q_RES_0402LF-10M,1%,1/16W,CHIP,CS61002FB02',
 ROOM='NIC_P3V3_BOM1',
 PART_NUMBER='CS61002FB02',
 VALUE='10M',
 PRIM_FILE='./archive_libs/logical/q_res/chips/chips.prt';

PART_NAME
 PR4526 'Q_RES_0402LF-10M,1%,1/16W,CHIP,CS61002FB02':
 ROOM='SCM_P12V_MAM_BOM1';

SECTION_NUMBER 1
 '@T6G_MB_LIB.T6G(SCH_1):PAGE350_I74@PURE_QUANTA.Q_RES(CHIPS)':
 C_PATH='@t6g_mb_lib.t6g(sch_1):page350_i74@pure_quanta.q_res(chips)',
 P_PATH='@t6g_mb_lib.t6g(sch_1):page152_i74@pure_quanta.q_res(chips)',
 PATH='I74',
 DRAWING='@T6G_MB_LIB.T6G(SCH_1):PAGE350',
 WATTAGE='1/16W',
 TOLERANCE='1%',
 MATERIAL='CHIP',
 PHYS_PAGE='152',
 XY='(3400,15250)',
 ROT='0',
 VER='2',
 PACK_TYPE='0402LF',
 LOCATION='PR4526',
 CDS_LIB='pure_quanta',
 CDS_PART_NAME='Q_RES_0402LF-10M,1%,1/16W,CHIP,CS61002FB02',
 ROOM='SCM_P12V_MAM_BOM1',
 PART_NUMBER='CS61002FB02',
 VALUE='10M',
 PRIM_FILE='./archive_libs/logical/q_res/chips/chips.prt';

PART_NAME
 PR4527 'Q_RES_0402LF-10M,1%,1/16W,CHIP,CS61002FB02':
 ROOM='E1S_P3V3_BOM1';

SECTION_NUMBER 1
 '@T6G_MB_LIB.T6G(SCH_1):PAGE324_I47@PURE_QUANTA.Q_RES(CHIPS)':
 C_PATH='@t6g_mb_lib.t6g(sch_1):page324_i47@pure_quanta.q_res(chips)',
 P_PATH='@t6g_mb_lib.t6g(sch_1):page146_i47@pure_quanta.q_res(chips)',
 PATH='I47',
 DRAWING='@T6G_MB_LIB.T6G(SCH_1):PAGE324',
 WATTAGE='1/16W',
 TOLERANCE='1%',
 MATERIAL='CHIP',
 PHYS_PAGE='146',
 XY='(2550,-1725)',
 ROT='0',
 VER='2',
 PACK_TYPE='0402LF',
 LOCATION='PR4527',
 CDS_LIB='pure_quanta',
 CDS_PART_NAME='Q_RES_0402LF-10M,1%,1/16W,CHIP,CS61002FB02',
 ROOM='E1S_P3V3_BOM1',
 PART_NUMBER='CS61002FB02',
 VALUE='10M',
 PRIM_FILE='./archive_libs/logical/q_res/chips/chips.prt';

PART_NAME
 PR4528 'Q_RES_0402LF-10M,1%,1/16W,CHIP,CS61002FB02':
 ROOM='E1S_P12V_MAM_TIC_BOM1';

SECTION_NUMBER 1
 '@T6G_MB_LIB.T6G(SCH_1):PAGE324_I73@PURE_QUANTA.Q_RES(CHIPS)':
 C_PATH='@t6g_mb_lib.t6g(sch_1):page324_i73@pure_quanta.q_res(chips)',
 P_PATH='@t6g_mb_lib.t6g(sch_1):page146_i73@pure_quanta.q_res(chips)',
 PATH='I73',
 DRAWING='@T6G_MB_LIB.T6G(SCH_1):PAGE324',
 WATTAGE='1/16W',
 TOLERANCE='1%',
 MATERIAL='CHIP',
 PHYS_PAGE='146',
 XY='(2600,1000)',
 ROT='0',
 VER='2',
 PACK_TYPE='0402LF',
 LOCATION='PR4528',
 CDS_LIB='pure_quanta',
 CDS_PART_NAME='Q_RES_0402LF-10M,1%,1/16W,CHIP,CS61002FB02',
 ROOM='E1S_P12V_MAM_TIC_BOM1',
 PART_NUMBER='CS61002FB02',
 VALUE='10M',
 PRIM_FILE='./archive_libs/logical/q_res/chips/chips.prt';

PART_NAME
 PR4540 'Q_RES_0402LF-20K,1%,1/16W,CHIP,CS32002FB06':
 ROOM='SCM_P12V_MPS_BOM2';

SECTION_NUMBER 1
 '@T6G_MB_LIB.T6G(SCH_1):PAGE350_I12@PURE_QUANTA.Q_RES(CHIPS)':
 C_PATH='@t6g_mb_lib.t6g(sch_1):page350_i12@pure_quanta.q_res(chips)',
 P_PATH='@t6g_mb_lib.t6g(sch_1):page152_i12@pure_quanta.q_res(chips)',
 PATH='I12',
 DRAWING='@T6G_MB_LIB.T6G(SCH_1):PAGE350',
 WATTAGE='1/16W',
 TOLERANCE='1%',
 MATERIAL='CHIP',
 PHYS_PAGE='152',
 XY='(350,11550)',
 ROT='0',
 VER='2',
 PACK_TYPE='0402LF',
 LOCATION='PR4540',
 CDS_LIB='pure_quanta',
 CDS_PART_NAME='Q_RES_0402LF-20K,1%,1/16W,CHIP,CS32002FB06',
 ROOM='SCM_P12V_MPS_BOM2',
 PART_NUMBER='CS32002FB06',
 VALUE='20K',
 PRIM_FILE='./archive_libs/logical/q_res/chips/chips.prt';

PART_NAME
 PR4541 'Q_RES_0402LF-20K,1%,1/16W,CHIP,CS32002FB06':
 ROOM='E1S_P12V_MPS_MAM_BOM2';

SECTION_NUMBER 1
 '@T6G_MB_LIB.T6G(SCH_1):PAGE323_I18@PURE_QUANTA.Q_RES(CHIPS)':
 C_PATH='@t6g_mb_lib.t6g(sch_1):page323_i18@pure_quanta.q_res(chips)',
 P_PATH='@t6g_mb_lib.t6g(sch_1):page147_i18@pure_quanta.q_res(chips)',
 PATH='I18',
 DRAWING='@T6G_MB_LIB.T6G(SCH_1):PAGE323',
 WATTAGE='1/16W',
 TOLERANCE='1%',
 MATERIAL='CHIP',
 PHYS_PAGE='147',
 XY='(-1275,850)',
 ROT='0',
 VER='2',
 PACK_TYPE='0402LF',
 LOCATION='PR4541',
 CDS_LIB='pure_quanta',
 CDS_PART_NAME='Q_RES_0402LF-20K,1%,1/16W,CHIP,CS32002FB06',
 ROOM='E1S_P12V_MPS_MAM_BOM2',
 PART_NUMBER='CS32002FB06',
 VALUE='20K',
 PRIM_FILE='./archive_libs/logical/q_res/chips/chips.prt';

PART_NAME
 PR5481 'Q_RES_0402LF-4.53K,1%,1/16W,CHIP,CS24532FB03':
 ROOM='NIC_P3V3_BOM1';

SECTION_NUMBER 1
 '@T6G_MB_LIB.T6G(SCH_1):PAGE338_I95@PURE_QUANTA.Q_RES(CHIPS)':
 C_PATH='@t6g_mb_lib.t6g(sch_1):page338_i95@pure_quanta.q_res(chips)',
 P_PATH='@t6g_mb_lib.t6g(sch_1):page134_i95@pure_quanta.q_res(chips)',
 PATH='I95',
 DRAWING='@T6G_MB_LIB.T6G(SCH_1):PAGE338',
 WATTAGE='1/16W',
 TOLERANCE='1%',
 MATERIAL='CHIP',
 PHYS_PAGE='134',
 XY='(8700,12425)',
 ROT='0',
 VER='2',
 PACK_TYPE='0402LF',
 LOCATION='PR5481',
 CDS_LIB='pure_quanta',
 CDS_PART_NAME='Q_RES_0402LF-4.53K,1%,1/16W,CHIP,CS24532FB03',
 ROOM='NIC_P3V3_BOM1',
 PART_NUMBER='CS24532FB03',
 VALUE='4.53K',
 PRIM_FILE='./archive_libs/logical/q_res/chips/chips.prt';

PART_NAME
 PR5484 'Q_RES_0402LF-30.1K,1%,1/16W,CHIP,CS33012FB03':
 ROOM='NIC_P12V_MAM_TIC_BOM1';

SECTION_NUMBER 1
 '@T6G_MB_LIB.T6G(SCH_1):PAGE338_I48@PURE_QUANTA.Q_RES(CHIPS)':
 C_PATH='@t6g_mb_lib.t6g(sch_1):page338_i48@pure_quanta.q_res(chips)',
 P_PATH='@t6g_mb_lib.t6g(sch_1):page134_i48@pure_quanta.q_res(chips)',
 PATH='I48',
 DRAWING='@T6G_MB_LIB.T6G(SCH_1):PAGE338',
 WATTAGE='1/16W',
 TOLERANCE='1%',
 MATERIAL='CHIP',
 PHYS_PAGE='134',
 XY='(6875,10225)',
 ROT='0',
 VER='2',
 PACK_TYPE='0402LF',
 LOCATION='PR5484',
 CDS_LIB='pure_quanta',
 CDS_PART_NAME='Q_RES_0402LF-30.1K,1%,1/16W,CHIP,CS33012FB03',
 ROOM='NIC_P12V_MAM_TIC_BOM1',
 PART_NUMBER='CS33012FB03',
 VALUE='30.1K',
 PRIM_FILE='./archive_libs/logical/q_res/chips/chips.prt';

PART_NAME
 PR6000 'Q_RES_0402LF-0,5%,1/16W,CHIP,CS00002JB13':;

SECTION_NUMBER 1
 '@T6G_MB_LIB.T6G(SCH_1):PAGE167_I17@PURE_QUANTA.Q_RES(CHIPS)':
 C_PATH='@t6g_mb_lib.t6g(sch_1):page167_i17@pure_quanta.q_res(chips)',
 P_PATH='@t6g_mb_lib.t6g(sch_1):page192_i17@pure_quanta.q_res(chips)',
 PATH='I17',
 DRAWING='@T6G_MB_LIB.T6G(SCH_1):PAGE167',
 WATTAGE='1/16W',
 TOLERANCE='5%',
 MATERIAL='CHIP',
 PHYS_PAGE='192',
 XY='(-7950,3400)',
 ROT='0',
 VER='1',
 PACK_TYPE='0402LF',
 LOCATION='PR6000',
 CDS_LIB='pure_quanta',
 CDS_PART_NAME='Q_RES_0402LF-0,5%,1/16W,CHIP,CS00002JB13',
 PART_NUMBER='CS00002JB13',
 VALUE='0',
 PRIM_FILE='./archive_libs/logical/q_res/chips/chips.prt';

PART_NAME
 PR6001 'Q_SP_RES4P-0.0003,1%,4W,SMLF,CHIP,SP_CS0000FFT09':
 ROOM='HSC BOM2';

SECTION_NUMBER 1
 '@T6G_MB_LIB.T6G(SCH_1):PAGE302_I55@PURE_QUANTA.Q_SP_RES4P(CHIPS)':
 C_PATH='@t6g_mb_lib.t6g(sch_1):page302_i55@pure_quanta.q_sp_res4p(chips)',
 P_PATH='@t6g_mb_lib.t6g(sch_1):page266_i55@pure_quanta.q_sp_res4p(chips)',
 PATH='I55',
 DRAWING='@T6G_MB_LIB.T6G(SCH_1):PAGE302',
 SEC_TYPE='',
 WATTAGE='4W',
 TOLERANCE='1%',
 PART_TYPE='SMLF',
 MATERIAL='CHIP',
 PHYS_PAGE='266',
 XY='(-3500,4950)',
 ROT='0',
 VER='1',
 LOCATION='PR6001',
 SEC='1',
 CDS_LIB='pure_quanta',
 CDS_PART_NAME='Q_SP_RES4P-0.0003,1%,4W,SMLF,CHIP,SP_CS0000FFT09',
 ROOM='HSC BOM2',
 PART_NUMBER='SP_CS0000FFT09',
 VALUE='0.0003',
 PRIM_FILE='./archive_libs/logical/q_sp_res4p/chips/chips.prt';

PART_NAME
 PR6002 'Q_SP_RES4P-0.003,1%,2W,SMLF,CHIP,SP_CS+003AFR00_1':
 ROOM='HSC BOM2';

SECTION_NUMBER 1
 '@T6G_MB_LIB.T6G(SCH_1):PAGE302_I81@PURE_QUANTA.Q_SP_RES4P(CHIPS)':
 C_PATH='@t6g_mb_lib.t6g(sch_1):page302_i81@pure_quanta.q_sp_res4p(chips)',
 P_PATH='@t6g_mb_lib.t6g(sch_1):page266_i81@pure_quanta.q_sp_res4p(chips)',
 PATH='I81',
 DRAWING='@T6G_MB_LIB.T6G(SCH_1):PAGE302',
 SEC_TYPE='',
 WATTAGE='2W',
 TOLERANCE='1%',
 PART_TYPE='SMLF',
 MATERIAL='CHIP',
 PHYS_PAGE='266',
 XY='(-3500,5250)',
 ROT='6',
 VER='1',
 LOCATION='PR6002',
 SEC='1',
 CDS_LIB='pure_quanta',
 CDS_PART_NAME='Q_SP_RES4P-0.003,1%,2W,SMLF,CHIP,SP_CS+003AFR00_1',
 ROOM='HSC BOM2',
 PART_NUMBER='SP_CS+003AFR00_1',
 VALUE='0.003',
 PRIM_FILE='./archive_libs/logical/q_sp_res4p/chips/chips.prt';

PART_NAME
 PR6003 'Q_RES_0402LF-10K,1%,1/16W,CHIP,CS31002FB08':;

SECTION_NUMBER 1
 '@T6G_MB_LIB.T6G(SCH_1):PAGE315_I12@PURE_QUANTA.Q_RES(CHIPS)':
 C_PATH='@t6g_mb_lib.t6g(sch_1):page315_i12@pure_quanta.q_res(chips)',
 P_PATH='@t6g_mb_lib.t6g(sch_1):page269_i12@pure_quanta.q_res(chips)',
 PATH='I12',
 DRAWING='@T6G_MB_LIB.T6G(SCH_1):PAGE315',
 WATTAGE='1/16W',
 TOLERANCE='1%',
 MATERIAL='CHIP',
 PHYS_PAGE='269',
 XY='(-2025,975)',
 ROT='0',
 VER='2',
 PACK_TYPE='0402LF',
 LOCATION='PR6003',
 CDS_LIB='pure_quanta',
 CDS_PART_NAME='Q_RES_0402LF-10K,1%,1/16W,CHIP,CS31002FB08',
 PART_NUMBER='CS31002FB08',
 VALUE='10K',
 PRIM_FILE='./archive_libs/logical/q_res/chips/chips.prt';

PART_NAME
 PR6004 'Q_RES_0402LF-11.5K,1%,1/16W,CHIP,CS31152FB03':;

SECTION_NUMBER 1
 '@T6G_MB_LIB.T6G(SCH_1):PAGE380_I6@PURE_QUANTA.Q_RES(CHIPS)':
 C_PATH='@t6g_mb_lib.t6g(sch_1):page380_i6@pure_quanta.q_res(chips)',
 P_PATH='@t6g_mb_lib.t6g(sch_1):page270_i6@pure_quanta.q_res(chips)',
 PATH='I6',
 DRAWING='@T6G_MB_LIB.T6G(SCH_1):PAGE380',
 WATTAGE='1/16W',
 TOLERANCE='1%',
 MATERIAL='CHIP',
 PHYS_PAGE='270',
 XY='(-5600,950)',
 ROT='0',
 VER='2',
 PACK_TYPE='0402LF',
 LOCATION='PR6004',
 CDS_LIB='pure_quanta',
 CDS_PART_NAME='Q_RES_0402LF-11.5K,1%,1/16W,CHIP,CS31152FB03',
 PART_NUMBER='CS31152FB03',
 VALUE='11.5K',
 PRIM_FILE='./archive_libs/logical/q_res/chips/chips.prt';

PART_NAME
 PR6005 'Q_RES_0402LF-60.4K,1%,1/16W,CHIP,CS36042FB04':;

SECTION_NUMBER 1
 '@T6G_MB_LIB.T6G(SCH_1):PAGE380_I11@PURE_QUANTA.Q_RES(CHIPS)':
 C_PATH='@t6g_mb_lib.t6g(sch_1):page380_i11@pure_quanta.q_res(chips)',
 P_PATH='@t6g_mb_lib.t6g(sch_1):page270_i11@pure_quanta.q_res(chips)',
 PATH='I11',
 DRAWING='@T6G_MB_LIB.T6G(SCH_1):PAGE380',
 WATTAGE='1/16W',
 TOLERANCE='1%',
 MATERIAL='CHIP',
 PHYS_PAGE='270',
 XY='(-5875,1800)',
 ROT='0',
 VER='1',
 PACK_TYPE='0402LF',
 LOCATION='PR6005',
 CDS_LIB='pure_quanta',
 CDS_PART_NAME='Q_RES_0402LF-60.4K,1%,1/16W,CHIP,CS36042FB04',
 PART_NUMBER='CS36042FB04',
 VALUE='60.4K',
 PRIM_FILE='./archive_libs/logical/q_res/chips/chips.prt';

PART_NAME
 PR6006 'Q_RES_0402LF-60.4K,1%,1/16W,CHIP,CS36042FB04':;

SECTION_NUMBER 1
 '@T6G_MB_LIB.T6G(SCH_1):PAGE315_I15@PURE_QUANTA.Q_RES(CHIPS)':
 C_PATH='@t6g_mb_lib.t6g(sch_1):page315_i15@pure_quanta.q_res(chips)',
 P_PATH='@t6g_mb_lib.t6g(sch_1):page269_i15@pure_quanta.q_res(chips)',
 PATH='I15',
 DRAWING='@T6G_MB_LIB.T6G(SCH_1):PAGE315',
 WATTAGE='1/16W',
 TOLERANCE='1%',
 MATERIAL='CHIP',
 PHYS_PAGE='269',
 XY='(-2300,1825)',
 ROT='0',
 VER='1',
 PACK_TYPE='0402LF',
 LOCATION='PR6006',
 CDS_LIB='pure_quanta',
 CDS_PART_NAME='Q_RES_0402LF-60.4K,1%,1/16W,CHIP,CS36042FB04',
 PART_NUMBER='CS36042FB04',
 VALUE='60.4K',
 PRIM_FILE='./archive_libs/logical/q_res/chips/chips.prt';

PART_NAME
 PR6007 'Q_RES_0402LF-20K,1%,1/16W,CHIP,CS32002FB06':;

SECTION_NUMBER 1
 '@T6G_MB_LIB.T6G(SCH_1):PAGE315_I28@PURE_QUANTA.Q_RES(CHIPS)':
 C_PATH='@t6g_mb_lib.t6g(sch_1):page315_i28@pure_quanta.q_res(chips)',
 P_PATH='@t6g_mb_lib.t6g(sch_1):page269_i28@pure_quanta.q_res(chips)',
 PATH='I28',
 DRAWING='@T6G_MB_LIB.T6G(SCH_1):PAGE315',
 WATTAGE='1/16W',
 TOLERANCE='1%',
 MATERIAL='CHIP',
 PHYS_PAGE='269',
 XY='(1525,1250)',
 ROT='0',
 VER='1',
 PACK_TYPE='0402LF',
 LOCATION='PR6007',
 CDS_LIB='pure_quanta',
 CDS_PART_NAME='Q_RES_0402LF-20K,1%,1/16W,CHIP,CS32002FB06',
 PART_NUMBER='CS32002FB06',
 VALUE='20K',
 PRIM_FILE='./archive_libs/logical/q_res/chips/chips.prt';

PART_NAME
 PR6008 'Q_RES_0402LF-10K,1%,1/16W,CHIP,CS31002FB08':;

SECTION_NUMBER 1
 '@T6G_MB_LIB.T6G(SCH_1):PAGE380_I27@PURE_QUANTA.Q_RES(CHIPS)':
 C_PATH='@t6g_mb_lib.t6g(sch_1):page380_i27@pure_quanta.q_res(chips)',
 P_PATH='@t6g_mb_lib.t6g(sch_1):page270_i27@pure_quanta.q_res(chips)',
 PATH='I27',
 DRAWING='@T6G_MB_LIB.T6G(SCH_1):PAGE380',
 WATTAGE='1/16W',
 TOLERANCE='1%',
 MATERIAL='CHIP',
 PHYS_PAGE='270',
 XY='(-2050,1225)',
 ROT='0',
 VER='1',
 PACK_TYPE='0402LF',
 LOCATION='PR6008',
 CDS_LIB='pure_quanta',
 CDS_PART_NAME='Q_RES_0402LF-10K,1%,1/16W,CHIP,CS31002FB08',
 PART_NUMBER='CS31002FB08',
 VALUE='10K',
 PRIM_FILE='./archive_libs/logical/q_res/chips/chips.prt';

PART_NAME
 PR6010 'Q_RES_0402LF-10K,1%,1/16W,CHIP,CS31002FB08':;

SECTION_NUMBER 1
 '@T6G_MB_LIB.T6G(SCH_1):PAGE315_I23@PURE_QUANTA.Q_RES(CHIPS)':
 C_PATH='@t6g_mb_lib.t6g(sch_1):page315_i23@pure_quanta.q_res(chips)',
 P_PATH='@t6g_mb_lib.t6g(sch_1):page269_i23@pure_quanta.q_res(chips)',
 PATH='I23',
 DRAWING='@T6G_MB_LIB.T6G(SCH_1):PAGE315',
 WATTAGE='1/16W',
 TOLERANCE='1%',
 MATERIAL='CHIP',
 PHYS_PAGE='269',
 XY='(475,900)',
 ROT='0',
 VER='2',
 PACK_TYPE='0402LF',
 LOCATION='PR6010',
 CDS_LIB='pure_quanta',
 CDS_PART_NAME='Q_RES_0402LF-10K,1%,1/16W,CHIP,CS31002FB08',
 PART_NUMBER='CS31002FB08',
 VALUE='10K',
 PRIM_FILE='./archive_libs/logical/q_res/chips/chips.prt';

PART_NAME
 PR6011 'Q_RES_0402LF-10K,1%,1/16W,CHIP,CS31002FB08':;

SECTION_NUMBER 1
 '@T6G_MB_LIB.T6G(SCH_1):PAGE380_I21@PURE_QUANTA.Q_RES(CHIPS)':
 C_PATH='@t6g_mb_lib.t6g(sch_1):page380_i21@pure_quanta.q_res(chips)',
 P_PATH='@t6g_mb_lib.t6g(sch_1):page270_i21@pure_quanta.q_res(chips)',
 PATH='I21',
 DRAWING='@T6G_MB_LIB.T6G(SCH_1):PAGE380',
 WATTAGE='1/16W',
 TOLERANCE='1%',
 MATERIAL='CHIP',
 PHYS_PAGE='270',
 XY='(-3100,875)',
 ROT='0',
 VER='2',
 PACK_TYPE='0402LF',
 LOCATION='PR6011',
 CDS_LIB='pure_quanta',
 CDS_PART_NAME='Q_RES_0402LF-10K,1%,1/16W,CHIP,CS31002FB08',
 PART_NUMBER='CS31002FB08',
 VALUE='10K',
 PRIM_FILE='./archive_libs/logical/q_res/chips/chips.prt';

PART_NAME
 PR6500 'Q_RES_0402LF-0,5%,1/16W,CHIP,CS00002JB13':;

SECTION_NUMBER 1
 '@T6G_MB_LIB.T6G(SCH_1):PAGE469_I21@PURE_QUANTA.Q_RES(CHIPS)':
 C_PATH='@t6g_mb_lib.t6g(sch_1):page469_i21@pure_quanta.q_res(chips)',
 P_PATH='@t6g_mb_lib.t6g(sch_1):page360_i21@pure_quanta.q_res(chips)',
 PATH='I21',
 DRAWING='@T6G_MB_LIB.T6G(SCH_1):PAGE469',
 WATTAGE='1/16W',
 TOLERANCE='5%',
 MATERIAL='CHIP',
 PHYS_PAGE='360',
 XY='(-6950,3200)',
 ROT='0',
 VER='1',
 PACK_TYPE='0402LF',
 LOCATION='PR6500',
 CDS_LIB='pure_quanta',
 CDS_PART_NAME='Q_RES_0402LF-0,5%,1/16W,CHIP,CS00002JB13',
 PART_NUMBER='CS00002JB13',
 VALUE='0',
 PRIM_FILE='./archive_libs/logical/q_res/chips/chips.prt';

PART_NAME
 PR6501 'Q_RES_0402LF-0,5%,1/16W,CHIP,CS00002JB13':;

SECTION_NUMBER 1
 '@T6G_MB_LIB.T6G(SCH_1):PAGE469_I13@PURE_QUANTA.Q_RES(CHIPS)':
 C_PATH='@t6g_mb_lib.t6g(sch_1):page469_i13@pure_quanta.q_res(chips)',
 P_PATH='@t6g_mb_lib.t6g(sch_1):page360_i13@pure_quanta.q_res(chips)',
 PATH='I13',
 DRAWING='@T6G_MB_LIB.T6G(SCH_1):PAGE469',
 WATTAGE='1/16W',
 TOLERANCE='5%',
 MATERIAL='CHIP',
 PHYS_PAGE='360',
 XY='(-7450,2800)',
 ROT='0',
 VER='2',
 PACK_TYPE='0402LF',
 LOCATION='PR6501',
 CDS_LIB='pure_quanta',
 CDS_PART_NAME='Q_RES_0402LF-0,5%,1/16W,CHIP,CS00002JB13',
 PART_NUMBER='CS00002JB13',
 VALUE='0',
 PRIM_FILE='./archive_libs/logical/q_res/chips/chips.prt';

PART_NAME
 PR6502 'Q_RES_0402LF-7.15K,1%,1/16W,CHIP,CS27152FB03':;

SECTION_NUMBER 1
 '@T6G_MB_LIB.T6G(SCH_1):PAGE469_I20@PURE_QUANTA.Q_RES(CHIPS)':
 C_PATH='@t6g_mb_lib.t6g(sch_1):page469_i20@pure_quanta.q_res(chips)',
 P_PATH='@t6g_mb_lib.t6g(sch_1):page360_i20@pure_quanta.q_res(chips)',
 PATH='I20',
 DRAWING='@T6G_MB_LIB.T6G(SCH_1):PAGE469',
 SEC_TYPE='0402LF',
 WATTAGE='1/16W',
 TOLERANCE='1%',
 MATERIAL='CHIP',
 PHYS_PAGE='360',
 XY='(-6575,2375)',
 ROT='0',
 VER='2',
 PACK_TYPE='0402LF',
 LOCATION='PR6502',
 SEC='1',
 CDS_LIB='pure_quanta',
 CDS_PART_NAME='Q_RES_0402LF-7.15K,1%,1/16W,CHIP,CS27152FB03',
 PART_NUMBER='CS27152FB03',
 VALUE='7.15K',
 PRIM_FILE='./archive_libs/logical/q_res/chips/chips.prt';

PART_NAME
 PR6505 'Q_RES_0402LF-20K,1%,1/16W,CHIP,CS32002FB06':;

SECTION_NUMBER 1
 '@T6G_MB_LIB.T6G(SCH_1):PAGE469_I35@PURE_QUANTA.Q_RES(CHIPS)':
 C_PATH='@t6g_mb_lib.t6g(sch_1):page469_i35@pure_quanta.q_res(chips)',
 P_PATH='@t6g_mb_lib.t6g(sch_1):page360_i35@pure_quanta.q_res(chips)',
 PATH='I35',
 DRAWING='@T6G_MB_LIB.T6G(SCH_1):PAGE469',
 WATTAGE='1/16W',
 TOLERANCE='1%',
 MATERIAL='CHIP',
 PHYS_PAGE='360',
 XY='(-3450,2950)',
 ROT='0',
 VER='1',
 PACK_TYPE='0402LF',
 LOCATION='PR6505',
 CDS_LIB='pure_quanta',
 CDS_PART_NAME='Q_RES_0402LF-20K,1%,1/16W,CHIP,CS32002FB06',
 PART_NUMBER='CS32002FB06',
 VALUE='20K',
 PRIM_FILE='./archive_libs/logical/q_res/chips/chips.prt';

PART_NAME
 PR6507 'Q_RES_0402LF-10K,1%,1/16W,CHIP,CS31002FB08':;

SECTION_NUMBER 1
 '@T6G_MB_LIB.T6G(SCH_1):PAGE469_I33@PURE_QUANTA.Q_RES(CHIPS)':
 C_PATH='@t6g_mb_lib.t6g(sch_1):page469_i33@pure_quanta.q_res(chips)',
 P_PATH='@t6g_mb_lib.t6g(sch_1):page360_i33@pure_quanta.q_res(chips)',
 PATH='I33',
 DRAWING='@T6G_MB_LIB.T6G(SCH_1):PAGE469',
 WATTAGE='1/16W',
 TOLERANCE='1%',
 MATERIAL='CHIP',
 PHYS_PAGE='360',
 XY='(-4025,2425)',
 ROT='0',
 VER='2',
 PACK_TYPE='0402LF',
 LOCATION='PR6507',
 CDS_LIB='pure_quanta',
 CDS_PART_NAME='Q_RES_0402LF-10K,1%,1/16W,CHIP,CS31002FB08',
 PART_NUMBER='CS31002FB08',
 VALUE='10K',
 PRIM_FILE='./archive_libs/logical/q_res/chips/chips.prt';

PART_NAME
 PR6520 'Q_RES_0402LF-0,5%,1/16W,CHIP,CS00002JB13':;

SECTION_NUMBER 1
 '@T6G_MB_LIB.T6G(SCH_1):PAGE470_I21@PURE_QUANTA.Q_RES(CHIPS)':
 C_PATH='@t6g_mb_lib.t6g(sch_1):page470_i21@pure_quanta.q_res(chips)',
 P_PATH='@t6g_mb_lib.t6g(sch_1):page361_i21@pure_quanta.q_res(chips)',
 PATH='I21',
 DRAWING='@T6G_MB_LIB.T6G(SCH_1):PAGE470',
 WATTAGE='1/16W',
 TOLERANCE='5%',
 MATERIAL='CHIP',
 PHYS_PAGE='361',
 XY='(-7000,3250)',
 ROT='0',
 VER='1',
 PACK_TYPE='0402LF',
 LOCATION='PR6520',
 CDS_LIB='pure_quanta',
 CDS_PART_NAME='Q_RES_0402LF-0,5%,1/16W,CHIP,CS00002JB13',
 PART_NUMBER='CS00002JB13',
 VALUE='0',
 PRIM_FILE='./archive_libs/logical/q_res/chips/chips.prt';

PART_NAME
 PR6521 'Q_RES_0402LF-0,5%,1/16W,CHIP,CS00002JB13':;

SECTION_NUMBER 1
 '@T6G_MB_LIB.T6G(SCH_1):PAGE470_I13@PURE_QUANTA.Q_RES(CHIPS)':
 C_PATH='@t6g_mb_lib.t6g(sch_1):page470_i13@pure_quanta.q_res(chips)',
 P_PATH='@t6g_mb_lib.t6g(sch_1):page361_i13@pure_quanta.q_res(chips)',
 PATH='I13',
 DRAWING='@T6G_MB_LIB.T6G(SCH_1):PAGE470',
 WATTAGE='1/16W',
 TOLERANCE='5%',
 MATERIAL='CHIP',
 PHYS_PAGE='361',
 XY='(-7500,2850)',
 ROT='0',
 VER='2',
 PACK_TYPE='0402LF',
 LOCATION='PR6521',
 CDS_LIB='pure_quanta',
 CDS_PART_NAME='Q_RES_0402LF-0,5%,1/16W,CHIP,CS00002JB13',
 PART_NUMBER='CS00002JB13',
 VALUE='0',
 PRIM_FILE='./archive_libs/logical/q_res/chips/chips.prt';

PART_NAME
 PR6522 'Q_RES_0402LF-7.15K,1%,1/16W,CHIP,CS27152FB03':;

SECTION_NUMBER 1
 '@T6G_MB_LIB.T6G(SCH_1):PAGE470_I20@PURE_QUANTA.Q_RES(CHIPS)':
 C_PATH='@t6g_mb_lib.t6g(sch_1):page470_i20@pure_quanta.q_res(chips)',
 P_PATH='@t6g_mb_lib.t6g(sch_1):page361_i20@pure_quanta.q_res(chips)',
 PATH='I20',
 DRAWING='@T6G_MB_LIB.T6G(SCH_1):PAGE470',
 SEC_TYPE='0402LF',
 WATTAGE='1/16W',
 TOLERANCE='1%',
 MATERIAL='CHIP',
 PHYS_PAGE='361',
 XY='(-6625,2425)',
 ROT='0',
 VER='2',
 PACK_TYPE='0402LF',
 LOCATION='PR6522',
 SEC='1',
 CDS_LIB='pure_quanta',
 CDS_PART_NAME='Q_RES_0402LF-7.15K,1%,1/16W,CHIP,CS27152FB03',
 PART_NUMBER='CS27152FB03',
 VALUE='7.15K',
 PRIM_FILE='./archive_libs/logical/q_res/chips/chips.prt';

PART_NAME
 PR6524 'Q_RES_0402LF-20K,1%,1/16W,CHIP,CS32002FB06':;

SECTION_NUMBER 1
 '@T6G_MB_LIB.T6G(SCH_1):PAGE470_I34@PURE_QUANTA.Q_RES(CHIPS)':
 C_PATH='@t6g_mb_lib.t6g(sch_1):page470_i34@pure_quanta.q_res(chips)',
 P_PATH='@t6g_mb_lib.t6g(sch_1):page361_i34@pure_quanta.q_res(chips)',
 PATH='I34',
 DRAWING='@T6G_MB_LIB.T6G(SCH_1):PAGE470',
 WATTAGE='1/16W',
 TOLERANCE='1%',
 MATERIAL='CHIP',
 PHYS_PAGE='361',
 XY='(-3500,3000)',
 ROT='0',
 VER='1',
 PACK_TYPE='0402LF',
 LOCATION='PR6524',
 CDS_LIB='pure_quanta',
 CDS_PART_NAME='Q_RES_0402LF-20K,1%,1/16W,CHIP,CS32002FB06',
 PART_NUMBER='CS32002FB06',
 VALUE='20K',
 PRIM_FILE='./archive_libs/logical/q_res/chips/chips.prt';

PART_NAME
 PR6526 'Q_RES_0402LF-10K,1%,1/16W,CHIP,CS31002FB08':;

SECTION_NUMBER 1
 '@T6G_MB_LIB.T6G(SCH_1):PAGE470_I32@PURE_QUANTA.Q_RES(CHIPS)':
 C_PATH='@t6g_mb_lib.t6g(sch_1):page470_i32@pure_quanta.q_res(chips)',
 P_PATH='@t6g_mb_lib.t6g(sch_1):page361_i32@pure_quanta.q_res(chips)',
 PATH='I32',
 DRAWING='@T6G_MB_LIB.T6G(SCH_1):PAGE470',
 WATTAGE='1/16W',
 TOLERANCE='1%',
 MATERIAL='CHIP',
 PHYS_PAGE='361',
 XY='(-4075,2475)',
 ROT='0',
 VER='2',
 PACK_TYPE='0402LF',
 LOCATION='PR6526',
 CDS_LIB='pure_quanta',
 CDS_PART_NAME='Q_RES_0402LF-10K,1%,1/16W,CHIP,CS31002FB08',
 PART_NUMBER='CS31002FB08',
 VALUE='10K',
 PRIM_FILE='./archive_libs/logical/q_res/chips/chips.prt';

PART_NAME
 PR6530 'Q_RES_0402LF-49.9,1%,1/16W,CHIP,CS04992FB07':;

SECTION_NUMBER 1
 '@T6G_MB_LIB.T6G(SCH_1):PAGE475_I34@PURE_QUANTA.Q_RES(CHIPS)':
 C_PATH='@t6g_mb_lib.t6g(sch_1):page475_i34@pure_quanta.q_res(chips)',
 P_PATH='@t6g_mb_lib.t6g(sch_1):page362_i34@pure_quanta.q_res(chips)',
 PATH='I34',
 DRAWING='@T6G_MB_LIB.T6G(SCH_1):PAGE475',
 WATTAGE='1/16W',
 TOLERANCE='1%',
 MATERIAL='CHIP',
 PHYS_PAGE='362',
 XY='(-9925,6025)',
 ROT='0',
 VER='1',
 PACK_TYPE='0402LF',
 LOCATION='PR6530',
 CDS_LIB='pure_quanta',
 CDS_PART_NAME='Q_RES_0402LF-49.9,1%,1/16W,CHIP,CS04992FB07',
 PART_NUMBER='CS04992FB07',
 VALUE='49.9',
 PRIM_FILE='./archive_libs/logical/q_res/chips/chips.prt';

PART_NAME
 PR6531 'Q_RES_0402LF-0,5%,1/16W,CHIP,CS00002JB13':;

SECTION_NUMBER 1
 '@T6G_MB_LIB.T6G(SCH_1):PAGE475_I105@PURE_QUANTA.Q_RES(CHIPS)':
 C_PATH='@t6g_mb_lib.t6g(sch_1):page475_i105@pure_quanta.q_res(chips)',
 P_PATH='@t6g_mb_lib.t6g(sch_1):page362_i105@pure_quanta.q_res(chips)',
 PATH='I105',
 DRAWING='@T6G_MB_LIB.T6G(SCH_1):PAGE475',
 SEC_TYPE='0402LF',
 WATTAGE='1/16W',
 TOLERANCE='5%',
 MATERIAL='CHIP',
 PHYS_PAGE='362',
 XY='(-8900,5875)',
 ROT='0',
 VER='1',
 PACK_TYPE='0402LF',
 LOCATION='PR6531',
 SEC='1',
 CDS_LIB='pure_quanta',
 CDS_PART_NAME='Q_RES_0402LF-0,5%,1/16W,CHIP,CS00002JB13',
 PART_NUMBER='CS00002JB13',
 VALUE='0',
 PRIM_FILE='./archive_libs/logical/q_res/chips/chips.prt';

PART_NAME
 PR6532 'Q_RES_0402LF-49.9,1%,1/16W,CHIP,CS04992FB07':;

SECTION_NUMBER 1
 '@T6G_MB_LIB.T6G(SCH_1):PAGE475_I32@PURE_QUANTA.Q_RES(CHIPS)':
 C_PATH='@t6g_mb_lib.t6g(sch_1):page475_i32@pure_quanta.q_res(chips)',
 P_PATH='@t6g_mb_lib.t6g(sch_1):page362_i32@pure_quanta.q_res(chips)',
 PATH='I32',
 DRAWING='@T6G_MB_LIB.T6G(SCH_1):PAGE475',
 WATTAGE='1/16W',
 TOLERANCE='1%',
 MATERIAL='CHIP',
 PHYS_PAGE='362',
 XY='(-9975,5350)',
 ROT='0',
 VER='1',
 PACK_TYPE='0402LF',
 LOCATION='PR6532',
 CDS_LIB='pure_quanta',
 CDS_PART_NAME='Q_RES_0402LF-49.9,1%,1/16W,CHIP,CS04992FB07',
 PART_NUMBER='CS04992FB07',
 VALUE='49.9',
 PRIM_FILE='./archive_libs/logical/q_res/chips/chips.prt';

PART_NAME
 PR6533 'Q_RES_0402LF-22.1K,1%,1/16W,CHIP,CS32212FB02':;

SECTION_NUMBER 1
 '@T6G_MB_LIB.T6G(SCH_1):PAGE477_I13@PURE_QUANTA.Q_RES(CHIPS)':
 C_PATH='@t6g_mb_lib.t6g(sch_1):page477_i13@pure_quanta.q_res(chips)',
 P_PATH='@t6g_mb_lib.t6g(sch_1):page364_i13@pure_quanta.q_res(chips)',
 PATH='I13',
 DRAWING='@T6G_MB_LIB.T6G(SCH_1):PAGE477',
 WATTAGE='1/16W',
 TOLERANCE='1%',
 MATERIAL='CHIP',
 PHYS_PAGE='364',
 XY='(-5750,1075)',
 ROT='0',
 VER='1',
 PACK_TYPE='0402LF',
 LOCATION='PR6533',
 CDS_LIB='pure_quanta',
 CDS_PART_NAME='Q_RES_0402LF-22.1K,1%,1/16W,CHIP,CS32212FB02',
 PART_NUMBER='CS32212FB02',
 VALUE='22.1K',
 PRIM_FILE='./archive_libs/logical/q_res/chips/chips.prt';

PART_NAME
 PR6538 'Q_RES_0402LF-1,1%,1/16W,CHIP,CS-1002FB04':;

SECTION_NUMBER 1
 '@T6G_MB_LIB.T6G(SCH_1):PAGE477_I83@PURE_QUANTA.Q_RES(CHIPS)':
 C_PATH='@t6g_mb_lib.t6g(sch_1):page477_i83@pure_quanta.q_res(chips)',
 P_PATH='@t6g_mb_lib.t6g(sch_1):page364_i83@pure_quanta.q_res(chips)',
 PATH='I83',
 DRAWING='@T6G_MB_LIB.T6G(SCH_1):PAGE477',
 WATTAGE='1/16W',
 TOLERANCE='1%',
 MATERIAL='CHIP',
 PHYS_PAGE='364',
 XY='(-2150,6175)',
 ROT='0',
 VER='1',
 PACK_TYPE='0402LF',
 LOCATION='PR6538',
 CDS_LIB='pure_quanta',
 CDS_PART_NAME='Q_RES_0402LF-1,1%,1/16W,CHIP,CS-1002FB04',
 PART_NUMBER='CS-1002FB04',
 VALUE='1',
 PRIM_FILE='./archive_libs/logical/q_res/chips/chips.prt';

PART_NAME
 PR6539 'Q_RES_0402LF-0,5%,1/16W,CHIP,CS00002JB13':;

SECTION_NUMBER 1
 '@T6G_MB_LIB.T6G(SCH_1):PAGE477_I69@PURE_QUANTA.Q_RES(CHIPS)':
 C_PATH='@t6g_mb_lib.t6g(sch_1):page477_i69@pure_quanta.q_res(chips)',
 P_PATH='@t6g_mb_lib.t6g(sch_1):page364_i69@pure_quanta.q_res(chips)',
 PATH='I69',
 DRAWING='@T6G_MB_LIB.T6G(SCH_1):PAGE477',
 WATTAGE='1/16W',
 TOLERANCE='5%',
 MATERIAL='CHIP',
 PHYS_PAGE='364',
 XY='(-2125,4175)',
 ROT='0',
 VER='1',
 PACK_TYPE='0402LF',
 LOCATION='PR6539',
 CDS_LIB='pure_quanta',
 CDS_PART_NAME='Q_RES_0402LF-0,5%,1/16W,CHIP,CS00002JB13',
 PART_NUMBER='CS00002JB13',
 VALUE='0',
 PRIM_FILE='./archive_libs/logical/q_res/chips/chips.prt';

PART_NAME
 PR6540 'Q_RES_0402LF-0,5%,1/16W,CHIP,CS00002JB13':;

SECTION_NUMBER 1
 '@T6G_MB_LIB.T6G(SCH_1):PAGE477_I68@PURE_QUANTA.Q_RES(CHIPS)':
 C_PATH='@t6g_mb_lib.t6g(sch_1):page477_i68@pure_quanta.q_res(chips)',
 P_PATH='@t6g_mb_lib.t6g(sch_1):page364_i68@pure_quanta.q_res(chips)',
 PATH='I68',
 DRAWING='@T6G_MB_LIB.T6G(SCH_1):PAGE477',
 WATTAGE='1/16W',
 TOLERANCE='5%',
 MATERIAL='CHIP',
 PHYS_PAGE='364',
 XY='(-2125,3725)',
 ROT='0',
 VER='1',
 PACK_TYPE='0402LF',
 LOCATION='PR6540',
 CDS_LIB='pure_quanta',
 CDS_PART_NAME='Q_RES_0402LF-0,5%,1/16W,CHIP,CS00002JB13',
 PART_NUMBER='CS00002JB13',
 VALUE='0',
 PRIM_FILE='./archive_libs/logical/q_res/chips/chips.prt';

PART_NAME
 PR6541 'Q_RES_0402LF-0,5%,1/16W,CHIP,CS00002JB13':;

SECTION_NUMBER 1
 '@T6G_MB_LIB.T6G(SCH_1):PAGE477_I65@PURE_QUANTA.Q_RES(CHIPS)':
 C_PATH='@t6g_mb_lib.t6g(sch_1):page477_i65@pure_quanta.q_res(chips)',
 P_PATH='@t6g_mb_lib.t6g(sch_1):page364_i65@pure_quanta.q_res(chips)',
 PATH='I65',
 DRAWING='@T6G_MB_LIB.T6G(SCH_1):PAGE477',
 WATTAGE='1/16W',
 TOLERANCE='5%',
 MATERIAL='CHIP',
 PHYS_PAGE='364',
 XY='(-2125,3275)',
 ROT='0',
 VER='1',
 PACK_TYPE='0402LF',
 LOCATION='PR6541',
 CDS_LIB='pure_quanta',
 CDS_PART_NAME='Q_RES_0402LF-0,5%,1/16W,CHIP,CS00002JB13',
 PART_NUMBER='CS00002JB13',
 VALUE='0',
 PRIM_FILE='./archive_libs/logical/q_res/chips/chips.prt';

PART_NAME
 PR6542 'Q_RES_0402LF-0,5%,1/16W,CHIP,CS00002JB13':;

SECTION_NUMBER 1
 '@T6G_MB_LIB.T6G(SCH_1):PAGE477_I64@PURE_QUANTA.Q_RES(CHIPS)':
 C_PATH='@t6g_mb_lib.t6g(sch_1):page477_i64@pure_quanta.q_res(chips)',
 P_PATH='@t6g_mb_lib.t6g(sch_1):page364_i64@pure_quanta.q_res(chips)',
 PATH='I64',
 DRAWING='@T6G_MB_LIB.T6G(SCH_1):PAGE477',
 WATTAGE='1/16W',
 TOLERANCE='5%',
 MATERIAL='CHIP',
 PHYS_PAGE='364',
 XY='(-2125,2825)',
 ROT='0',
 VER='1',
 PACK_TYPE='0402LF',
 LOCATION='PR6542',
 CDS_LIB='pure_quanta',
 CDS_PART_NAME='Q_RES_0402LF-0,5%,1/16W,CHIP,CS00002JB13',
 PART_NUMBER='CS00002JB13',
 VALUE='0',
 PRIM_FILE='./archive_libs/logical/q_res/chips/chips.prt';

PART_NAME
 PR6543 'Q_RES_0402LF-0,5%,1/16W,CHIP,CS00002JB13':;

SECTION_NUMBER 1
 '@T6G_MB_LIB.T6G(SCH_1):PAGE477_I58@PURE_QUANTA.Q_RES(CHIPS)':
 C_PATH='@t6g_mb_lib.t6g(sch_1):page477_i58@pure_quanta.q_res(chips)',
 P_PATH='@t6g_mb_lib.t6g(sch_1):page364_i58@pure_quanta.q_res(chips)',
 PATH='I58',
 DRAWING='@T6G_MB_LIB.T6G(SCH_1):PAGE477',
 WATTAGE='1/16W',
 TOLERANCE='5%',
 MATERIAL='CHIP',
 PHYS_PAGE='364',
 XY='(-2125,2375)',
 ROT='0',
 VER='1',
 PACK_TYPE='0402LF',
 LOCATION='PR6543',
 CDS_LIB='pure_quanta',
 CDS_PART_NAME='Q_RES_0402LF-0,5%,1/16W,CHIP,CS00002JB13',
 PART_NUMBER='CS00002JB13',
 VALUE='0',
 PRIM_FILE='./archive_libs/logical/q_res/chips/chips.prt';

PART_NAME
 PR6544 'Q_RES_0402LF-0,5%,1/16W,CHIP,CS00002JB13':;

SECTION_NUMBER 1
 '@T6G_MB_LIB.T6G(SCH_1):PAGE477_I57@PURE_QUANTA.Q_RES(CHIPS)':
 C_PATH='@t6g_mb_lib.t6g(sch_1):page477_i57@pure_quanta.q_res(chips)',
 P_PATH='@t6g_mb_lib.t6g(sch_1):page364_i57@pure_quanta.q_res(chips)',
 PATH='I57',
 DRAWING='@T6G_MB_LIB.T6G(SCH_1):PAGE477',
 WATTAGE='1/16W',
 TOLERANCE='5%',
 MATERIAL='CHIP',
 PHYS_PAGE='364',
 XY='(-2125,1925)',
 ROT='0',
 VER='1',
 PACK_TYPE='0402LF',
 LOCATION='PR6544',
 CDS_LIB='pure_quanta',
 CDS_PART_NAME='Q_RES_0402LF-0,5%,1/16W,CHIP,CS00002JB13',
 PART_NUMBER='CS00002JB13',
 VALUE='0',
 PRIM_FILE='./archive_libs/logical/q_res/chips/chips.prt';

PART_NAME
 PR6548 'Q_RES_0402LF-0,5%,1/16W,CHIP,CS00002JB13':;

SECTION_NUMBER 1
 '@T6G_MB_LIB.T6G(SCH_1):PAGE477_I52@PURE_QUANTA.Q_RES(CHIPS)':
 C_PATH='@t6g_mb_lib.t6g(sch_1):page477_i52@pure_quanta.q_res(chips)',
 P_PATH='@t6g_mb_lib.t6g(sch_1):page364_i52@pure_quanta.q_res(chips)',
 PATH='I52',
 DRAWING='@T6G_MB_LIB.T6G(SCH_1):PAGE477',
 WATTAGE='1/16W',
 TOLERANCE='5%',
 MATERIAL='CHIP',
 PHYS_PAGE='364',
 XY='(-2125,1275)',
 ROT='0',
 VER='1',
 PACK_TYPE='0402LF',
 LOCATION='PR6548',
 CDS_LIB='pure_quanta',
 CDS_PART_NAME='Q_RES_0402LF-0,5%,1/16W,CHIP,CS00002JB13',
 PART_NUMBER='CS00002JB13',
 VALUE='0',
 PRIM_FILE='./archive_libs/logical/q_res/chips/chips.prt';

PART_NAME
 PR6550 'Q_RES_0402LF-0,5%,1/16W,CHIP,CS00002JB13':;

SECTION_NUMBER 1
 '@T6G_MB_LIB.T6G(SCH_1):PAGE476_I183@PURE_QUANTA.Q_RES(CHIPS)':
 C_PATH='@t6g_mb_lib.t6g(sch_1):page476_i183@pure_quanta.q_res(chips)',
 P_PATH='@t6g_mb_lib.t6g(sch_1):page363_i183@pure_quanta.q_res(chips)',
 PATH='I183',
 DRAWING='@T6G_MB_LIB.T6G(SCH_1):PAGE476',
 SEC_TYPE='0402LF',
 WATTAGE='1/16W',
 TOLERANCE='5%',
 MATERIAL='CHIP',
 PHYS_PAGE='363',
 XY='(-6450,-4650)',
 ROT='0',
 VER='2',
 PACK_TYPE='0402LF',
 LOCATION='PR6550',
 SEC='1',
 CDS_LIB='pure_quanta',
 CDS_PART_NAME='Q_RES_0402LF-0,5%,1/16W,CHIP,CS00002JB13',
 PART_NUMBER='CS00002JB13',
 VALUE='0',
 PRIM_FILE='./archive_libs/logical/q_res/chips/chips.prt';

PART_NAME
 PR6551 'Q_RES_0402LF-0,5%,1/16W,EMPTY,CS00002JB13':;

SECTION_NUMBER 1
 '@T6G_MB_LIB.T6G(SCH_1):PAGE476_I185@PURE_QUANTA.Q_RES(CHIPS)':
 C_PATH='@t6g_mb_lib.t6g(sch_1):page476_i185@pure_quanta.q_res(chips)',
 P_PATH='@t6g_mb_lib.t6g(sch_1):page363_i185@pure_quanta.q_res(chips)',
 PATH='I185',
 DRAWING='@T6G_MB_LIB.T6G(SCH_1):PAGE476',
 SEC_TYPE='0402LF',
 WATTAGE='1/16W',
 TOLERANCE='5%',
 MATERIAL='EMPTY',
 PHYS_PAGE='363',
 XY='(-5550,-4650)',
 ROT='0',
 VER='2',
 PACK_TYPE='0402LF',
 LOCATION='PR6551',
 SEC='1',
 CDS_LIB='pure_quanta',
 CDS_PART_NAME='Q_RES_0402LF-0,5%,1/16W,EMPTY,CS00002JB13',
 PART_NUMBER='CS00002JB13',
 VALUE='0',
 PRIM_FILE='./archive_libs/logical/q_res/chips/chips.prt';

PART_NAME
 PR6552 'Q_RES_0402LF-2.2,5%,1/16W,CHIP,TMP_QCS-2202JB25':;

SECTION_NUMBER 1
 '@T6G_MB_LIB.T6G(SCH_1):PAGE476_I58@PURE_QUANTA.Q_RES(CHIPS)':
 C_PATH='@t6g_mb_lib.t6g(sch_1):page476_i58@pure_quanta.q_res(chips)',
 P_PATH='@t6g_mb_lib.t6g(sch_1):page363_i58@pure_quanta.q_res(chips)',
 PATH='I58',
 DRAWING='@T6G_MB_LIB.T6G(SCH_1):PAGE476',
 BOM_COST='VR_DIMM ',
 WATTAGE='1/16W',
 TOLERANCE='5%',
 MATERIAL='CHIP',
 PHYS_PAGE='363',
 XY='(-5900,-5500)',
 ROT='0',
 VER='2',
 PACK_TYPE='0402LF',
 LOCATION='PR6552',
 CDS_LIB='pure_quanta',
 CDS_PART_NAME='Q_RES_0402LF-2.2,5%,1/16W,CHIP,TMP_QCS-2202JB25',
 PART_NUMBER='TMP_QCS-2202JB25',
 VALUE='2.2',
 PRIM_FILE='./archive_libs/logical/q_res/chips/chips.prt';

PART_NAME
 PR6553 'Q_RES_0402LF-8.87K,1%,1/16W,EMPTY,CS28872FB01':;

SECTION_NUMBER 1
 '@T6G_MB_LIB.T6G(SCH_1):PAGE476_I220@PURE_QUANTA.Q_RES(CHIPS)':
 C_PATH='@t6g_mb_lib.t6g(sch_1):page476_i220@pure_quanta.q_res(chips)',
 P_PATH='@t6g_mb_lib.t6g(sch_1):page363_i220@pure_quanta.q_res(chips)',
 PATH='I220',
 DRAWING='@T6G_MB_LIB.T6G(SCH_1):PAGE476',
 SEC_TYPE='0402LF',
 WATTAGE='1/16W',
 TOLERANCE='1%',
 MATERIAL='EMPTY',
 PHYS_PAGE='363',
 XY='(-5850,-7000)',
 ROT='0',
 VER='2',
 PACK_TYPE='0402LF',
 LOCATION='PR6553',
 SEC='1',
 CDS_LIB='pure_quanta',
 CDS_PART_NAME='Q_RES_0402LF-8.87K,1%,1/16W,EMPTY,CS28872FB01',
 PART_NUMBER='CS28872FB01',
 VALUE='8.87K',
 PRIM_FILE='./archive_libs/logical/q_res/chips/chips.prt';

PART_NAME
 PR6554 'Q_RES_0402LF-5.6,1%,1/16W,CHIP,CS-5602FB01':;

SECTION_NUMBER 1
 '@T6G_MB_LIB.T6G(SCH_1):PAGE476_I221@PURE_QUANTA.Q_RES(CHIPS)':
 C_PATH='@t6g_mb_lib.t6g(sch_1):page476_i221@pure_quanta.q_res(chips)',
 P_PATH='@t6g_mb_lib.t6g(sch_1):page363_i221@pure_quanta.q_res(chips)',
 PATH='I221',
 DRAWING='@T6G_MB_LIB.T6G(SCH_1):PAGE476',
 SEC_TYPE='0402LF',
 WATTAGE='1/16W',
 TOLERANCE='1%',
 MATERIAL='CHIP',
 PHYS_PAGE='363',
 XY='(-2500,-6100)',
 ROT='0',
 VER='1',
 PACK_TYPE='0402LF',
 LOCATION='PR6554',
 SEC='1',
 CDS_LIB='pure_quanta',
 CDS_PART_NAME='Q_RES_0402LF-5.6,1%,1/16W,CHIP,CS-5602FB01',
 PART_NUMBER='CS-5602FB01',
 VALUE='5.6',
 PRIM_FILE='./archive_libs/logical/q_res/chips/chips.prt';

PART_NAME
 PR6555 'Q_RES_0402LF-1.5,1%,1/8W,EMPTY,CS-1504FB00':;

SECTION_NUMBER 1
 '@T6G_MB_LIB.T6G(SCH_1):PAGE476_I283@PURE_QUANTA.Q_RES(CHIPS)':
 C_PATH='@t6g_mb_lib.t6g(sch_1):page476_i283@pure_quanta.q_res(chips)',
 P_PATH='@t6g_mb_lib.t6g(sch_1):page363_i283@pure_quanta.q_res(chips)',
 PATH='I283',
 DRAWING='@T6G_MB_LIB.T6G(SCH_1):PAGE476',
 WATTAGE='1/8W',
 TOLERANCE='1%',
 MATERIAL='EMPTY',
 PHYS_PAGE='363',
 XY='(-2400,-7175)',
 ROT='0',
 VER='2',
 PACK_TYPE='0402LF',
 LOCATION='PR6555',
 CDS_LIB='pure_quanta',
 CDS_PART_NAME='Q_RES_0402LF-1.5,1%,1/8W,EMPTY,CS-1504FB00',
 PART_NUMBER='CS-1504FB00',
 VALUE='1.5',
 PRIM_FILE='./archive_libs/logical/q_res/chips/chips.prt';

PART_NAME
 PR6556 'Q_RES_0402LF-0,5%,1/16W,CHIP,CS00002JB13':;

SECTION_NUMBER 1
 '@T6G_MB_LIB.T6G(SCH_1):PAGE476_I42@PURE_QUANTA.Q_RES(CHIPS)':
 C_PATH='@t6g_mb_lib.t6g(sch_1):page476_i42@pure_quanta.q_res(chips)',
 P_PATH='@t6g_mb_lib.t6g(sch_1):page363_i42@pure_quanta.q_res(chips)',
 PATH='I42',
 DRAWING='@T6G_MB_LIB.T6G(SCH_1):PAGE476',
 BOM_COST='VR_DIMM ',
 WATTAGE='1/16W',
 TOLERANCE='5%',
 MATERIAL='CHIP',
 PHYS_PAGE='363',
 XY='(-2150,-7625)',
 ROT='0',
 VER='1',
 PACK_TYPE='0402LF',
 LOCATION='PR6556',
 CDS_LIB='pure_quanta',
 CDS_PART_NAME='Q_RES_0402LF-0,5%,1/16W,CHIP,CS00002JB13',
 PART_NUMBER='CS00002JB13',
 VALUE='0',
 PRIM_FILE='./archive_libs/logical/q_res/chips/chips.prt';

PART_NAME
 PR6557 'Q_RES_0603LF-499,1%,1/10W,CHIP,CS14993F901':;

SECTION_NUMBER 1
 '@T6G_MB_LIB.T6G(SCH_1):PAGE476_I187@PURE_QUANTA.Q_RES(CHIPS)':
 C_PATH='@t6g_mb_lib.t6g(sch_1):page476_i187@pure_quanta.q_res(chips)',
 P_PATH='@t6g_mb_lib.t6g(sch_1):page363_i187@pure_quanta.q_res(chips)',
 PATH='I187',
 DRAWING='@T6G_MB_LIB.T6G(SCH_1):PAGE476',
 SEC_TYPE='0603LF',
 WATTAGE='1/10W',
 TOLERANCE='1%',
 MATERIAL='CHIP',
 PHYS_PAGE='363',
 XY='(975,-6625)',
 ROT='0',
 VER='2',
 PACK_TYPE='0603LF',
 LOCATION='PR6557',
 SEC='1',
 CDS_LIB='pure_quanta',
 CDS_PART_NAME='Q_RES_0603LF-499,1%,1/10W,CHIP,CS14993F901',
 PART_NUMBER='CS14993F901',
 VALUE='499',
 PRIM_FILE='./archive_libs/logical/q_res/chips/chips.prt';

PART_NAME
 PR6560 'Q_RES_0402LF-2.2,5%,1/16W,CHIP,TMP_QCS-2202JB25':;

SECTION_NUMBER 1
 '@T6G_MB_LIB.T6G(SCH_1):PAGE476_I269@PURE_QUANTA.Q_RES(CHIPS)':
 C_PATH='@t6g_mb_lib.t6g(sch_1):page476_i269@pure_quanta.q_res(chips)',
 P_PATH='@t6g_mb_lib.t6g(sch_1):page363_i269@pure_quanta.q_res(chips)',
 PATH='I269',
 DRAWING='@T6G_MB_LIB.T6G(SCH_1):PAGE476',
 BOM_COST='VR_DIMM ',
 WATTAGE='1/16W',
 TOLERANCE='5%',
 MATERIAL='CHIP',
 PHYS_PAGE='363',
 XY='(-5775,-8400)',
 ROT='0',
 VER='2',
 PACK_TYPE='0402LF',
 LOCATION='PR6560',
 CDS_LIB='pure_quanta',
 CDS_PART_NAME='Q_RES_0402LF-2.2,5%,1/16W,CHIP,TMP_QCS-2202JB25',
 PART_NUMBER='TMP_QCS-2202JB25',
 VALUE='2.2',
 PRIM_FILE='./archive_libs/logical/q_res/chips/chips.prt';

PART_NAME
 PR6561 'Q_RES_0402LF-8.87K,1%,1/16W,EMPTY,CS28872FB01':;

SECTION_NUMBER 1
 '@T6G_MB_LIB.T6G(SCH_1):PAGE476_I276@PURE_QUANTA.Q_RES(CHIPS)':
 C_PATH='@t6g_mb_lib.t6g(sch_1):page476_i276@pure_quanta.q_res(chips)',
 P_PATH='@t6g_mb_lib.t6g(sch_1):page363_i276@pure_quanta.q_res(chips)',
 PATH='I276',
 DRAWING='@T6G_MB_LIB.T6G(SCH_1):PAGE476',
 WATTAGE='1/16W',
 TOLERANCE='1%',
 MATERIAL='EMPTY',
 PHYS_PAGE='363',
 XY='(-5725,-9900)',
 ROT='0',
 VER='2',
 PACK_TYPE='0402LF',
 LOCATION='PR6561',
 CDS_LIB='pure_quanta',
 CDS_PART_NAME='Q_RES_0402LF-8.87K,1%,1/16W,EMPTY,CS28872FB01',
 PART_NUMBER='CS28872FB01',
 VALUE='8.87K',
 PRIM_FILE='./archive_libs/logical/q_res/chips/chips.prt';

PART_NAME
 PR6562 'Q_RES_0402LF-5.6,1%,1/16W,CHIP,CS-5602FB01':;

SECTION_NUMBER 1
 '@T6G_MB_LIB.T6G(SCH_1):PAGE476_I262@PURE_QUANTA.Q_RES(CHIPS)':
 C_PATH='@t6g_mb_lib.t6g(sch_1):page476_i262@pure_quanta.q_res(chips)',
 P_PATH='@t6g_mb_lib.t6g(sch_1):page363_i262@pure_quanta.q_res(chips)',
 PATH='I262',
 DRAWING='@T6G_MB_LIB.T6G(SCH_1):PAGE476',
 WATTAGE='1/16W',
 TOLERANCE='1%',
 MATERIAL='CHIP',
 PHYS_PAGE='363',
 XY='(-2375,-9000)',
 ROT='0',
 VER='1',
 PACK_TYPE='0402LF',
 LOCATION='PR6562',
 CDS_LIB='pure_quanta',
 CDS_PART_NAME='Q_RES_0402LF-5.6,1%,1/16W,CHIP,CS-5602FB01',
 PART_NUMBER='CS-5602FB01',
 VALUE='5.6',
 PRIM_FILE='./archive_libs/logical/q_res/chips/chips.prt';

PART_NAME
 PR6563 'Q_RES_0402LF-1.5,1%,1/8W,EMPTY,CS-1504FB00':;

SECTION_NUMBER 1
 '@T6G_MB_LIB.T6G(SCH_1):PAGE476_I286@PURE_QUANTA.Q_RES(CHIPS)':
 C_PATH='@t6g_mb_lib.t6g(sch_1):page476_i286@pure_quanta.q_res(chips)',
 P_PATH='@t6g_mb_lib.t6g(sch_1):page363_i286@pure_quanta.q_res(chips)',
 PATH='I286',
 DRAWING='@T6G_MB_LIB.T6G(SCH_1):PAGE476',
 WATTAGE='1/8W',
 TOLERANCE='1%',
 MATERIAL='EMPTY',
 PHYS_PAGE='363',
 XY='(-2400,-10075)',
 ROT='0',
 VER='2',
 PACK_TYPE='0402LF',
 LOCATION='PR6563',
 CDS_LIB='pure_quanta',
 CDS_PART_NAME='Q_RES_0402LF-1.5,1%,1/8W,EMPTY,CS-1504FB00',
 PART_NUMBER='CS-1504FB00',
 VALUE='1.5',
 PRIM_FILE='./archive_libs/logical/q_res/chips/chips.prt';

PART_NAME
 PR6564 'Q_RES_0402LF-0,5%,1/16W,CHIP,CS00002JB13':;

SECTION_NUMBER 1
 '@T6G_MB_LIB.T6G(SCH_1):PAGE476_I263@PURE_QUANTA.Q_RES(CHIPS)':
 C_PATH='@t6g_mb_lib.t6g(sch_1):page476_i263@pure_quanta.q_res(chips)',
 P_PATH='@t6g_mb_lib.t6g(sch_1):page363_i263@pure_quanta.q_res(chips)',
 PATH='I263',
 DRAWING='@T6G_MB_LIB.T6G(SCH_1):PAGE476',
 BOM_COST='VR_DIMM ',
 WATTAGE='1/16W',
 TOLERANCE='5%',
 MATERIAL='CHIP',
 PHYS_PAGE='363',
 XY='(-1950,-10425)',
 ROT='0',
 VER='1',
 PACK_TYPE='0402LF',
 LOCATION='PR6564',
 CDS_LIB='pure_quanta',
 CDS_PART_NAME='Q_RES_0402LF-0,5%,1/16W,CHIP,CS00002JB13',
 PART_NUMBER='CS00002JB13',
 VALUE='0',
 PRIM_FILE='./archive_libs/logical/q_res/chips/chips.prt';

PART_NAME
 PR6600 'Q_RES_0402LF-49.9,1%,1/16W,CHIP,CS04992FB07':;

SECTION_NUMBER 1
 '@T6G_MB_LIB.T6G(SCH_1):PAGE477_I23@PURE_QUANTA.Q_RES(CHIPS)':
 C_PATH='@t6g_mb_lib.t6g(sch_1):page477_i23@pure_quanta.q_res(chips)',
 P_PATH='@t6g_mb_lib.t6g(sch_1):page364_i23@pure_quanta.q_res(chips)',
 PATH='I23',
 DRAWING='@T6G_MB_LIB.T6G(SCH_1):PAGE477',
 WATTAGE='1/16W',
 TOLERANCE='1%',
 MATERIAL='CHIP',
 PHYS_PAGE='364',
 XY='(-7125,4325)',
 ROT='0',
 VER='1',
 PACK_TYPE='0402LF',
 LOCATION='PR6600',
 CDS_LIB='pure_quanta',
 CDS_PART_NAME='Q_RES_0402LF-49.9,1%,1/16W,CHIP,CS04992FB07',
 PART_NUMBER='CS04992FB07',
 VALUE='49.9',
 PRIM_FILE='./archive_libs/logical/q_res/chips/chips.prt';

PART_NAME
 PR6601 'Q_RES_0402LF-0,5%,1/16W,CHIP,CS00002JB13':;

SECTION_NUMBER 1
 '@T6G_MB_LIB.T6G(SCH_1):PAGE477_I27@PURE_QUANTA.Q_RES(CHIPS)':
 C_PATH='@t6g_mb_lib.t6g(sch_1):page477_i27@pure_quanta.q_res(chips)',
 P_PATH='@t6g_mb_lib.t6g(sch_1):page364_i27@pure_quanta.q_res(chips)',
 PATH='I27',
 DRAWING='@T6G_MB_LIB.T6G(SCH_1):PAGE477',
 WATTAGE='1/16W',
 TOLERANCE='5%',
 MATERIAL='CHIP',
 PHYS_PAGE='364',
 XY='(-6100,4175)',
 ROT='0',
 VER='1',
 PACK_TYPE='0402LF',
 LOCATION='PR6601',
 CDS_LIB='pure_quanta',
 CDS_PART_NAME='Q_RES_0402LF-0,5%,1/16W,CHIP,CS00002JB13',
 PART_NUMBER='CS00002JB13',
 VALUE='0',
 PRIM_FILE='./archive_libs/logical/q_res/chips/chips.prt';

PART_NAME
 PR6602 'Q_RES_0402LF-49.9,1%,1/16W,CHIP,CS04992FB07':;

SECTION_NUMBER 1
 '@T6G_MB_LIB.T6G(SCH_1):PAGE477_I22@PURE_QUANTA.Q_RES(CHIPS)':
 C_PATH='@t6g_mb_lib.t6g(sch_1):page477_i22@pure_quanta.q_res(chips)',
 P_PATH='@t6g_mb_lib.t6g(sch_1):page364_i22@pure_quanta.q_res(chips)',
 PATH='I22',
 DRAWING='@T6G_MB_LIB.T6G(SCH_1):PAGE477',
 WATTAGE='1/16W',
 TOLERANCE='1%',
 MATERIAL='CHIP',
 PHYS_PAGE='364',
 XY='(-7175,3650)',
 ROT='0',
 VER='1',
 PACK_TYPE='0402LF',
 LOCATION='PR6602',
 CDS_LIB='pure_quanta',
 CDS_PART_NAME='Q_RES_0402LF-49.9,1%,1/16W,CHIP,CS04992FB07',
 PART_NUMBER='CS04992FB07',
 VALUE='49.9',
 PRIM_FILE='./archive_libs/logical/q_res/chips/chips.prt';

PART_NAME
 PR6603 'Q_RES_0402LF-0,5%,1/16W,CHIP,CS00002JB13':;

SECTION_NUMBER 1
 '@T6G_MB_LIB.T6G(SCH_1):PAGE475_I183@PURE_QUANTA.Q_RES(CHIPS)':
 C_PATH='@t6g_mb_lib.t6g(sch_1):page475_i183@pure_quanta.q_res(chips)',
 P_PATH='@t6g_mb_lib.t6g(sch_1):page362_i183@pure_quanta.q_res(chips)',
 PATH='I183',
 DRAWING='@T6G_MB_LIB.T6G(SCH_1):PAGE475',
 SEC_TYPE='0402LF',
 WATTAGE='1/16W',
 TOLERANCE='5%',
 MATERIAL='CHIP',
 PHYS_PAGE='362',
 XY='(-8550,2775)',
 ROT='0',
 VER='1',
 PACK_TYPE='0402LF',
 LOCATION='PR6603',
 SEC='1',
 CDS_LIB='pure_quanta',
 CDS_PART_NAME='Q_RES_0402LF-0,5%,1/16W,CHIP,CS00002JB13',
 PART_NUMBER='CS00002JB13',
 VALUE='0',
 PRIM_FILE='./archive_libs/logical/q_res/chips/chips.prt';

PART_NAME
 PR6604 'Q_RES_0402LF-5.36K,1%,1/16W,EMPTY,CS25362FB02':;

SECTION_NUMBER 1
 '@T6G_MB_LIB.T6G(SCH_1):PAGE475_I178@PURE_QUANTA.Q_RES(CHIPS)':
 C_PATH='@t6g_mb_lib.t6g(sch_1):page475_i178@pure_quanta.q_res(chips)',
 P_PATH='@t6g_mb_lib.t6g(sch_1):page362_i178@pure_quanta.q_res(chips)',
 PATH='I178',
 DRAWING='@T6G_MB_LIB.T6G(SCH_1):PAGE475',
 SEC_TYPE='0402LF',
 WATTAGE='1/16W',
 TOLERANCE='1%',
 MATERIAL='EMPTY',
 PHYS_PAGE='362',
 XY='(-9500,2300)',
 ROT='0',
 VER='1',
 PACK_TYPE='0402LF',
 LOCATION='PR6604',
 SEC='1',
 CDS_LIB='pure_quanta',
 CDS_PART_NAME='Q_RES_0402LF-5.36K,1%,1/16W,EMPTY,CS25362FB02',
 PART_NUMBER='CS25362FB02',
 VALUE='5.36K',
 PRIM_FILE='./archive_libs/logical/q_res/chips/chips.prt';

PART_NAME
 PR6605 'Q_RES_0402LF-0,5%,1/16W,CHIP,CS00002JB13':;

SECTION_NUMBER 1
 '@T6G_MB_LIB.T6G(SCH_1):PAGE475_I150@PURE_QUANTA.Q_RES(CHIPS)':
 C_PATH='@t6g_mb_lib.t6g(sch_1):page475_i150@pure_quanta.q_res(chips)',
 P_PATH='@t6g_mb_lib.t6g(sch_1):page362_i150@pure_quanta.q_res(chips)',
 PATH='I150',
 DRAWING='@T6G_MB_LIB.T6G(SCH_1):PAGE475',
 SEC_TYPE='0402LF',
 WATTAGE='1/16W',
 TOLERANCE='5%',
 MATERIAL='CHIP',
 PHYS_PAGE='362',
 XY='(-8800,2100)',
 ROT='2',
 VER='2',
 PACK_TYPE='0402LF',
 LOCATION='PR6605',
 SEC='1',
 CDS_LIB='pure_quanta',
 CDS_PART_NAME='Q_RES_0402LF-0,5%,1/16W,CHIP,CS00002JB13',
 PART_NUMBER='CS00002JB13',
 VALUE='0',
 PRIM_FILE='./archive_libs/logical/q_res/chips/chips.prt';

PART_NAME
 PR6606 'Q_RES_0402LF-0,5%,1/16W,CHIP,CS00002JB13':;

SECTION_NUMBER 1
 '@T6G_MB_LIB.T6G(SCH_1):PAGE475_I160@PURE_QUANTA.Q_RES(CHIPS)':
 C_PATH='@t6g_mb_lib.t6g(sch_1):page475_i160@pure_quanta.q_res(chips)',
 P_PATH='@t6g_mb_lib.t6g(sch_1):page362_i160@pure_quanta.q_res(chips)',
 PATH='I160',
 DRAWING='@T6G_MB_LIB.T6G(SCH_1):PAGE475',
 SEC_TYPE='0402LF',
 WATTAGE='1/16W',
 TOLERANCE='5%',
 MATERIAL='CHIP',
 PHYS_PAGE='362',
 XY='(-9100,2425)',
 ROT='0',
 VER='1',
 PACK_TYPE='0402LF',
 LOCATION='PR6606',
 SEC='1',
 CDS_LIB='pure_quanta',
 CDS_PART_NAME='Q_RES_0402LF-0,5%,1/16W,CHIP,CS00002JB13',
 PART_NUMBER='CS00002JB13',
 VALUE='0',
 PRIM_FILE='./archive_libs/logical/q_res/chips/chips.prt';

PART_NAME
 PR6607 'Q_RES_0402LF-1K,1%,1/16W,EMPTY,CS21002FB06':;

SECTION_NUMBER 1
 '@T6G_MB_LIB.T6G(SCH_1):PAGE475_I125@PURE_QUANTA.Q_RES(CHIPS)':
 C_PATH='@t6g_mb_lib.t6g(sch_1):page475_i125@pure_quanta.q_res(chips)',
 P_PATH='@t6g_mb_lib.t6g(sch_1):page362_i125@pure_quanta.q_res(chips)',
 PATH='I125',
 DRAWING='@T6G_MB_LIB.T6G(SCH_1):PAGE475',
 WATTAGE='1/16W',
 TOLERANCE='1%',
 MATERIAL='EMPTY',
 PHYS_PAGE='362',
 XY='(-8050,2100)',
 ROT='2',
 VER='2',
 PACK_TYPE='0402LF',
 LOCATION='PR6607',
 CDS_LIB='pure_quanta',
 CDS_PART_NAME='Q_RES_0402LF-1K,1%,1/16W,EMPTY,CS21002FB06',
 PART_NUMBER='CS21002FB06',
 VALUE='1K',
 PRIM_FILE='./archive_libs/logical/q_res/chips/chips.prt';

PART_NAME
 PR6608 'Q_RES_0402LF-1,1%,1/16W,CHIP,CS-1002FB04':;

SECTION_NUMBER 1
 '@T6G_MB_LIB.T6G(SCH_1):PAGE475_I131@PURE_QUANTA.Q_RES(CHIPS)':
 C_PATH='@t6g_mb_lib.t6g(sch_1):page475_i131@pure_quanta.q_res(chips)',
 P_PATH='@t6g_mb_lib.t6g(sch_1):page362_i131@pure_quanta.q_res(chips)',
 PATH='I131',
 DRAWING='@T6G_MB_LIB.T6G(SCH_1):PAGE475',
 SEC_TYPE='0402LF',
 WATTAGE='1/16W',
 TOLERANCE='1%',
 MATERIAL='CHIP',
 PHYS_PAGE='362',
 XY='(-4950,7875)',
 ROT='0',
 VER='1',
 PACK_TYPE='0402LF',
 LOCATION='PR6608',
 SEC='1',
 CDS_LIB='pure_quanta',
 CDS_PART_NAME='Q_RES_0402LF-1,1%,1/16W,CHIP,CS-1002FB04',
 PART_NUMBER='CS-1002FB04',
 VALUE='1',
 PRIM_FILE='./archive_libs/logical/q_res/chips/chips.prt';

PART_NAME
 PR6609 'Q_RES_0402LF-0,5%,1/16W,CHIP,CS00002JB13':;

SECTION_NUMBER 1
 '@T6G_MB_LIB.T6G(SCH_1):PAGE475_I188@PURE_QUANTA.Q_RES(CHIPS)':
 C_PATH='@t6g_mb_lib.t6g(sch_1):page475_i188@pure_quanta.q_res(chips)',
 P_PATH='@t6g_mb_lib.t6g(sch_1):page362_i188@pure_quanta.q_res(chips)',
 PATH='I188',
 DRAWING='@T6G_MB_LIB.T6G(SCH_1):PAGE475',
 WATTAGE='1/16W',
 TOLERANCE='5%',
 MATERIAL='CHIP',
 PHYS_PAGE='362',
 XY='(-4800,5875)',
 ROT='0',
 VER='1',
 PACK_TYPE='0402LF',
 LOCATION='PR6609',
 CDS_LIB='pure_quanta',
 CDS_PART_NAME='Q_RES_0402LF-0,5%,1/16W,CHIP,CS00002JB13',
 PART_NUMBER='CS00002JB13',
 VALUE='0',
 PRIM_FILE='./archive_libs/logical/q_res/chips/chips.prt';

PART_NAME
 PR6610 'Q_RES_0402LF-0,5%,1/16W,CHIP,CS00002JB13':;

SECTION_NUMBER 1
 '@T6G_MB_LIB.T6G(SCH_1):PAGE475_I190@PURE_QUANTA.Q_RES(CHIPS)':
 C_PATH='@t6g_mb_lib.t6g(sch_1):page475_i190@pure_quanta.q_res(chips)',
 P_PATH='@t6g_mb_lib.t6g(sch_1):page362_i190@pure_quanta.q_res(chips)',
 PATH='I190',
 DRAWING='@T6G_MB_LIB.T6G(SCH_1):PAGE475',
 WATTAGE='1/16W',
 TOLERANCE='5%',
 MATERIAL='CHIP',
 PHYS_PAGE='362',
 XY='(-4800,5425)',
 ROT='0',
 VER='1',
 PACK_TYPE='0402LF',
 LOCATION='PR6610',
 CDS_LIB='pure_quanta',
 CDS_PART_NAME='Q_RES_0402LF-0,5%,1/16W,CHIP,CS00002JB13',
 PART_NUMBER='CS00002JB13',
 VALUE='0',
 PRIM_FILE='./archive_libs/logical/q_res/chips/chips.prt';

PART_NAME
 PR6611 'Q_RES_0402LF-0,5%,1/16W,CHIP,CS00002JB13':;

SECTION_NUMBER 1
 '@T6G_MB_LIB.T6G(SCH_1):PAGE475_I191@PURE_QUANTA.Q_RES(CHIPS)':
 C_PATH='@t6g_mb_lib.t6g(sch_1):page475_i191@pure_quanta.q_res(chips)',
 P_PATH='@t6g_mb_lib.t6g(sch_1):page362_i191@pure_quanta.q_res(chips)',
 PATH='I191',
 DRAWING='@T6G_MB_LIB.T6G(SCH_1):PAGE475',
 WATTAGE='1/16W',
 TOLERANCE='5%',
 MATERIAL='CHIP',
 PHYS_PAGE='362',
 XY='(-4775,4975)',
 ROT='0',
 VER='1',
 PACK_TYPE='0402LF',
 LOCATION='PR6611',
 CDS_LIB='pure_quanta',
 CDS_PART_NAME='Q_RES_0402LF-0,5%,1/16W,CHIP,CS00002JB13',
 PART_NUMBER='CS00002JB13',
 VALUE='0',
 PRIM_FILE='./archive_libs/logical/q_res/chips/chips.prt';

PART_NAME
 PR6612 'Q_RES_0402LF-0,5%,1/16W,CHIP,CS00002JB13':;

SECTION_NUMBER 1
 '@T6G_MB_LIB.T6G(SCH_1):PAGE475_I192@PURE_QUANTA.Q_RES(CHIPS)':
 C_PATH='@t6g_mb_lib.t6g(sch_1):page475_i192@pure_quanta.q_res(chips)',
 P_PATH='@t6g_mb_lib.t6g(sch_1):page362_i192@pure_quanta.q_res(chips)',
 PATH='I192',
 DRAWING='@T6G_MB_LIB.T6G(SCH_1):PAGE475',
 WATTAGE='1/16W',
 TOLERANCE='5%',
 MATERIAL='CHIP',
 PHYS_PAGE='362',
 XY='(-4775,4525)',
 ROT='0',
 VER='1',
 PACK_TYPE='0402LF',
 LOCATION='PR6612',
 CDS_LIB='pure_quanta',
 CDS_PART_NAME='Q_RES_0402LF-0,5%,1/16W,CHIP,CS00002JB13',
 PART_NUMBER='CS00002JB13',
 VALUE='0',
 PRIM_FILE='./archive_libs/logical/q_res/chips/chips.prt';

PART_NAME
 PR6613 'Q_RES_0402LF-0,5%,1/16W,CHIP,CS00002JB13':;

SECTION_NUMBER 1
 '@T6G_MB_LIB.T6G(SCH_1):PAGE475_I193@PURE_QUANTA.Q_RES(CHIPS)':
 C_PATH='@t6g_mb_lib.t6g(sch_1):page475_i193@pure_quanta.q_res(chips)',
 P_PATH='@t6g_mb_lib.t6g(sch_1):page362_i193@pure_quanta.q_res(chips)',
 PATH='I193',
 DRAWING='@T6G_MB_LIB.T6G(SCH_1):PAGE475',
 WATTAGE='1/16W',
 TOLERANCE='5%',
 MATERIAL='CHIP',
 PHYS_PAGE='362',
 XY='(-4775,4075)',
 ROT='0',
 VER='1',
 PACK_TYPE='0402LF',
 LOCATION='PR6613',
 CDS_LIB='pure_quanta',
 CDS_PART_NAME='Q_RES_0402LF-0,5%,1/16W,CHIP,CS00002JB13',
 PART_NUMBER='CS00002JB13',
 VALUE='0',
 PRIM_FILE='./archive_libs/logical/q_res/chips/chips.prt';

PART_NAME
 PR6614 'Q_RES_0402LF-0,5%,1/16W,CHIP,CS00002JB13':;

SECTION_NUMBER 1
 '@T6G_MB_LIB.T6G(SCH_1):PAGE475_I198@PURE_QUANTA.Q_RES(CHIPS)':
 C_PATH='@t6g_mb_lib.t6g(sch_1):page475_i198@pure_quanta.q_res(chips)',
 P_PATH='@t6g_mb_lib.t6g(sch_1):page362_i198@pure_quanta.q_res(chips)',
 PATH='I198',
 DRAWING='@T6G_MB_LIB.T6G(SCH_1):PAGE475',
 WATTAGE='1/16W',
 TOLERANCE='5%',
 MATERIAL='CHIP',
 PHYS_PAGE='362',
 XY='(-4825,3625)',
 ROT='0',
 VER='1',
 PACK_TYPE='0402LF',
 LOCATION='PR6614',
 CDS_LIB='pure_quanta',
 CDS_PART_NAME='Q_RES_0402LF-0,5%,1/16W,CHIP,CS00002JB13',
 PART_NUMBER='CS00002JB13',
 VALUE='0',
 PRIM_FILE='./archive_libs/logical/q_res/chips/chips.prt';

PART_NAME
 PR6615 'Q_RES_0402LF-1K,1%,1/16W,CHIP,CS21002FB06':;

SECTION_NUMBER 1
 '@T6G_MB_LIB.T6G(SCH_1):PAGE475_I135@PURE_QUANTA.Q_RES(CHIPS)':
 C_PATH='@t6g_mb_lib.t6g(sch_1):page475_i135@pure_quanta.q_res(chips)',
 P_PATH='@t6g_mb_lib.t6g(sch_1):page362_i135@pure_quanta.q_res(chips)',
 PATH='I135',
 DRAWING='@T6G_MB_LIB.T6G(SCH_1):PAGE475',
 SEC_TYPE='0402LF',
 WATTAGE='1/16W',
 TOLERANCE='1%',
 MATERIAL='CHIP',
 PHYS_PAGE='362',
 XY='(-3525,3625)',
 ROT='0',
 VER='2',
 PACK_TYPE='0402LF',
 LOCATION='PR6615',
 SEC='1',
 CDS_LIB='pure_quanta',
 CDS_PART_NAME='Q_RES_0402LF-1K,1%,1/16W,CHIP,CS21002FB06',
 PART_NUMBER='CS21002FB06',
 VALUE='1K',
 PRIM_FILE='./archive_libs/logical/q_res/chips/chips.prt';

PART_NAME
 PR6616 'Q_RES_0402LF-0,5%,1/16W,CHIP,CS00002JB13':;

SECTION_NUMBER 1
 '@T6G_MB_LIB.T6G(SCH_1):PAGE475_I136@PURE_QUANTA.Q_RES(CHIPS)':
 C_PATH='@t6g_mb_lib.t6g(sch_1):page475_i136@pure_quanta.q_res(chips)',
 P_PATH='@t6g_mb_lib.t6g(sch_1):page362_i136@pure_quanta.q_res(chips)',
 PATH='I136',
 DRAWING='@T6G_MB_LIB.T6G(SCH_1):PAGE475',
 SEC_TYPE='0402LF',
 WATTAGE='1/16W',
 TOLERANCE='5%',
 MATERIAL='CHIP',
 PHYS_PAGE='362',
 XY='(-4775,3375)',
 ROT='0',
 VER='1',
 PACK_TYPE='0402LF',
 LOCATION='PR6616',
 SEC='1',
 CDS_LIB='pure_quanta',
 CDS_PART_NAME='Q_RES_0402LF-0,5%,1/16W,CHIP,CS00002JB13',
 PART_NUMBER='CS00002JB13',
 VALUE='0',
 PRIM_FILE='./archive_libs/logical/q_res/chips/chips.prt';

PART_NAME
 PR6618 'Q_RES_0402LF-0,5%,1/16W,CHIP,CS00002JB13':;

SECTION_NUMBER 1
 '@T6G_MB_LIB.T6G(SCH_1):PAGE475_I204@PURE_QUANTA.Q_RES(CHIPS)':
 C_PATH='@t6g_mb_lib.t6g(sch_1):page475_i204@pure_quanta.q_res(chips)',
 P_PATH='@t6g_mb_lib.t6g(sch_1):page362_i204@pure_quanta.q_res(chips)',
 PATH='I204',
 DRAWING='@T6G_MB_LIB.T6G(SCH_1):PAGE475',
 WATTAGE='1/16W',
 TOLERANCE='5%',
 MATERIAL='CHIP',
 PHYS_PAGE='362',
 XY='(-4825,2975)',
 ROT='0',
 VER='1',
 PACK_TYPE='0402LF',
 LOCATION='PR6618',
 CDS_LIB='pure_quanta',
 CDS_PART_NAME='Q_RES_0402LF-0,5%,1/16W,CHIP,CS00002JB13',
 PART_NUMBER='CS00002JB13',
 VALUE='0',
 PRIM_FILE='./archive_libs/logical/q_res/chips/chips.prt';

PART_NAME
 PR6619 'Q_RES_0402LF-0,5%,1/16W,CHIP,CS00002JB13':;

SECTION_NUMBER 1
 '@T6G_MB_LIB.T6G(SCH_1):PAGE478_I42@PURE_QUANTA.Q_RES(CHIPS)':
 C_PATH='@t6g_mb_lib.t6g(sch_1):page478_i42@pure_quanta.q_res(chips)',
 P_PATH='@t6g_mb_lib.t6g(sch_1):page365_i42@pure_quanta.q_res(chips)',
 PATH='I42',
 DRAWING='@T6G_MB_LIB.T6G(SCH_1):PAGE478',
 WATTAGE='1/16W',
 TOLERANCE='5%',
 MATERIAL='CHIP',
 PHYS_PAGE='365',
 XY='(-9425,6150)',
 ROT='0',
 VER='2',
 PACK_TYPE='0402LF',
 LOCATION='PR6619',
 CDS_LIB='pure_quanta',
 CDS_PART_NAME='Q_RES_0402LF-0,5%,1/16W,CHIP,CS00002JB13',
 PART_NUMBER='CS00002JB13',
 VALUE='0',
 PRIM_FILE='./archive_libs/logical/q_res/chips/chips.prt';

PART_NAME
 PR6620 'Q_RES_0402LF-0,5%,1/16W,EMPTY,CS00002JB13':;

SECTION_NUMBER 1
 '@T6G_MB_LIB.T6G(SCH_1):PAGE478_I56@PURE_QUANTA.Q_RES(CHIPS)':
 C_PATH='@t6g_mb_lib.t6g(sch_1):page478_i56@pure_quanta.q_res(chips)',
 P_PATH='@t6g_mb_lib.t6g(sch_1):page365_i56@pure_quanta.q_res(chips)',
 PATH='I56',
 DRAWING='@T6G_MB_LIB.T6G(SCH_1):PAGE478',
 WATTAGE='1/16W',
 TOLERANCE='5%',
 MATERIAL='EMPTY',
 PHYS_PAGE='365',
 XY='(-8525,6150)',
 ROT='0',
 VER='2',
 PACK_TYPE='0402LF',
 LOCATION='PR6620',
 CDS_LIB='pure_quanta',
 CDS_PART_NAME='Q_RES_0402LF-0,5%,1/16W,EMPTY,CS00002JB13',
 PART_NUMBER='CS00002JB13',
 VALUE='0',
 PRIM_FILE='./archive_libs/logical/q_res/chips/chips.prt';

PART_NAME
 PR6621 'Q_RES_0402LF-2.2,5%,1/16W,CHIP,TMP_QCS-2202JB25':;

SECTION_NUMBER 1
 '@T6G_MB_LIB.T6G(SCH_1):PAGE478_I53@PURE_QUANTA.Q_RES(CHIPS)':
 C_PATH='@t6g_mb_lib.t6g(sch_1):page478_i53@pure_quanta.q_res(chips)',
 P_PATH='@t6g_mb_lib.t6g(sch_1):page365_i53@pure_quanta.q_res(chips)',
 PATH='I53',
 DRAWING='@T6G_MB_LIB.T6G(SCH_1):PAGE478',
 BOM_COST='VR_DIMM ',
 WATTAGE='1/16W',
 TOLERANCE='5%',
 MATERIAL='CHIP',
 PHYS_PAGE='365',
 XY='(-8875,5300)',
 ROT='0',
 VER='2',
 PACK_TYPE='0402LF',
 LOCATION='PR6621',
 CDS_LIB='pure_quanta',
 CDS_PART_NAME='Q_RES_0402LF-2.2,5%,1/16W,CHIP,TMP_QCS-2202JB25',
 PART_NUMBER='TMP_QCS-2202JB25',
 VALUE='2.2',
 PRIM_FILE='./archive_libs/logical/q_res/chips/chips.prt';

PART_NAME
 PR6622 'Q_RES_0402LF-8.87K,1%,1/16W,EMPTY,CS28872FB01':;

SECTION_NUMBER 1
 '@T6G_MB_LIB.T6G(SCH_1):PAGE478_I46@PURE_QUANTA.Q_RES(CHIPS)':
 C_PATH='@t6g_mb_lib.t6g(sch_1):page478_i46@pure_quanta.q_res(chips)',
 P_PATH='@t6g_mb_lib.t6g(sch_1):page365_i46@pure_quanta.q_res(chips)',
 PATH='I46',
 DRAWING='@T6G_MB_LIB.T6G(SCH_1):PAGE478',
 WATTAGE='1/16W',
 TOLERANCE='1%',
 MATERIAL='EMPTY',
 PHYS_PAGE='365',
 XY='(-8825,3800)',
 ROT='0',
 VER='2',
 PACK_TYPE='0402LF',
 LOCATION='PR6622',
 CDS_LIB='pure_quanta',
 CDS_PART_NAME='Q_RES_0402LF-8.87K,1%,1/16W,EMPTY,CS28872FB01',
 PART_NUMBER='CS28872FB01',
 VALUE='8.87K',
 PRIM_FILE='./archive_libs/logical/q_res/chips/chips.prt';

PART_NAME
 PR6623 'Q_RES_0402LF-5.6,1%,1/16W,CHIP,CS-5602FB01':;

SECTION_NUMBER 1
 '@T6G_MB_LIB.T6G(SCH_1):PAGE478_I62@PURE_QUANTA.Q_RES(CHIPS)':
 C_PATH='@t6g_mb_lib.t6g(sch_1):page478_i62@pure_quanta.q_res(chips)',
 P_PATH='@t6g_mb_lib.t6g(sch_1):page365_i62@pure_quanta.q_res(chips)',
 PATH='I62',
 DRAWING='@T6G_MB_LIB.T6G(SCH_1):PAGE478',
 WATTAGE='1/16W',
 TOLERANCE='1%',
 MATERIAL='CHIP',
 PHYS_PAGE='365',
 XY='(-5475,4700)',
 ROT='0',
 VER='1',
 PACK_TYPE='0402LF',
 LOCATION='PR6623',
 CDS_LIB='pure_quanta',
 CDS_PART_NAME='Q_RES_0402LF-5.6,1%,1/16W,CHIP,CS-5602FB01',
 PART_NUMBER='CS-5602FB01',
 VALUE='5.6',
 PRIM_FILE='./archive_libs/logical/q_res/chips/chips.prt';

PART_NAME
 PR6624 'Q_RES_0402LF-1.5,1%,1/8W,EMPTY,CS-1504FB00':;

SECTION_NUMBER 1
 '@T6G_MB_LIB.T6G(SCH_1):PAGE478_I106@PURE_QUANTA.Q_RES(CHIPS)':
 C_PATH='@t6g_mb_lib.t6g(sch_1):page478_i106@pure_quanta.q_res(chips)',
 P_PATH='@t6g_mb_lib.t6g(sch_1):page365_i106@pure_quanta.q_res(chips)',
 PATH='I106',
 DRAWING='@T6G_MB_LIB.T6G(SCH_1):PAGE478',
 WATTAGE='1/8W',
 TOLERANCE='1%',
 MATERIAL='EMPTY',
 PHYS_PAGE='365',
 XY='(-5425,3625)',
 ROT='0',
 VER='2',
 PACK_TYPE='0402LF',
 LOCATION='PR6624',
 CDS_LIB='pure_quanta',
 CDS_PART_NAME='Q_RES_0402LF-1.5,1%,1/8W,EMPTY,CS-1504FB00',
 PART_NUMBER='CS-1504FB00',
 VALUE='1.5',
 PRIM_FILE='./archive_libs/logical/q_res/chips/chips.prt';

PART_NAME
 PR6625 'Q_RES_0603LF-499,1%,1/10W,CHIP,CS14993F901':;

SECTION_NUMBER 1
 '@T6G_MB_LIB.T6G(SCH_1):PAGE478_I97@PURE_QUANTA.Q_RES(CHIPS)':
 C_PATH='@t6g_mb_lib.t6g(sch_1):page478_i97@pure_quanta.q_res(chips)',
 P_PATH='@t6g_mb_lib.t6g(sch_1):page365_i97@pure_quanta.q_res(chips)',
 PATH='I97',
 DRAWING='@T6G_MB_LIB.T6G(SCH_1):PAGE478',
 WATTAGE='1/10W',
 TOLERANCE='1%',
 MATERIAL='CHIP',
 PHYS_PAGE='365',
 XY='(-2000,4175)',
 ROT='0',
 VER='2',
 PACK_TYPE='0603LF',
 LOCATION='PR6625',
 CDS_LIB='pure_quanta',
 CDS_PART_NAME='Q_RES_0603LF-499,1%,1/10W,CHIP,CS14993F901',
 PART_NUMBER='CS14993F901',
 VALUE='499',
 PRIM_FILE='./archive_libs/logical/q_res/chips/chips.prt';

PART_NAME
 PR6626 'Q_RES_0402LF-0,5%,1/16W,CHIP,CS00002JB13':;

SECTION_NUMBER 1
 '@T6G_MB_LIB.T6G(SCH_1):PAGE478_I59@PURE_QUANTA.Q_RES(CHIPS)':
 C_PATH='@t6g_mb_lib.t6g(sch_1):page478_i59@pure_quanta.q_res(chips)',
 P_PATH='@t6g_mb_lib.t6g(sch_1):page365_i59@pure_quanta.q_res(chips)',
 PATH='I59',
 DRAWING='@T6G_MB_LIB.T6G(SCH_1):PAGE478',
 BOM_COST='VR_DIMM ',
 WATTAGE='1/16W',
 TOLERANCE='5%',
 MATERIAL='CHIP',
 PHYS_PAGE='365',
 XY='(-5100,3200)',
 ROT='0',
 VER='1',
 PACK_TYPE='0402LF',
 LOCATION='PR6626',
 CDS_LIB='pure_quanta',
 CDS_PART_NAME='Q_RES_0402LF-0,5%,1/16W,CHIP,CS00002JB13',
 PART_NUMBER='CS00002JB13',
 VALUE='0',
 PRIM_FILE='./archive_libs/logical/q_res/chips/chips.prt';

PART_NAME
 PR6627 'Q_RES_0402LF-2.2,5%,1/16W,CHIP,TMP_QCS-2202JB25':;

SECTION_NUMBER 1
 '@T6G_MB_LIB.T6G(SCH_1):PAGE478_I11@PURE_QUANTA.Q_RES(CHIPS)':
 C_PATH='@t6g_mb_lib.t6g(sch_1):page478_i11@pure_quanta.q_res(chips)',
 P_PATH='@t6g_mb_lib.t6g(sch_1):page365_i11@pure_quanta.q_res(chips)',
 PATH='I11',
 DRAWING='@T6G_MB_LIB.T6G(SCH_1):PAGE478',
 BOM_COST='VR_DIMM ',
 WATTAGE='1/16W',
 TOLERANCE='5%',
 MATERIAL='CHIP',
 PHYS_PAGE='365',
 XY='(-8750,2400)',
 ROT='0',
 VER='2',
 PACK_TYPE='0402LF',
 LOCATION='PR6627',
 CDS_LIB='pure_quanta',
 CDS_PART_NAME='Q_RES_0402LF-2.2,5%,1/16W,CHIP,TMP_QCS-2202JB25',
 PART_NUMBER='TMP_QCS-2202JB25',
 VALUE='2.2',
 PRIM_FILE='./archive_libs/logical/q_res/chips/chips.prt';

PART_NAME
 PR6628 'Q_RES_0402LF-8.87K,1%,1/16W,EMPTY,CS28872FB01':;

SECTION_NUMBER 1
 '@T6G_MB_LIB.T6G(SCH_1):PAGE478_I5@PURE_QUANTA.Q_RES(CHIPS)':
 C_PATH='@t6g_mb_lib.t6g(sch_1):page478_i5@pure_quanta.q_res(chips)',
 P_PATH='@t6g_mb_lib.t6g(sch_1):page365_i5@pure_quanta.q_res(chips)',
 PATH='I5',
 DRAWING='@T6G_MB_LIB.T6G(SCH_1):PAGE478',
 WATTAGE='1/16W',
 TOLERANCE='1%',
 MATERIAL='EMPTY',
 PHYS_PAGE='365',
 XY='(-8700,900)',
 ROT='0',
 VER='2',
 PACK_TYPE='0402LF',
 LOCATION='PR6628',
 CDS_LIB='pure_quanta',
 CDS_PART_NAME='Q_RES_0402LF-8.87K,1%,1/16W,EMPTY,CS28872FB01',
 PART_NUMBER='CS28872FB01',
 VALUE='8.87K',
 PRIM_FILE='./archive_libs/logical/q_res/chips/chips.prt';

PART_NAME
 PR6629 'Q_RES_0402LF-5.6,1%,1/16W,CHIP,CS-5602FB01':;

SECTION_NUMBER 1
 '@T6G_MB_LIB.T6G(SCH_1):PAGE478_I19@PURE_QUANTA.Q_RES(CHIPS)':
 C_PATH='@t6g_mb_lib.t6g(sch_1):page478_i19@pure_quanta.q_res(chips)',
 P_PATH='@t6g_mb_lib.t6g(sch_1):page365_i19@pure_quanta.q_res(chips)',
 PATH='I19',
 DRAWING='@T6G_MB_LIB.T6G(SCH_1):PAGE478',
 WATTAGE='1/16W',
 TOLERANCE='1%',
 MATERIAL='CHIP',
 PHYS_PAGE='365',
 XY='(-5350,1800)',
 ROT='0',
 VER='1',
 PACK_TYPE='0402LF',
 LOCATION='PR6629',
 CDS_LIB='pure_quanta',
 CDS_PART_NAME='Q_RES_0402LF-5.6,1%,1/16W,CHIP,CS-5602FB01',
 PART_NUMBER='CS-5602FB01',
 VALUE='5.6',
 PRIM_FILE='./archive_libs/logical/q_res/chips/chips.prt';

PART_NAME
 PR6630 'Q_RES_0402LF-1.5,1%,1/8W,EMPTY,CS-1504FB00':;

SECTION_NUMBER 1
 '@T6G_MB_LIB.T6G(SCH_1):PAGE478_I110@PURE_QUANTA.Q_RES(CHIPS)':
 C_PATH='@t6g_mb_lib.t6g(sch_1):page478_i110@pure_quanta.q_res(chips)',
 P_PATH='@t6g_mb_lib.t6g(sch_1):page365_i110@pure_quanta.q_res(chips)',
 PATH='I110',
 DRAWING='@T6G_MB_LIB.T6G(SCH_1):PAGE478',
 WATTAGE='1/8W',
 TOLERANCE='1%',
 MATERIAL='EMPTY',
 PHYS_PAGE='365',
 XY='(-5400,725)',
 ROT='0',
 VER='2',
 PACK_TYPE='0402LF',
 LOCATION='PR6630',
 CDS_LIB='pure_quanta',
 CDS_PART_NAME='Q_RES_0402LF-1.5,1%,1/8W,EMPTY,CS-1504FB00',
 PART_NUMBER='CS-1504FB00',
 VALUE='1.5',
 PRIM_FILE='./archive_libs/logical/q_res/chips/chips.prt';

PART_NAME
 PR6631 'Q_RES_0402LF-0,5%,1/16W,CHIP,CS00002JB13':;

SECTION_NUMBER 1
 '@T6G_MB_LIB.T6G(SCH_1):PAGE478_I16@PURE_QUANTA.Q_RES(CHIPS)':
 C_PATH='@t6g_mb_lib.t6g(sch_1):page478_i16@pure_quanta.q_res(chips)',
 P_PATH='@t6g_mb_lib.t6g(sch_1):page365_i16@pure_quanta.q_res(chips)',
 PATH='I16',
 DRAWING='@T6G_MB_LIB.T6G(SCH_1):PAGE478',
 BOM_COST='VR_DIMM ',
 WATTAGE='1/16W',
 TOLERANCE='5%',
 MATERIAL='CHIP',
 PHYS_PAGE='365',
 XY='(-5025,375)',
 ROT='0',
 VER='1',
 PACK_TYPE='0402LF',
 LOCATION='PR6631',
 CDS_LIB='pure_quanta',
 CDS_PART_NAME='Q_RES_0402LF-0,5%,1/16W,CHIP,CS00002JB13',
 PART_NUMBER='CS00002JB13',
 VALUE='0',
 PRIM_FILE='./archive_libs/logical/q_res/chips/chips.prt';

PART_NAME
 PR6800 'Q_RES_0402LF-2.2,1%,1/16W,CHIP,CS-2202FB01':;

SECTION_NUMBER 1
 '@T6G_MB_LIB.T6G(SCH_1):PAGE469_I29@PURE_QUANTA.Q_RES(CHIPS)':
 C_PATH='@t6g_mb_lib.t6g(sch_1):page469_i29@pure_quanta.q_res(chips)',
 P_PATH='@t6g_mb_lib.t6g(sch_1):page360_i29@pure_quanta.q_res(chips)',
 PATH='I29',
 DRAWING='@T6G_MB_LIB.T6G(SCH_1):PAGE469',
 WATTAGE='1/16W',
 TOLERANCE='1%',
 MATERIAL='CHIP',
 PHYS_PAGE='360',
 XY='(-4450,3700)',
 ROT='0',
 VER='1',
 PACK_TYPE='0402LF',
 LOCATION='PR6800',
 CDS_LIB='pure_quanta',
 CDS_PART_NAME='Q_RES_0402LF-2.2,1%,1/16W,CHIP,CS-2202FB01',
 PART_NUMBER='CS-2202FB01',
 VALUE='2.2',
 PRIM_FILE='./archive_libs/logical/q_res/chips/chips.prt';

PART_NAME
 PR6801 'Q_RES_0402LF-2.2,1%,1/16W,CHIP,CS-2202FB01':;

SECTION_NUMBER 1
 '@T6G_MB_LIB.T6G(SCH_1):PAGE470_I28@PURE_QUANTA.Q_RES(CHIPS)':
 C_PATH='@t6g_mb_lib.t6g(sch_1):page470_i28@pure_quanta.q_res(chips)',
 P_PATH='@t6g_mb_lib.t6g(sch_1):page361_i28@pure_quanta.q_res(chips)',
 PATH='I28',
 DRAWING='@T6G_MB_LIB.T6G(SCH_1):PAGE470',
 WATTAGE='1/16W',
 TOLERANCE='1%',
 MATERIAL='CHIP',
 PHYS_PAGE='361',
 XY='(-4525,3750)',
 ROT='0',
 VER='1',
 PACK_TYPE='0402LF',
 LOCATION='PR6801',
 CDS_LIB='pure_quanta',
 CDS_PART_NAME='Q_RES_0402LF-2.2,1%,1/16W,CHIP,CS-2202FB01',
 PART_NUMBER='CS-2202FB01',
 VALUE='2.2',
 PRIM_FILE='./archive_libs/logical/q_res/chips/chips.prt';

PART_NAME
 PR6802 'Q_RES_0402LF-0,5%,1/16W,EMPTY,CS00002JB13':;

SECTION_NUMBER 1
 '@T6G_MB_LIB.T6G(SCH_1):PAGE477_I44@PURE_QUANTA.Q_RES(CHIPS)':
 C_PATH='@t6g_mb_lib.t6g(sch_1):page477_i44@pure_quanta.q_res(chips)',
 P_PATH='@t6g_mb_lib.t6g(sch_1):page364_i44@pure_quanta.q_res(chips)',
 PATH='I44',
 DRAWING='@T6G_MB_LIB.T6G(SCH_1):PAGE477',
 WATTAGE='1/16W',
 TOLERANCE='5%',
 MATERIAL='EMPTY',
 PHYS_PAGE='364',
 XY='(-5500,5250)',
 ROT='0',
 VER='2',
 PACK_TYPE='0402LF',
 LOCATION='PR6802',
 CDS_LIB='pure_quanta',
 CDS_PART_NAME='Q_RES_0402LF-0,5%,1/16W,EMPTY,CS00002JB13',
 PART_NUMBER='CS00002JB13',
 VALUE='0',
 PRIM_FILE='./archive_libs/logical/q_res/chips/chips.prt';

PART_NAME
 PR6803 'Q_RES_0402LF-1K,1%,1/16W,EMPTY,CS21002FB06':;

SECTION_NUMBER 1
 '@T6G_MB_LIB.T6G(SCH_1):PAGE475_I167@PURE_QUANTA.Q_RES(CHIPS)':
 C_PATH='@t6g_mb_lib.t6g(sch_1):page475_i167@pure_quanta.q_res(chips)',
 P_PATH='@t6g_mb_lib.t6g(sch_1):page362_i167@pure_quanta.q_res(chips)',
 PATH='I167',
 DRAWING='@T6G_MB_LIB.T6G(SCH_1):PAGE475',
 SEC_TYPE='0402LF',
 WATTAGE='1/16W',
 TOLERANCE='1%',
 MATERIAL='EMPTY',
 PHYS_PAGE='362',
 XY='(-9375,7275)',
 ROT='0',
 VER='1',
 PACK_TYPE='0402LF',
 LOCATION='PR6803',
 SEC='1',
 CDS_LIB='pure_quanta',
 CDS_PART_NAME='Q_RES_0402LF-1K,1%,1/16W,EMPTY,CS21002FB06',
 PART_NUMBER='CS21002FB06',
 VALUE='1K',
 PRIM_FILE='./archive_libs/logical/q_res/chips/chips.prt';

PART_NAME
 PR6804 'Q_RES_0402LF-1K,1%,1/16W,EMPTY,CS21002FB06':;

SECTION_NUMBER 1
 '@T6G_MB_LIB.T6G(SCH_1):PAGE477_I36@PURE_QUANTA.Q_RES(CHIPS)':
 C_PATH='@t6g_mb_lib.t6g(sch_1):page477_i36@pure_quanta.q_res(chips)',
 P_PATH='@t6g_mb_lib.t6g(sch_1):page364_i36@pure_quanta.q_res(chips)',
 PATH='I36',
 DRAWING='@T6G_MB_LIB.T6G(SCH_1):PAGE477',
 WATTAGE='1/16W',
 TOLERANCE='1%',
 MATERIAL='EMPTY',
 PHYS_PAGE='364',
 XY='(-6575,5575)',
 ROT='0',
 VER='1',
 PACK_TYPE='0402LF',
 LOCATION='PR6804',
 CDS_LIB='pure_quanta',
 CDS_PART_NAME='Q_RES_0402LF-1K,1%,1/16W,EMPTY,CS21002FB06',
 PART_NUMBER='CS21002FB06',
 VALUE='1K',
 PRIM_FILE='./archive_libs/logical/q_res/chips/chips.prt';

PART_NAME
 PR6805 'Q_RES_0402LF-1K,1%,1/16W,EMPTY,CS21002FB06':;

SECTION_NUMBER 1
 '@T6G_MB_LIB.T6G(SCH_1):PAGE475_I166@PURE_QUANTA.Q_RES(CHIPS)':
 C_PATH='@t6g_mb_lib.t6g(sch_1):page475_i166@pure_quanta.q_res(chips)',
 P_PATH='@t6g_mb_lib.t6g(sch_1):page362_i166@pure_quanta.q_res(chips)',
 PATH='I166',
 DRAWING='@T6G_MB_LIB.T6G(SCH_1):PAGE475',
 SEC_TYPE='0402LF',
 WATTAGE='1/16W',
 TOLERANCE='1%',
 MATERIAL='EMPTY',
 PHYS_PAGE='362',
 XY='(-9375,7425)',
 ROT='0',
 VER='1',
 PACK_TYPE='0402LF',
 LOCATION='PR6805',
 SEC='1',
 CDS_LIB='pure_quanta',
 CDS_PART_NAME='Q_RES_0402LF-1K,1%,1/16W,EMPTY,CS21002FB06',
 PART_NUMBER='CS21002FB06',
 VALUE='1K',
 PRIM_FILE='./archive_libs/logical/q_res/chips/chips.prt';

PART_NAME
 PR6806 'Q_RES_0402LF-1K,1%,1/16W,EMPTY,CS21002FB06':;

SECTION_NUMBER 1
 '@T6G_MB_LIB.T6G(SCH_1):PAGE477_I37@PURE_QUANTA.Q_RES(CHIPS)':
 C_PATH='@t6g_mb_lib.t6g(sch_1):page477_i37@pure_quanta.q_res(chips)',
 P_PATH='@t6g_mb_lib.t6g(sch_1):page364_i37@pure_quanta.q_res(chips)',
 PATH='I37',
 DRAWING='@T6G_MB_LIB.T6G(SCH_1):PAGE477',
 WATTAGE='1/16W',
 TOLERANCE='1%',
 MATERIAL='EMPTY',
 PHYS_PAGE='364',
 XY='(-6575,5725)',
 ROT='0',
 VER='1',
 PACK_TYPE='0402LF',
 LOCATION='PR6806',
 CDS_LIB='pure_quanta',
 CDS_PART_NAME='Q_RES_0402LF-1K,1%,1/16W,EMPTY,CS21002FB06',
 PART_NUMBER='CS21002FB06',
 VALUE='1K',
 PRIM_FILE='./archive_libs/logical/q_res/chips/chips.prt';

PART_NAME
 PR6807 'Q_RES_0402LF-0,5%,1/16W,EMPTY,CS00002JB13':;

SECTION_NUMBER 1
 '@T6G_MB_LIB.T6G(SCH_1):PAGE475_I158@PURE_QUANTA.Q_RES(CHIPS)':
 C_PATH='@t6g_mb_lib.t6g(sch_1):page475_i158@pure_quanta.q_res(chips)',
 P_PATH='@t6g_mb_lib.t6g(sch_1):page362_i158@pure_quanta.q_res(chips)',
 PATH='I158',
 DRAWING='@T6G_MB_LIB.T6G(SCH_1):PAGE475',
 SEC_TYPE='0402LF',
 WATTAGE='1/16W',
 TOLERANCE='5%',
 MATERIAL='EMPTY',
 PHYS_PAGE='362',
 XY='(-9100,2525)',
 ROT='0',
 VER='1',
 PACK_TYPE='0402LF',
 LOCATION='PR6807',
 SEC='1',
 CDS_LIB='pure_quanta',
 CDS_PART_NAME='Q_RES_0402LF-0,5%,1/16W,EMPTY,CS00002JB13',
 PART_NUMBER='CS00002JB13',
 VALUE='0',
 PRIM_FILE='./archive_libs/logical/q_res/chips/chips.prt';

PART_NAME
 PR6808 'Q_RES_0402LF-0,5%,1/16W,EMPTY,CS00002JB13':;

SECTION_NUMBER 1
 '@T6G_MB_LIB.T6G(SCH_1):PAGE477_I11@PURE_QUANTA.Q_RES(CHIPS)':
 C_PATH='@t6g_mb_lib.t6g(sch_1):page477_i11@pure_quanta.q_res(chips)',
 P_PATH='@t6g_mb_lib.t6g(sch_1):page364_i11@pure_quanta.q_res(chips)',
 PATH='I11',
 DRAWING='@T6G_MB_LIB.T6G(SCH_1):PAGE477',
 WATTAGE='1/16W',
 TOLERANCE='5%',
 MATERIAL='EMPTY',
 PHYS_PAGE='364',
 XY='(-6300,825)',
 ROT='0',
 VER='1',
 PACK_TYPE='0402LF',
 LOCATION='PR6808',
 CDS_LIB='pure_quanta',
 CDS_PART_NAME='Q_RES_0402LF-0,5%,1/16W,EMPTY,CS00002JB13',
 PART_NUMBER='CS00002JB13',
 VALUE='0',
 PRIM_FILE='./archive_libs/logical/q_res/chips/chips.prt';

PART_NAME
 PR6809 'Q_RES_0402LF-0,5%,1/16W,CHIP,CS00002JB13':;

SECTION_NUMBER 1
 '@T6G_MB_LIB.T6G(SCH_1):PAGE477_I10@PURE_QUANTA.Q_RES(CHIPS)':
 C_PATH='@t6g_mb_lib.t6g(sch_1):page477_i10@pure_quanta.q_res(chips)',
 P_PATH='@t6g_mb_lib.t6g(sch_1):page364_i10@pure_quanta.q_res(chips)',
 PATH='I10',
 DRAWING='@T6G_MB_LIB.T6G(SCH_1):PAGE477',
 WATTAGE='1/16W',
 TOLERANCE='5%',
 MATERIAL='CHIP',
 PHYS_PAGE='364',
 XY='(-6300,725)',
 ROT='0',
 VER='1',
 PACK_TYPE='0402LF',
 LOCATION='PR6809',
 CDS_LIB='pure_quanta',
 CDS_PART_NAME='Q_RES_0402LF-0,5%,1/16W,CHIP,CS00002JB13',
 PART_NUMBER='CS00002JB13',
 VALUE='0',
 PRIM_FILE='./archive_libs/logical/q_res/chips/chips.prt';

PART_NAME
 PR6810 'Q_RES_0402LF-0,5%,1/16W,CHIP,CS00002JB13':;

SECTION_NUMBER 1
 '@T6G_MB_LIB.T6G(SCH_1):PAGE475_I165@PURE_QUANTA.Q_RES(CHIPS)':
 C_PATH='@t6g_mb_lib.t6g(sch_1):page475_i165@pure_quanta.q_res(chips)',
 P_PATH='@t6g_mb_lib.t6g(sch_1):page362_i165@pure_quanta.q_res(chips)',
 PATH='I165',
 DRAWING='@T6G_MB_LIB.T6G(SCH_1):PAGE475',
 SEC_TYPE='0402LF',
 WATTAGE='1/16W',
 TOLERANCE='5%',
 MATERIAL='CHIP',
 PHYS_PAGE='362',
 XY='(-9000,6950)',
 ROT='0',
 VER='2',
 PACK_TYPE='0402LF',
 LOCATION='PR6810',
 SEC='1',
 CDS_LIB='pure_quanta',
 CDS_PART_NAME='Q_RES_0402LF-0,5%,1/16W,CHIP,CS00002JB13',
 PART_NUMBER='CS00002JB13',
 VALUE='0',
 PRIM_FILE='./archive_libs/logical/q_res/chips/chips.prt';

PART_NAME
 PR6811 'Q_RES_0402LF-0,5%,1/16W,CHIP,CS00002JB13':;

SECTION_NUMBER 1
 '@T6G_MB_LIB.T6G(SCH_1):PAGE477_I42@PURE_QUANTA.Q_RES(CHIPS)':
 C_PATH='@t6g_mb_lib.t6g(sch_1):page477_i42@pure_quanta.q_res(chips)',
 P_PATH='@t6g_mb_lib.t6g(sch_1):page364_i42@pure_quanta.q_res(chips)',
 PATH='I42',
 DRAWING='@T6G_MB_LIB.T6G(SCH_1):PAGE477',
 WATTAGE='1/16W',
 TOLERANCE='5%',
 MATERIAL='CHIP',
 PHYS_PAGE='364',
 XY='(-6200,5250)',
 ROT='0',
 VER='2',
 PACK_TYPE='0402LF',
 LOCATION='PR6811',
 CDS_LIB='pure_quanta',
 CDS_PART_NAME='Q_RES_0402LF-0,5%,1/16W,CHIP,CS00002JB13',
 PART_NUMBER='CS00002JB13',
 VALUE='0',
 PRIM_FILE='./archive_libs/logical/q_res/chips/chips.prt';

PART_NAME
 PR6812 'Q_RES_0402LF-1K,1%,1/16W,CHIP,CS21002FB06':;

SECTION_NUMBER 1
 '@T6G_MB_LIB.T6G(SCH_1):PAGE477_I86@PURE_QUANTA.Q_RES(CHIPS)':
 C_PATH='@t6g_mb_lib.t6g(sch_1):page477_i86@pure_quanta.q_res(chips)',
 P_PATH='@t6g_mb_lib.t6g(sch_1):page364_i86@pure_quanta.q_res(chips)',
 PATH='I86',
 DRAWING='@T6G_MB_LIB.T6G(SCH_1):PAGE477',
 WATTAGE='1/16W',
 TOLERANCE='1%',
 MATERIAL='CHIP',
 PHYS_PAGE='364',
 XY='(-750,1900)',
 ROT='0',
 VER='2',
 PACK_TYPE='0402LF',
 LOCATION='PR6812',
 CDS_LIB='pure_quanta',
 CDS_PART_NAME='Q_RES_0402LF-1K,1%,1/16W,CHIP,CS21002FB06',
 PART_NUMBER='CS21002FB06',
 VALUE='1K',
 PRIM_FILE='./archive_libs/logical/q_res/chips/chips.prt';

PART_NAME
 PR6813 'Q_RES_0402LF-1K,1%,1/16W,EMPTY,CS21002FB06':;

SECTION_NUMBER 1
 '@T6G_MB_LIB.T6G(SCH_1):PAGE477_I46@PURE_QUANTA.Q_RES(CHIPS)':
 C_PATH='@t6g_mb_lib.t6g(sch_1):page477_i46@pure_quanta.q_res(chips)',
 P_PATH='@t6g_mb_lib.t6g(sch_1):page364_i46@pure_quanta.q_res(chips)',
 PATH='I46',
 DRAWING='@T6G_MB_LIB.T6G(SCH_1):PAGE477',
 WATTAGE='1/16W',
 TOLERANCE='1%',
 MATERIAL='EMPTY',
 PHYS_PAGE='364',
 XY='(-5250,400)',
 ROT='2',
 VER='2',
 PACK_TYPE='0402LF',
 LOCATION='PR6813',
 CDS_LIB='pure_quanta',
 CDS_PART_NAME='Q_RES_0402LF-1K,1%,1/16W,EMPTY,CS21002FB06',
 PART_NUMBER='CS21002FB06',
 VALUE='1K',
 PRIM_FILE='./archive_libs/logical/q_res/chips/chips.prt';

PART_NAME
 PR6814 'Q_RES_0402LF-10K,1%,1/16W,EMPTY,CS31002FB08':;

SECTION_NUMBER 1
 '@T6G_MB_LIB.T6G(SCH_1):PAGE475_I138@PURE_QUANTA.Q_RES(CHIPS)':
 C_PATH='@t6g_mb_lib.t6g(sch_1):page475_i138@pure_quanta.q_res(chips)',
 P_PATH='@t6g_mb_lib.t6g(sch_1):page362_i138@pure_quanta.q_res(chips)',
 PATH='I138',
 DRAWING='@T6G_MB_LIB.T6G(SCH_1):PAGE475',
 SEC_TYPE='0402LF',
 WATTAGE='1/16W',
 TOLERANCE='1%',
 MATERIAL='EMPTY',
 PHYS_PAGE='362',
 XY='(-4600,2475)',
 ROT='0',
 VER='2',
 PACK_TYPE='0402LF',
 LOCATION='PR6814',
 SEC='1',
 CDS_LIB='pure_quanta',
 CDS_PART_NAME='Q_RES_0402LF-10K,1%,1/16W,EMPTY,CS31002FB08',
 PART_NUMBER='CS31002FB08',
 VALUE='10K',
 PRIM_FILE='./archive_libs/logical/q_res/chips/chips.prt';

PART_NAME
 PR6815 'Q_RES_0402LF-10K,1%,1/16W,EMPTY,CS31002FB08':;

SECTION_NUMBER 1
 '@T6G_MB_LIB.T6G(SCH_1):PAGE477_I54@PURE_QUANTA.Q_RES(CHIPS)':
 C_PATH='@t6g_mb_lib.t6g(sch_1):page477_i54@pure_quanta.q_res(chips)',
 P_PATH='@t6g_mb_lib.t6g(sch_1):page364_i54@pure_quanta.q_res(chips)',
 PATH='I54',
 DRAWING='@T6G_MB_LIB.T6G(SCH_1):PAGE477',
 WATTAGE='1/16W',
 TOLERANCE='1%',
 MATERIAL='EMPTY',
 PHYS_PAGE='364',
 XY='(-1800,775)',
 ROT='0',
 VER='2',
 PACK_TYPE='0402LF',
 LOCATION='PR6815',
 CDS_LIB='pure_quanta',
 CDS_PART_NAME='Q_RES_0402LF-10K,1%,1/16W,EMPTY,CS31002FB08',
 PART_NUMBER='CS31002FB08',
 VALUE='10K',
 PRIM_FILE='./archive_libs/logical/q_res/chips/chips.prt';

PART_NAME
 PR6816 'Q_RES_0402LF-0,5%,1/16W,CHIP,CS00002JB13':;

SECTION_NUMBER 1
 '@T6G_MB_LIB.T6G(SCH_1):PAGE477_I56@PURE_QUANTA.Q_RES(CHIPS)':
 C_PATH='@t6g_mb_lib.t6g(sch_1):page477_i56@pure_quanta.q_res(chips)',
 P_PATH='@t6g_mb_lib.t6g(sch_1):page364_i56@pure_quanta.q_res(chips)',
 PATH='I56',
 DRAWING='@T6G_MB_LIB.T6G(SCH_1):PAGE477',
 WATTAGE='1/16W',
 TOLERANCE='5%',
 MATERIAL='CHIP',
 PHYS_PAGE='364',
 XY='(-1975,1675)',
 ROT='0',
 VER='1',
 PACK_TYPE='0402LF',
 LOCATION='PR6816',
 CDS_LIB='pure_quanta',
 CDS_PART_NAME='Q_RES_0402LF-0,5%,1/16W,CHIP,CS00002JB13',
 PART_NUMBER='CS00002JB13',
 VALUE='0',
 PRIM_FILE='./archive_libs/logical/q_res/chips/chips.prt';

PART_NAME
 PR6817 'Q_RES_0402LF-1K,1%,1/16W,EMPTY,CS21002FB06':;

SECTION_NUMBER 1
 '@T6G_MB_LIB.T6G(SCH_1):PAGE475_I169@PURE_QUANTA.Q_RES(CHIPS)':
 C_PATH='@t6g_mb_lib.t6g(sch_1):page475_i169@pure_quanta.q_res(chips)',
 P_PATH='@t6g_mb_lib.t6g(sch_1):page362_i169@pure_quanta.q_res(chips)',
 PATH='I169',
 DRAWING='@T6G_MB_LIB.T6G(SCH_1):PAGE475',
 SEC_TYPE='0402LF',
 WATTAGE='1/16W',
 TOLERANCE='1%',
 MATERIAL='EMPTY',
 PHYS_PAGE='362',
 XY='(-9375,7125)',
 ROT='0',
 VER='1',
 PACK_TYPE='0402LF',
 LOCATION='PR6817',
 SEC='1',
 CDS_LIB='pure_quanta',
 CDS_PART_NAME='Q_RES_0402LF-1K,1%,1/16W,EMPTY,CS21002FB06',
 PART_NUMBER='CS21002FB06',
 VALUE='1K',
 PRIM_FILE='./archive_libs/logical/q_res/chips/chips.prt';

PART_NAME
 PR6818 'Q_RES_0402LF-1K,1%,1/16W,EMPTY,CS21002FB06':;

SECTION_NUMBER 1
 '@T6G_MB_LIB.T6G(SCH_1):PAGE477_I32@PURE_QUANTA.Q_RES(CHIPS)':
 C_PATH='@t6g_mb_lib.t6g(sch_1):page477_i32@pure_quanta.q_res(chips)',
 P_PATH='@t6g_mb_lib.t6g(sch_1):page364_i32@pure_quanta.q_res(chips)',
 PATH='I32',
 DRAWING='@T6G_MB_LIB.T6G(SCH_1):PAGE477',
 WATTAGE='1/16W',
 TOLERANCE='1%',
 MATERIAL='EMPTY',
 PHYS_PAGE='364',
 XY='(-6575,5425)',
 ROT='0',
 VER='1',
 PACK_TYPE='0402LF',
 LOCATION='PR6818',
 CDS_LIB='pure_quanta',
 CDS_PART_NAME='Q_RES_0402LF-1K,1%,1/16W,EMPTY,CS21002FB06',
 PART_NUMBER='CS21002FB06',
 VALUE='1K',
 PRIM_FILE='./archive_libs/logical/q_res/chips/chips.prt';

PART_NAME
 PR6819 'Q_RES_0402LF-0,5%,1/16W,CHIP,CS00002JB13':;

SECTION_NUMBER 1
 '@T6G_MB_LIB.T6G(SCH_1):PAGE475_I168@PURE_QUANTA.Q_RES(CHIPS)':
 C_PATH='@t6g_mb_lib.t6g(sch_1):page475_i168@pure_quanta.q_res(chips)',
 P_PATH='@t6g_mb_lib.t6g(sch_1):page362_i168@pure_quanta.q_res(chips)',
 PATH='I168',
 DRAWING='@T6G_MB_LIB.T6G(SCH_1):PAGE475',
 SEC_TYPE='0402LF',
 WATTAGE='1/16W',
 TOLERANCE='5%',
 MATERIAL='CHIP',
 PHYS_PAGE='362',
 XY='(-8650,6950)',
 ROT='0',
 VER='2',
 PACK_TYPE='0402LF',
 LOCATION='PR6819',
 SEC='1',
 CDS_LIB='pure_quanta',
 CDS_PART_NAME='Q_RES_0402LF-0,5%,1/16W,CHIP,CS00002JB13',
 PART_NUMBER='CS00002JB13',
 VALUE='0',
 PRIM_FILE='./archive_libs/logical/q_res/chips/chips.prt';

PART_NAME
 PR6820 'Q_RES_0402LF-0,5%,1/16W,CHIP,CS00002JB13':;

SECTION_NUMBER 1
 '@T6G_MB_LIB.T6G(SCH_1):PAGE477_I43@PURE_QUANTA.Q_RES(CHIPS)':
 C_PATH='@t6g_mb_lib.t6g(sch_1):page477_i43@pure_quanta.q_res(chips)',
 P_PATH='@t6g_mb_lib.t6g(sch_1):page364_i43@pure_quanta.q_res(chips)',
 PATH='I43',
 DRAWING='@T6G_MB_LIB.T6G(SCH_1):PAGE477',
 WATTAGE='1/16W',
 TOLERANCE='5%',
 MATERIAL='CHIP',
 PHYS_PAGE='364',
 XY='(-5850,5250)',
 ROT='0',
 VER='2',
 PACK_TYPE='0402LF',
 LOCATION='PR6820',
 CDS_LIB='pure_quanta',
 CDS_PART_NAME='Q_RES_0402LF-0,5%,1/16W,CHIP,CS00002JB13',
 PART_NUMBER='CS00002JB13',
 VALUE='0',
 PRIM_FILE='./archive_libs/logical/q_res/chips/chips.prt';

PART_NAME
 PR6821 'Q_RES_0402LF-0,5%,1/16W,CHIP,CS00002JB13':;

SECTION_NUMBER 1
 '@T6G_MB_LIB.T6G(SCH_1):PAGE477_I3@PURE_QUANTA.Q_RES(CHIPS)':
 C_PATH='@t6g_mb_lib.t6g(sch_1):page477_i3@pure_quanta.q_res(chips)',
 P_PATH='@t6g_mb_lib.t6g(sch_1):page364_i3@pure_quanta.q_res(chips)',
 PATH='I3',
 DRAWING='@T6G_MB_LIB.T6G(SCH_1):PAGE477',
 WATTAGE='1/16W',
 TOLERANCE='5%',
 MATERIAL='CHIP',
 PHYS_PAGE='364',
 XY='(-6000,400)',
 ROT='2',
 VER='2',
 PACK_TYPE='0402LF',
 LOCATION='PR6821',
 CDS_LIB='pure_quanta',
 CDS_PART_NAME='Q_RES_0402LF-0,5%,1/16W,CHIP,CS00002JB13',
 PART_NUMBER='CS00002JB13',
 VALUE='0',
 PRIM_FILE='./archive_libs/logical/q_res/chips/chips.prt';

PART_NAME
 PR8000 'Q_RES_0402LF-0,5%,1/16W,CHIP,CS00002JB13':;

SECTION_NUMBER 1
 '@T6G_MB_LIB.T6G(SCH_1):PAGE167_I46@PURE_QUANTA.Q_RES(CHIPS)':
 C_PATH='@t6g_mb_lib.t6g(sch_1):page167_i46@pure_quanta.q_res(chips)',
 P_PATH='@t6g_mb_lib.t6g(sch_1):page192_i46@pure_quanta.q_res(chips)',
 PATH='I46',
 DRAWING='@T6G_MB_LIB.T6G(SCH_1):PAGE167',
 WATTAGE='1/16W',
 TOLERANCE='5%',
 MATERIAL='CHIP',
 PHYS_PAGE='192',
 XY='(-5750,3900)',
 ROT='0',
 VER='1',
 PACK_TYPE='0402LF',
 LOCATION='PR8000',
 CDS_LIB='pure_quanta',
 CDS_PART_NAME='Q_RES_0402LF-0,5%,1/16W,CHIP,CS00002JB13',
 PART_NUMBER='CS00002JB13',
 VALUE='0',
 PRIM_FILE='./archive_libs/logical/q_res/chips/chips.prt';

PART_NAME
 PR8001 'Q_RES_0402LF-2.2,1%,1/16W,CHIP,CS-2202FB01':;

SECTION_NUMBER 1
 '@T6G_MB_LIB.T6G(SCH_1):PAGE184_I58@PURE_QUANTA.Q_RES(CHIPS)':
 C_PATH='@t6g_mb_lib.t6g(sch_1):page184_i58@pure_quanta.q_res(chips)',
 P_PATH='@t6g_mb_lib.t6g(sch_1):page209_i58@pure_quanta.q_res(chips)',
 PATH='I58',
 DRAWING='@T6G_MB_LIB.T6G(SCH_1):PAGE184',
 SEC_TYPE='0402LF',
 WATTAGE='1/16W',
 TOLERANCE='1%',
 MATERIAL='CHIP',
 PHYS_PAGE='209',
 XY='(-4550,3875)',
 ROT='0',
 VER='1',
 PACK_TYPE='0402LF',
 LOCATION='PR8001',
 SEC='1',
 CDS_LIB='pure_quanta',
 CDS_PART_NAME='Q_RES_0402LF-2.2,1%,1/16W,CHIP,CS-2202FB01',
 PART_NUMBER='CS-2202FB01',
 VALUE='2.2',
 PRIM_FILE='./archive_libs/logical/q_res/chips/chips.prt';

PART_NAME
 PR8002 'Q_RES_0402LF-2.2,1%,1/16W,CHIP,CS-2202FB01':;

SECTION_NUMBER 1
 '@T6G_MB_LIB.T6G(SCH_1):PAGE201_I58@PURE_QUANTA.Q_RES(CHIPS)':
 C_PATH='@t6g_mb_lib.t6g(sch_1):page201_i58@pure_quanta.q_res(chips)',
 P_PATH='@t6g_mb_lib.t6g(sch_1):page226_i58@pure_quanta.q_res(chips)',
 PATH='I58',
 DRAWING='@T6G_MB_LIB.T6G(SCH_1):PAGE201',
 SEC_TYPE='0402LF',
 WATTAGE='1/16W',
 TOLERANCE='1%',
 MATERIAL='CHIP',
 PHYS_PAGE='226',
 XY='(-4250,4300)',
 ROT='0',
 VER='1',
 PACK_TYPE='0402LF',
 LOCATION='PR8002',
 SEC='1',
 CDS_LIB='pure_quanta',
 CDS_PART_NAME='Q_RES_0402LF-2.2,1%,1/16W,CHIP,CS-2202FB01',
 PART_NUMBER='CS-2202FB01',
 VALUE='2.2',
 PRIM_FILE='./archive_libs/logical/q_res/chips/chips.prt';

PART_NAME
 PR8003 'Q_RES_0402LF-2.2,1%,1/16W,CHIP,CS-2202FB01':;

SECTION_NUMBER 1
 '@T6G_MB_LIB.T6G(SCH_1):PAGE315_I45@PURE_QUANTA.Q_RES(CHIPS)':
 C_PATH='@t6g_mb_lib.t6g(sch_1):page315_i45@pure_quanta.q_res(chips)',
 P_PATH='@t6g_mb_lib.t6g(sch_1):page269_i45@pure_quanta.q_res(chips)',
 PATH='I45',
 DRAWING='@T6G_MB_LIB.T6G(SCH_1):PAGE315',
 SEC_TYPE='0402LF',
 WATTAGE='1/16W',
 TOLERANCE='1%',
 MATERIAL='CHIP',
 PHYS_PAGE='269',
 XY='(-100,2325)',
 ROT='0',
 VER='1',
 PACK_TYPE='0402LF',
 LOCATION='PR8003',
 SEC='1',
 CDS_LIB='pure_quanta',
 CDS_PART_NAME='Q_RES_0402LF-2.2,1%,1/16W,CHIP,CS-2202FB01',
 PART_NUMBER='CS-2202FB01',
 VALUE='2.2',
 PRIM_FILE='./archive_libs/logical/q_res/chips/chips.prt';

PART_NAME
 PR8004 'Q_RES_0402LF-2.2,1%,1/16W,CHIP,CS-2202FB01':;

SECTION_NUMBER 1
 '@T6G_MB_LIB.T6G(SCH_1):PAGE380_I45@PURE_QUANTA.Q_RES(CHIPS)':
 C_PATH='@t6g_mb_lib.t6g(sch_1):page380_i45@pure_quanta.q_res(chips)',
 P_PATH='@t6g_mb_lib.t6g(sch_1):page270_i45@pure_quanta.q_res(chips)',
 PATH='I45',
 DRAWING='@T6G_MB_LIB.T6G(SCH_1):PAGE380',
 SEC_TYPE='0402LF',
 WATTAGE='1/16W',
 TOLERANCE='1%',
 MATERIAL='CHIP',
 PHYS_PAGE='270',
 XY='(-3675,2300)',
 ROT='0',
 VER='1',
 PACK_TYPE='0402LF',
 LOCATION='PR8004',
 SEC='1',
 CDS_LIB='pure_quanta',
 CDS_PART_NAME='Q_RES_0402LF-2.2,1%,1/16W,CHIP,CS-2202FB01',
 PART_NUMBER='CS-2202FB01',
 VALUE='2.2',
 PRIM_FILE='./archive_libs/logical/q_res/chips/chips.prt';

PART_NAME
 PR8005 'Q_RES_0402LF-0,5%,1/16W,CHIP,CS00002JB13':;

SECTION_NUMBER 1
 '@T6G_MB_LIB.T6G(SCH_1):PAGE168_I147@PURE_QUANTA.Q_RES(CHIPS)':
 C_PATH='@t6g_mb_lib.t6g(sch_1):page168_i147@pure_quanta.q_res(chips)',
 P_PATH='@t6g_mb_lib.t6g(sch_1):page193_i147@pure_quanta.q_res(chips)',
 PATH='I147',
 DRAWING='@T6G_MB_LIB.T6G(SCH_1):PAGE168',
 WATTAGE='1/16W',
 TOLERANCE='5%',
 MATERIAL='CHIP',
 PHYS_PAGE='193',
 XY='(-5625,6050)',
 ROT='0',
 VER='1',
 PACK_TYPE='0402LF',
 LOCATION='PR8005',
 CDS_LIB='pure_quanta',
 CDS_PART_NAME='Q_RES_0402LF-0,5%,1/16W,CHIP,CS00002JB13',
 PART_NUMBER='CS00002JB13',
 VALUE='0',
 PRIM_FILE='./archive_libs/logical/q_res/chips/chips.prt';

PART_NAME
 PR8006 'Q_RES_0402LF-0,5%,1/16W,CHIP,CS00002JB13':;

SECTION_NUMBER 1
 '@T6G_MB_LIB.T6G(SCH_1):PAGE168_I148@PURE_QUANTA.Q_RES(CHIPS)':
 C_PATH='@t6g_mb_lib.t6g(sch_1):page168_i148@pure_quanta.q_res(chips)',
 P_PATH='@t6g_mb_lib.t6g(sch_1):page193_i148@pure_quanta.q_res(chips)',
 PATH='I148',
 DRAWING='@T6G_MB_LIB.T6G(SCH_1):PAGE168',
 WATTAGE='1/16W',
 TOLERANCE='5%',
 MATERIAL='CHIP',
 PHYS_PAGE='193',
 XY='(-5600,5900)',
 ROT='0',
 VER='1',
 PACK_TYPE='0402LF',
 LOCATION='PR8006',
 CDS_LIB='pure_quanta',
 CDS_PART_NAME='Q_RES_0402LF-0,5%,1/16W,CHIP,CS00002JB13',
 PART_NUMBER='CS00002JB13',
 VALUE='0',
 PRIM_FILE='./archive_libs/logical/q_res/chips/chips.prt';

PART_NAME
 PR8007 'Q_RES_0402LF-0,5%,1/16W,CHIP,CS00002JB13':;

SECTION_NUMBER 1
 '@T6G_MB_LIB.T6G(SCH_1):PAGE175_I137@PURE_QUANTA.Q_RES(CHIPS)':
 C_PATH='@t6g_mb_lib.t6g(sch_1):page175_i137@pure_quanta.q_res(chips)',
 P_PATH='@t6g_mb_lib.t6g(sch_1):page200_i137@pure_quanta.q_res(chips)',
 PATH='I137',
 DRAWING='@T6G_MB_LIB.T6G(SCH_1):PAGE175',
 WATTAGE='1/16W',
 TOLERANCE='5%',
 MATERIAL='CHIP',
 PHYS_PAGE='200',
 XY='(-6475,5850)',
 ROT='0',
 VER='1',
 PACK_TYPE='0402LF',
 LOCATION='PR8007',
 CDS_LIB='pure_quanta',
 CDS_PART_NAME='Q_RES_0402LF-0,5%,1/16W,CHIP,CS00002JB13',
 PART_NUMBER='CS00002JB13',
 VALUE='0',
 PRIM_FILE='./archive_libs/logical/q_res/chips/chips.prt';

PART_NAME
 PR8008 'Q_RES_0402LF-0,5%,1/16W,CHIP,CS00002JB13':;

SECTION_NUMBER 1
 '@T6G_MB_LIB.T6G(SCH_1):PAGE175_I136@PURE_QUANTA.Q_RES(CHIPS)':
 C_PATH='@t6g_mb_lib.t6g(sch_1):page175_i136@pure_quanta.q_res(chips)',
 P_PATH='@t6g_mb_lib.t6g(sch_1):page200_i136@pure_quanta.q_res(chips)',
 PATH='I136',
 DRAWING='@T6G_MB_LIB.T6G(SCH_1):PAGE175',
 WATTAGE='1/16W',
 TOLERANCE='5%',
 MATERIAL='CHIP',
 PHYS_PAGE='200',
 XY='(-6500,5700)',
 ROT='0',
 VER='1',
 PACK_TYPE='0402LF',
 LOCATION='PR8008',
 CDS_LIB='pure_quanta',
 CDS_PART_NAME='Q_RES_0402LF-0,5%,1/16W,CHIP,CS00002JB13',
 PART_NUMBER='CS00002JB13',
 VALUE='0',
 PRIM_FILE='./archive_libs/logical/q_res/chips/chips.prt';

PART_NAME
 PR8009 'Q_RES_0402LF-0,5%,1/16W,CHIP,CS00002JB13':;

SECTION_NUMBER 1
 '@T6G_MB_LIB.T6G(SCH_1):PAGE185_I143@PURE_QUANTA.Q_RES(CHIPS)':
 C_PATH='@t6g_mb_lib.t6g(sch_1):page185_i143@pure_quanta.q_res(chips)',
 P_PATH='@t6g_mb_lib.t6g(sch_1):page210_i143@pure_quanta.q_res(chips)',
 PATH='I143',
 DRAWING='@T6G_MB_LIB.T6G(SCH_1):PAGE185',
 WATTAGE='1/16W',
 TOLERANCE='5%',
 MATERIAL='CHIP',
 PHYS_PAGE='210',
 XY='(-2800,7425)',
 ROT='0',
 VER='1',
 PACK_TYPE='0402LF',
 LOCATION='PR8009',
 CDS_LIB='pure_quanta',
 CDS_PART_NAME='Q_RES_0402LF-0,5%,1/16W,CHIP,CS00002JB13',
 PART_NUMBER='CS00002JB13',
 VALUE='0',
 PRIM_FILE='./archive_libs/logical/q_res/chips/chips.prt';

PART_NAME
 PR8010 'Q_RES_0402LF-0,5%,1/16W,CHIP,CS00002JB13':;

SECTION_NUMBER 1
 '@T6G_MB_LIB.T6G(SCH_1):PAGE185_I144@PURE_QUANTA.Q_RES(CHIPS)':
 C_PATH='@t6g_mb_lib.t6g(sch_1):page185_i144@pure_quanta.q_res(chips)',
 P_PATH='@t6g_mb_lib.t6g(sch_1):page210_i144@pure_quanta.q_res(chips)',
 PATH='I144',
 DRAWING='@T6G_MB_LIB.T6G(SCH_1):PAGE185',
 WATTAGE='1/16W',
 TOLERANCE='5%',
 MATERIAL='CHIP',
 PHYS_PAGE='210',
 XY='(-2800,7275)',
 ROT='0',
 VER='1',
 PACK_TYPE='0402LF',
 LOCATION='PR8010',
 CDS_LIB='pure_quanta',
 CDS_PART_NAME='Q_RES_0402LF-0,5%,1/16W,CHIP,CS00002JB13',
 PART_NUMBER='CS00002JB13',
 VALUE='0',
 PRIM_FILE='./archive_libs/logical/q_res/chips/chips.prt';

PART_NAME
 PR8011 'Q_RES_0402LF-0,5%,1/16W,CHIP,CS00002JB13':;

SECTION_NUMBER 1
 '@T6G_MB_LIB.T6G(SCH_1):PAGE192_I137@PURE_QUANTA.Q_RES(CHIPS)':
 C_PATH='@t6g_mb_lib.t6g(sch_1):page192_i137@pure_quanta.q_res(chips)',
 P_PATH='@t6g_mb_lib.t6g(sch_1):page217_i137@pure_quanta.q_res(chips)',
 PATH='I137',
 DRAWING='@T6G_MB_LIB.T6G(SCH_1):PAGE192',
 WATTAGE='1/16W',
 TOLERANCE='5%',
 MATERIAL='CHIP',
 PHYS_PAGE='217',
 XY='(-2875,6775)',
 ROT='0',
 VER='1',
 PACK_TYPE='0402LF',
 LOCATION='PR8011',
 CDS_LIB='pure_quanta',
 CDS_PART_NAME='Q_RES_0402LF-0,5%,1/16W,CHIP,CS00002JB13',
 PART_NUMBER='CS00002JB13',
 VALUE='0',
 PRIM_FILE='./archive_libs/logical/q_res/chips/chips.prt';

PART_NAME
 PR8012 'Q_RES_0402LF-0,5%,1/16W,CHIP,CS00002JB13':;

SECTION_NUMBER 1
 '@T6G_MB_LIB.T6G(SCH_1):PAGE192_I138@PURE_QUANTA.Q_RES(CHIPS)':
 C_PATH='@t6g_mb_lib.t6g(sch_1):page192_i138@pure_quanta.q_res(chips)',
 P_PATH='@t6g_mb_lib.t6g(sch_1):page217_i138@pure_quanta.q_res(chips)',
 PATH='I138',
 DRAWING='@T6G_MB_LIB.T6G(SCH_1):PAGE192',
 WATTAGE='1/16W',
 TOLERANCE='5%',
 MATERIAL='CHIP',
 PHYS_PAGE='217',
 XY='(-2875,6625)',
 ROT='0',
 VER='1',
 PACK_TYPE='0402LF',
 LOCATION='PR8012',
 CDS_LIB='pure_quanta',
 CDS_PART_NAME='Q_RES_0402LF-0,5%,1/16W,CHIP,CS00002JB13',
 PART_NUMBER='CS00002JB13',
 VALUE='0',
 PRIM_FILE='./archive_libs/logical/q_res/chips/chips.prt';

PART_NAME
 PR8073 'Q_RES_0402LF-1K,1%,1/16W,CHIP,CS21002FB06':;

SECTION_NUMBER 1
 '@T6G_MB_LIB.T6G(SCH_1):PAGE245_I65@PURE_QUANTA.Q_RES(CHIPS)':
 C_PATH='@t6g_mb_lib.t6g(sch_1):page245_i65@pure_quanta.q_res(chips)',
 P_PATH='@t6g_mb_lib.t6g(sch_1):page190_i65@pure_quanta.q_res(chips)',
 PATH='I65',
 DRAWING='@T6G_MB_LIB.T6G(SCH_1):PAGE245',
 WATTAGE='1/16W',
 TOLERANCE='1%',
 MATERIAL='CHIP',
 PHYS_PAGE='190',
 XY='(900,450)',
 ROT='0',
 VER='2',
 PACK_TYPE='0402LF',
 LOCATION='PR8073',
 CDS_LIB='pure_quanta',
 CDS_PART_NAME='Q_RES_0402LF-1K,1%,1/16W,CHIP,CS21002FB06',
 PART_NUMBER='CS21002FB06',
 VALUE='1K',
 PRIM_FILE='./archive_libs/logical/q_res/chips/chips.prt';

PART_NAME
 PR8089 'Q_RES_0402LF-16.9K,1%,1/16W,CHIP,CS31692FB03':;

SECTION_NUMBER 1
 '@T6G_MB_LIB.T6G(SCH_1):PAGE244_I15@PURE_QUANTA.Q_RES(CHIPS)':
 C_PATH='@t6g_mb_lib.t6g(sch_1):page244_i15@pure_quanta.q_res(chips)',
 P_PATH='@t6g_mb_lib.t6g(sch_1):page189_i15@pure_quanta.q_res(chips)',
 PATH='I15',
 DRAWING='@T6G_MB_LIB.T6G(SCH_1):PAGE244',
 SEC_TYPE='0402LF',
 WATTAGE='1/16W',
 TOLERANCE='1%',
 MATERIAL='CHIP',
 PHYS_PAGE='189',
 XY='(-5887,6732)',
 ROT='0',
 VER='2',
 PACK_TYPE='0402LF',
 LOCATION='PR8089',
 SEC='1',
 CDS_LIB='pure_quanta',
 CDS_PART_NAME='Q_RES_0402LF-16.9K,1%,1/16W,CHIP,CS31692FB03',
 PART_NUMBER='CS31692FB03',
 VALUE='16.9K',
 PRIM_FILE='./archive_libs/logical/q_res/chips/chips.prt';

PART_NAME
 PR8091 'Q_RES_0402LF-11.8K,0.1%,1/16W,CHIP,CS31182BB06':;

SECTION_NUMBER 1
 '@T6G_MB_LIB.T6G(SCH_1):PAGE244_I23@PURE_QUANTA.Q_RES(CHIPS)':
 C_PATH='@t6g_mb_lib.t6g(sch_1):page244_i23@pure_quanta.q_res(chips)',
 P_PATH='@t6g_mb_lib.t6g(sch_1):page189_i23@pure_quanta.q_res(chips)',
 PATH='I23',
 DRAWING='@T6G_MB_LIB.T6G(SCH_1):PAGE244',
 WATTAGE='1/16W',
 TOLERANCE='0.1%',
 MATERIAL='CHIP',
 PHYS_PAGE='189',
 XY='(-3675,7025)',
 ROT='0',
 VER='2',
 PACK_TYPE='0402LF',
 LOCATION='PR8091',
 CDS_LIB='pure_quanta',
 CDS_PART_NAME='Q_RES_0402LF-11.8K,0.1%,1/16W,CHIP,CS31182BB06',
 PART_NUMBER='CS31182BB06',
 VALUE='11.8K',
 PRIM_FILE='./archive_libs/logical/q_res/chips/chips.prt';

PART_NAME
 PR8092 'Q_RES_0402LF-86.6K,1%,1/16W,CHIP,CS38662FB05':;

SECTION_NUMBER 1
 '@T6G_MB_LIB.T6G(SCH_1):PAGE244_I27@PURE_QUANTA.Q_RES(CHIPS)':
 C_PATH='@t6g_mb_lib.t6g(sch_1):page244_i27@pure_quanta.q_res(chips)',
 P_PATH='@t6g_mb_lib.t6g(sch_1):page189_i27@pure_quanta.q_res(chips)',
 PATH='I27',
 DRAWING='@T6G_MB_LIB.T6G(SCH_1):PAGE244',
 WATTAGE='1/16W',
 TOLERANCE='1%',
 MATERIAL='CHIP',
 PHYS_PAGE='189',
 XY='(-2300,6950)',
 ROT='0',
 VER='1',
 PACK_TYPE='0402LF',
 LOCATION='PR8092',
 CDS_LIB='pure_quanta',
 CDS_PART_NAME='Q_RES_0402LF-86.6K,1%,1/16W,CHIP,CS38662FB05',
 PART_NUMBER='CS38662FB05',
 VALUE='86.6K',
 PRIM_FILE='./archive_libs/logical/q_res/chips/chips.prt';

PART_NAME
 PR8389 'Q_RES_0402LF-1,1%,1/16W,CHIP,CS-1002FB04':;

SECTION_NUMBER 1
 '@T6G_MB_LIB.T6G(SCH_1):PAGE245_I20@PURE_QUANTA.Q_RES(CHIPS)':
 C_PATH='@t6g_mb_lib.t6g(sch_1):page245_i20@pure_quanta.q_res(chips)',
 P_PATH='@t6g_mb_lib.t6g(sch_1):page190_i20@pure_quanta.q_res(chips)',
 PATH='I20',
 DRAWING='@T6G_MB_LIB.T6G(SCH_1):PAGE245',
 WATTAGE='1/16W',
 TOLERANCE='1%',
 MATERIAL='CHIP',
 PHYS_PAGE='190',
 XY='(-1800,-150)',
 ROT='0',
 VER='1',
 PACK_TYPE='0402LF',
 LOCATION='PR8389',
 CDS_LIB='pure_quanta',
 CDS_PART_NAME='Q_RES_0402LF-1,1%,1/16W,CHIP,CS-1002FB04',
 PART_NUMBER='CS-1002FB04',
 VALUE='1',
 PRIM_FILE='./archive_libs/logical/q_res/chips/chips.prt';

PART_NAME
 PU2 'ISL99390FRZTR5935-ISL99390FRZ-TR5935,SMLF,IC,AL099A':;

SECTION_NUMBER 1
 '@T6G_MB_LIB.T6G(SCH_1):PAGE176_I33@PURE_QUANTA.ISL99390FRZTR5935(CHIPS)':
 C_PATH='@t6g_mb_lib.t6g(sch_1):page176_i33@pure_quanta.isl99390frztr5935(chips)~
',
 P_PATH='@t6g_mb_lib.t6g(sch_1):page201_i33@pure_quanta.isl99390frztr5935(chips)~
',
 PATH='I33',
 DRAWING='@T6G_MB_LIB.T6G(SCH_1):PAGE176',
 PART_TYPE='SMLF',
 MATERIAL='IC',
 PHYS_PAGE='201',
 XY='(-7225,1175)',
 ROT='0',
 VER='1',
 LOCATION='PU2',
 CDS_LIB='pure_quanta',
 CDS_PART_NAME='ISL99390FRZTR5935-ISL99390FRZ-TR5935,SMLF,IC,AL099A',
 PART_NUMBER='AL099390004',
 VALUE='ISL99390FRZ-TR5935',
 PRIM_FILE='./archive_libs/logical/isl99390frztr5935/chips/chips.prt';

PART_NAME
 PU3 'MPQ8633BGLEC838Z-MPQ8633BGLE-C838-Z,SMLF,IC,AL0086A':;

SECTION_NUMBER 1
 '@T6G_MB_LIB.T6G(SCH_1):PAGE201_I15@PURE_QUANTA.MPQ8633BGLEC838Z(CHIPS)':
 C_PATH='@t6g_mb_lib.t6g(sch_1):page201_i15@pure_quanta.mpq8633bglec838z(chips)',
 P_PATH='@t6g_mb_lib.t6g(sch_1):page226_i15@pure_quanta.mpq8633bglec838z(chips)',
 PATH='I15',
 DRAWING='@T6G_MB_LIB.T6G(SCH_1):PAGE201',
 PART_TYPE='SMLF',
 MATERIAL='IC',
 PHYS_PAGE='226',
 XY='(-5425,3825)',
 ROT='0',
 VER='1',
 LOCATION='PU3',
 CDS_LIB='pure_quanta',
 CDS_PART_NAME='MPQ8633BGLEC838Z-MPQ8633BGLE-C838-Z,SMLF,IC,AL0086A',
 PART_NUMBER='AL008633005',
 VALUE='MPQ8633BGLE-C838-Z',
 PRIM_FILE='./archive_libs/logical/mpq8633bglec838z/chips/chips.prt';

PART_NAME
 PU4 'ISL99390FRZTR5935-ISL99390FRZ-TR5935,SMLF,IC,AL099A':;

SECTION_NUMBER 1
 '@T6G_MB_LIB.T6G(SCH_1):PAGE186_I88@PURE_QUANTA.ISL99390FRZTR5935(CHIPS)':
 C_PATH='@t6g_mb_lib.t6g(sch_1):page186_i88@pure_quanta.isl99390frztr5935(chips)~
',
 P_PATH='@t6g_mb_lib.t6g(sch_1):page211_i88@pure_quanta.isl99390frztr5935(chips)~
',
 PATH='I88',
 DRAWING='@T6G_MB_LIB.T6G(SCH_1):PAGE186',
 PART_TYPE='SMLF',
 MATERIAL='IC',
 PHYS_PAGE='211',
 XY='(-6125,4450)',
 ROT='0',
 VER='1',
 LOCATION='PU4',
 CDS_LIB='pure_quanta',
 CDS_PART_NAME='ISL99390FRZTR5935-ISL99390FRZ-TR5935,SMLF,IC,AL099A',
 PART_NUMBER='AL099390004',
 VALUE='ISL99390FRZ-TR5935',
 PRIM_FILE='./archive_libs/logical/isl99390frztr5935/chips/chips.prt';

PART_NAME
 PU5 'ISL99390FRZTR5935-ISL99390FRZ-TR5935,SMLF,IC,AL099A':;

SECTION_NUMBER 1
 '@T6G_MB_LIB.T6G(SCH_1):PAGE193_I31@PURE_QUANTA.ISL99390FRZTR5935(CHIPS)':
 C_PATH='@t6g_mb_lib.t6g(sch_1):page193_i31@pure_quanta.isl99390frztr5935(chips)~
',
 P_PATH='@t6g_mb_lib.t6g(sch_1):page218_i31@pure_quanta.isl99390frztr5935(chips)~
',
 PATH='I31',
 DRAWING='@T6G_MB_LIB.T6G(SCH_1):PAGE193',
 SEC_TYPE='',
 PART_TYPE='SMLF',
 MATERIAL='IC',
 PHYS_PAGE='218',
 XY='(-6825,1975)',
 ROT='0',
 VER='1',
 LOCATION='PU5',
 SEC='1',
 CDS_LIB='pure_quanta',
 CDS_PART_NAME='ISL99390FRZTR5935-ISL99390FRZ-TR5935,SMLF,IC,AL099A',
 PART_NUMBER='AL099390004',
 VALUE='ISL99390FRZ-TR5935',
 PRIM_FILE='./archive_libs/logical/isl99390frztr5935/chips/chips.prt';

PART_NAME
 PU6 'ISL99390FRZTR5935-ISL99390FRZ-TR5935,SMLF,IC,AL099A':;

SECTION_NUMBER 1
 '@T6G_MB_LIB.T6G(SCH_1):PAGE169_I26@PURE_QUANTA.ISL99390FRZTR5935(CHIPS)':
 C_PATH='@t6g_mb_lib.t6g(sch_1):page169_i26@pure_quanta.isl99390frztr5935(chips)~
',
 P_PATH='@t6g_mb_lib.t6g(sch_1):page194_i26@pure_quanta.isl99390frztr5935(chips)~
',
 PATH='I26',
 DRAWING='@T6G_MB_LIB.T6G(SCH_1):PAGE169',
 PART_TYPE='SMLF',
 MATERIAL='IC',
 PHYS_PAGE='194',
 XY='(-6200,4350)',
 ROT='0',
 VER='1',
 LOCATION='PU6',
 CDS_LIB='pure_quanta',
 CDS_PART_NAME='ISL99390FRZTR5935-ISL99390FRZ-TR5935,SMLF,IC,AL099A',
 PART_NUMBER='AL099390004',
 VALUE='ISL99390FRZ-TR5935',
 PRIM_FILE='./archive_libs/logical/isl99390frztr5935/chips/chips.prt';

PART_NAME
 PU9 'NCP3284AMNTXG-NCP3284AMNTXG,SMLF,IC,AL003284002':;

SECTION_NUMBER 1
 '@T6G_MB_LIB.T6G(SCH_1):PAGE245_I21@PURE_QUANTA.NCP3284AMNTXG(CHIPS)':
 C_PATH='@t6g_mb_lib.t6g(sch_1):page245_i21@pure_quanta.ncp3284amntxg(chips)',
 P_PATH='@t6g_mb_lib.t6g(sch_1):page190_i21@pure_quanta.ncp3284amntxg(chips)',
 PATH='I21',
 DRAWING='@T6G_MB_LIB.T6G(SCH_1):PAGE245',
 PART_TYPE='SMLF',
 MATERIAL='IC',
 PHYS_PAGE='190',
 XY='(-100,-500)',
 ROT='0',
 VER='1',
 LOCATION='PU9',
 CDS_LIB='pure_quanta',
 CDS_PART_NAME='NCP3284AMNTXG-NCP3284AMNTXG,SMLF,IC,AL003284002',
 PART_NUMBER='AL003284002',
 VALUE='NCP3284AMNTXG',
 PRIM_FILE='./archive_libs/logical/ncp3284amntxg/chips/chips.prt';

PART_NAME
 PU10 'ISL99390FRZTR5935-ISL99390FRZ-TR5935,SMLF,IC,AL099A':;

SECTION_NUMBER 1
 '@T6G_MB_LIB.T6G(SCH_1):PAGE171_I73@PURE_QUANTA.ISL99390FRZTR5935(CHIPS)':
 C_PATH='@t6g_mb_lib.t6g(sch_1):page171_i73@pure_quanta.isl99390frztr5935(chips)~
',
 P_PATH='@t6g_mb_lib.t6g(sch_1):page196_i73@pure_quanta.isl99390frztr5935(chips)~
',
 PATH='I73',
 DRAWING='@T6G_MB_LIB.T6G(SCH_1):PAGE171',
 PART_TYPE='SMLF',
 MATERIAL='IC',
 PHYS_PAGE='196',
 XY='(-5700,1850)',
 ROT='0',
 VER='1',
 LOCATION='PU10',
 CDS_LIB='pure_quanta',
 CDS_PART_NAME='ISL99390FRZTR5935-ISL99390FRZ-TR5935,SMLF,IC,AL099A',
 PART_NUMBER='AL099390004',
 VALUE='ISL99390FRZ-TR5935',
 PRIM_FILE='./archive_libs/logical/isl99390frztr5935/chips/chips.prt';

PART_NAME
 PU11 'ISL99390FRZTR5935-ISL99390FRZ-TR5935,SMLF,IC,AL099A':;

SECTION_NUMBER 1
 '@T6G_MB_LIB.T6G(SCH_1):PAGE178_I73@PURE_QUANTA.ISL99390FRZTR5935(CHIPS)':
 C_PATH='@t6g_mb_lib.t6g(sch_1):page178_i73@pure_quanta.isl99390frztr5935(chips)~
',
 P_PATH='@t6g_mb_lib.t6g(sch_1):page203_i73@pure_quanta.isl99390frztr5935(chips)~
',
 PATH='I73',
 DRAWING='@T6G_MB_LIB.T6G(SCH_1):PAGE178',
 PART_TYPE='SMLF',
 MATERIAL='IC',
 PHYS_PAGE='203',
 XY='(3375,2225)',
 ROT='0',
 VER='1',
 LOCATION='PU11',
 CDS_LIB='pure_quanta',
 CDS_PART_NAME='ISL99390FRZTR5935-ISL99390FRZ-TR5935,SMLF,IC,AL099A',
 PART_NUMBER='AL099390004',
 VALUE='ISL99390FRZ-TR5935',
 PRIM_FILE='./archive_libs/logical/isl99390frztr5935/chips/chips.prt';

PART_NAME
 PU12 'RAA229620GNPHA0-RAA229620GNP#HA0,SMLF,IC,ARF0TGP40A':;

SECTION_NUMBER 1
 '@T6G_MB_LIB.T6G(SCH_1):PAGE175_I128@PURE_QUANTA.RAA229620GNPHA0(CHIPS)':
 C_PATH='@t6g_mb_lib.t6g(sch_1):page175_i128@pure_quanta.raa229620gnpha0(chips)',
 P_PATH='@t6g_mb_lib.t6g(sch_1):page200_i128@pure_quanta.raa229620gnpha0(chips)',
 PATH='I128',
 DRAWING='@T6G_MB_LIB.T6G(SCH_1):PAGE175',
 PART_TYPE='SMLF',
 MATERIAL='IC',
 PHYS_PAGE='200',
 XY='(-4100,3550)',
 ROT='0',
 VER='1',
 LOCATION='PU12',
 CDS_LIB='pure_quanta',
 CDS_PART_NAME='RAA229620GNPHA0-RAA229620GNP#HA0,SMLF,IC,ARF0TGP40A',
 PART_NUMBER='ARF0TGP4002',
 VALUE='RAA229620GNP#HA0',
 PRIM_FILE='./archive_libs/logical/raa229620gnpha0/chips/chips.prt';

PART_NAME
 PU13 'ISL99390FRZTR5935-ISL99390FRZ-TR5935,SMLF,IC,AL099A':;

SECTION_NUMBER 1
 '@T6G_MB_LIB.T6G(SCH_1):PAGE176_I35@PURE_QUANTA.ISL99390FRZTR5935(CHIPS)':
 C_PATH='@t6g_mb_lib.t6g(sch_1):page176_i35@pure_quanta.isl99390frztr5935(chips)~
',
 P_PATH='@t6g_mb_lib.t6g(sch_1):page201_i35@pure_quanta.isl99390frztr5935(chips)~
',
 PATH='I35',
 DRAWING='@T6G_MB_LIB.T6G(SCH_1):PAGE176',
 PART_TYPE='SMLF',
 MATERIAL='IC',
 PHYS_PAGE='201',
 XY='(-7200,4125)',
 ROT='0',
 VER='1',
 LOCATION='PU13',
 CDS_LIB='pure_quanta',
 CDS_PART_NAME='ISL99390FRZTR5935-ISL99390FRZ-TR5935,SMLF,IC,AL099A',
 PART_NUMBER='AL099390004',
 VALUE='ISL99390FRZ-TR5935',
 PRIM_FILE='./archive_libs/logical/isl99390frztr5935/chips/chips.prt';

PART_NAME
 PU14 'ISL99390FRZTR5935-ISL99390FRZ-TR5935,SMLF,IC,AL099A':;

SECTION_NUMBER 1
 '@T6G_MB_LIB.T6G(SCH_1):PAGE177_I21@PURE_QUANTA.ISL99390FRZTR5935(CHIPS)':
 C_PATH='@t6g_mb_lib.t6g(sch_1):page177_i21@pure_quanta.isl99390frztr5935(chips)~
',
 P_PATH='@t6g_mb_lib.t6g(sch_1):page202_i21@pure_quanta.isl99390frztr5935(chips)~
',
 PATH='I21',
 DRAWING='@T6G_MB_LIB.T6G(SCH_1):PAGE177',
 PART_TYPE='SMLF',
 MATERIAL='IC',
 PHYS_PAGE='202',
 XY='(3250,1525)',
 ROT='0',
 VER='1',
 LOCATION='PU14',
 CDS_LIB='pure_quanta',
 CDS_PART_NAME='ISL99390FRZTR5935-ISL99390FRZ-TR5935,SMLF,IC,AL099A',
 PART_NUMBER='AL099390004',
 VALUE='ISL99390FRZ-TR5935',
 PRIM_FILE='./archive_libs/logical/isl99390frztr5935/chips/chips.prt';

PART_NAME
 PU15 'ISL99390FRZTR5935-ISL99390FRZ-TR5935,SMLF,IC,AL099A':;

SECTION_NUMBER 1
 '@T6G_MB_LIB.T6G(SCH_1):PAGE177_I23@PURE_QUANTA.ISL99390FRZTR5935(CHIPS)':
 C_PATH='@t6g_mb_lib.t6g(sch_1):page177_i23@pure_quanta.isl99390frztr5935(chips)~
',
 P_PATH='@t6g_mb_lib.t6g(sch_1):page202_i23@pure_quanta.isl99390frztr5935(chips)~
',
 PATH='I23',
 DRAWING='@T6G_MB_LIB.T6G(SCH_1):PAGE177',
 PART_TYPE='SMLF',
 MATERIAL='IC',
 PHYS_PAGE='202',
 XY='(3275,4350)',
 ROT='0',
 VER='1',
 LOCATION='PU15',
 CDS_LIB='pure_quanta',
 CDS_PART_NAME='ISL99390FRZTR5935-ISL99390FRZ-TR5935,SMLF,IC,AL099A',
 PART_NUMBER='AL099390004',
 VALUE='ISL99390FRZ-TR5935',
 PRIM_FILE='./archive_libs/logical/isl99390frztr5935/chips/chips.prt';

PART_NAME
 PU16 'ISL99390FRZTR5935-ISL99390FRZ-TR5935,SMLF,IC,AL099A':;

SECTION_NUMBER 1
 '@T6G_MB_LIB.T6G(SCH_1):PAGE178_I22@PURE_QUANTA.ISL99390FRZTR5935(CHIPS)':
 C_PATH='@t6g_mb_lib.t6g(sch_1):page178_i22@pure_quanta.isl99390frztr5935(chips)~
',
 P_PATH='@t6g_mb_lib.t6g(sch_1):page203_i22@pure_quanta.isl99390frztr5935(chips)~
',
 PATH='I22',
 DRAWING='@T6G_MB_LIB.T6G(SCH_1):PAGE178',
 PART_TYPE='SMLF',
 MATERIAL='IC',
 PHYS_PAGE='203',
 XY='(3400,4875)',
 ROT='0',
 VER='1',
 LOCATION='PU16',
 CDS_LIB='pure_quanta',
 CDS_PART_NAME='ISL99390FRZTR5935-ISL99390FRZ-TR5935,SMLF,IC,AL099A',
 PART_NUMBER='AL099390004',
 VALUE='ISL99390FRZ-TR5935',
 PRIM_FILE='./archive_libs/logical/isl99390frztr5935/chips/chips.prt';

PART_NAME
 PU17 'ISL99390FRZTR5935-ISL99390FRZ-TR5935,SMLF,IC,AL099A':;

SECTION_NUMBER 1
 '@T6G_MB_LIB.T6G(SCH_1):PAGE180_I84@PURE_QUANTA.ISL99390FRZTR5935(CHIPS)':
 C_PATH='@t6g_mb_lib.t6g(sch_1):page180_i84@pure_quanta.isl99390frztr5935(chips)~
',
 P_PATH='@t6g_mb_lib.t6g(sch_1):page205_i84@pure_quanta.isl99390frztr5935(chips)~
',
 PATH='I84',
 DRAWING='@T6G_MB_LIB.T6G(SCH_1):PAGE180',
 PART_TYPE='SMLF',
 MATERIAL='IC',
 PHYS_PAGE='205',
 XY='(2850,4975)',
 ROT='0',
 VER='1',
 LOCATION='PU17',
 CDS_LIB='pure_quanta',
 CDS_PART_NAME='ISL99390FRZTR5935-ISL99390FRZ-TR5935,SMLF,IC,AL099A',
 PART_NUMBER='AL099390004',
 VALUE='ISL99390FRZ-TR5935',
 PRIM_FILE='./archive_libs/logical/isl99390frztr5935/chips/chips.prt';

PART_NAME
 PU18 'ISL99390FRZTR5935-ISL99390FRZ-TR5935,SMLF,IC,AL099A':;

SECTION_NUMBER 1
 '@T6G_MB_LIB.T6G(SCH_1):PAGE180_I15@PURE_QUANTA.ISL99390FRZTR5935(CHIPS)':
 C_PATH='@t6g_mb_lib.t6g(sch_1):page180_i15@pure_quanta.isl99390frztr5935(chips)~
',
 P_PATH='@t6g_mb_lib.t6g(sch_1):page205_i15@pure_quanta.isl99390frztr5935(chips)~
',
 PATH='I15',
 DRAWING='@T6G_MB_LIB.T6G(SCH_1):PAGE180',
 PART_TYPE='SMLF',
 MATERIAL='IC',
 PHYS_PAGE='205',
 XY='(2850,2175)',
 ROT='0',
 VER='1',
 LOCATION='PU18',
 CDS_LIB='pure_quanta',
 CDS_PART_NAME='ISL99390FRZTR5935-ISL99390FRZ-TR5935,SMLF,IC,AL099A',
 PART_NUMBER='AL099390004',
 VALUE='ISL99390FRZ-TR5935',
 PRIM_FILE='./archive_libs/logical/isl99390frztr5935/chips/chips.prt';

PART_NAME
 PU19 'ISL99390FRZTR5935-ISL99390FRZ-TR5935,SMLF,IC,AL099A':;

SECTION_NUMBER 1
 '@T6G_MB_LIB.T6G(SCH_1):PAGE181_I32@PURE_QUANTA.ISL99390FRZTR5935(CHIPS)':
 C_PATH='@t6g_mb_lib.t6g(sch_1):page181_i32@pure_quanta.isl99390frztr5935(chips)~
',
 P_PATH='@t6g_mb_lib.t6g(sch_1):page206_i32@pure_quanta.isl99390frztr5935(chips)~
',
 PATH='I32',
 DRAWING='@T6G_MB_LIB.T6G(SCH_1):PAGE181',
 PART_TYPE='SMLF',
 MATERIAL='IC',
 PHYS_PAGE='206',
 XY='(-9350,5425)',
 ROT='0',
 VER='1',
 LOCATION='PU19',
 CDS_LIB='pure_quanta',
 CDS_PART_NAME='ISL99390FRZTR5935-ISL99390FRZ-TR5935,SMLF,IC,AL099A',
 PART_NUMBER='AL099390004',
 VALUE='ISL99390FRZ-TR5935',
 PRIM_FILE='./archive_libs/logical/isl99390frztr5935/chips/chips.prt';

PART_NAME
 PU20 'ISL99390FRZTR5935-ISL99390FRZ-TR5935,SMLF,IC,AL099A':;

SECTION_NUMBER 1
 '@T6G_MB_LIB.T6G(SCH_1):PAGE181_I73@PURE_QUANTA.ISL99390FRZTR5935(CHIPS)':
 C_PATH='@t6g_mb_lib.t6g(sch_1):page181_i73@pure_quanta.isl99390frztr5935(chips)~
',
 P_PATH='@t6g_mb_lib.t6g(sch_1):page206_i73@pure_quanta.isl99390frztr5935(chips)~
',
 PATH='I73',
 DRAWING='@T6G_MB_LIB.T6G(SCH_1):PAGE181',
 PART_TYPE='SMLF',
 MATERIAL='IC',
 PHYS_PAGE='206',
 XY='(-9350,2625)',
 ROT='0',
 VER='1',
 LOCATION='PU20',
 CDS_LIB='pure_quanta',
 CDS_PART_NAME='ISL99390FRZTR5935-ISL99390FRZ-TR5935,SMLF,IC,AL099A',
 PART_NUMBER='AL099390004',
 VALUE='ISL99390FRZ-TR5935',
 PRIM_FILE='./archive_libs/logical/isl99390frztr5935/chips/chips.prt';

PART_NAME
 PU21 'RAA229621GNPHA0-RAA229621GNP#HA0,SMLF,IC,ARF0TGP40A':;

SECTION_NUMBER 1
 '@T6G_MB_LIB.T6G(SCH_1):PAGE182_I24@PURE_QUANTA.RAA229621GNPHA0(CHIPS)':
 C_PATH='@t6g_mb_lib.t6g(sch_1):page182_i24@pure_quanta.raa229621gnpha0(chips)',
 P_PATH='@t6g_mb_lib.t6g(sch_1):page207_i24@pure_quanta.raa229621gnpha0(chips)',
 PATH='I24',
 DRAWING='@T6G_MB_LIB.T6G(SCH_1):PAGE182',
 PART_TYPE='SMLF',
 MATERIAL='IC',
 PHYS_PAGE='207',
 XY='(-4425,3375)',
 ROT='0',
 VER='1',
 LOCATION='PU21',
 CDS_LIB='pure_quanta',
 CDS_PART_NAME='RAA229621GNPHA0-RAA229621GNP#HA0,SMLF,IC,ARF0TGP40A',
 PART_NUMBER='ARF0TGP4003',
 VALUE='RAA229621GNP#HA0',
 PRIM_FILE='./archive_libs/logical/raa229621gnpha0/chips/chips.prt';

PART_NAME
 PU22 'ISL99390FRZTR5935-ISL99390FRZ-TR5935,SMLF,IC,AL099A':;

SECTION_NUMBER 1
 '@T6G_MB_LIB.T6G(SCH_1):PAGE183_I92@PURE_QUANTA.ISL99390FRZTR5935(CHIPS)':
 C_PATH='@t6g_mb_lib.t6g(sch_1):page183_i92@pure_quanta.isl99390frztr5935(chips)~
',
 P_PATH='@t6g_mb_lib.t6g(sch_1):page208_i92@pure_quanta.isl99390frztr5935(chips)~
',
 PATH='I92',
 DRAWING='@T6G_MB_LIB.T6G(SCH_1):PAGE183',
 PART_TYPE='SMLF',
 MATERIAL='IC',
 PHYS_PAGE='208',
 XY='(-6050,4425)',
 ROT='0',
 VER='1',
 LOCATION='PU22',
 CDS_LIB='pure_quanta',
 CDS_PART_NAME='ISL99390FRZTR5935-ISL99390FRZ-TR5935,SMLF,IC,AL099A',
 PART_NUMBER='AL099390004',
 VALUE='ISL99390FRZ-TR5935',
 PRIM_FILE='./archive_libs/logical/isl99390frztr5935/chips/chips.prt';

PART_NAME
 PU23 'ISL99390FRZTR5935-ISL99390FRZ-TR5935,SMLF,IC,AL099A':;

SECTION_NUMBER 1
 '@T6G_MB_LIB.T6G(SCH_1):PAGE183_I13@PURE_QUANTA.ISL99390FRZTR5935(CHIPS)':
 C_PATH='@t6g_mb_lib.t6g(sch_1):page183_i13@pure_quanta.isl99390frztr5935(chips)~
',
 P_PATH='@t6g_mb_lib.t6g(sch_1):page208_i13@pure_quanta.isl99390frztr5935(chips)~
',
 PATH='I13',
 DRAWING='@T6G_MB_LIB.T6G(SCH_1):PAGE183',
 PART_TYPE='SMLF',
 MATERIAL='IC',
 PHYS_PAGE='208',
 XY='(-6000,1500)',
 ROT='0',
 VER='1',
 LOCATION='PU23',
 CDS_LIB='pure_quanta',
 CDS_PART_NAME='ISL99390FRZTR5935-ISL99390FRZ-TR5935,SMLF,IC,AL099A',
 PART_NUMBER='AL099390004',
 VALUE='ISL99390FRZ-TR5935',
 PRIM_FILE='./archive_libs/logical/isl99390frztr5935/chips/chips.prt';

PART_NAME
 PU24 'ISL99390FRZTR5935-ISL99390FRZ-TR5935,SMLF,IC,AL099A':;

SECTION_NUMBER 1
 '@T6G_MB_LIB.T6G(SCH_1):PAGE188_I73@PURE_QUANTA.ISL99390FRZTR5935(CHIPS)':
 C_PATH='@t6g_mb_lib.t6g(sch_1):page188_i73@pure_quanta.isl99390frztr5935(chips)~
',
 P_PATH='@t6g_mb_lib.t6g(sch_1):page213_i73@pure_quanta.isl99390frztr5935(chips)~
',
 PATH='I73',
 DRAWING='@T6G_MB_LIB.T6G(SCH_1):PAGE188',
 PART_TYPE='SMLF',
 MATERIAL='IC',
 PHYS_PAGE='213',
 XY='(-5650,1950)',
 ROT='0',
 VER='1',
 LOCATION='PU24',
 CDS_LIB='pure_quanta',
 CDS_PART_NAME='ISL99390FRZTR5935-ISL99390FRZ-TR5935,SMLF,IC,AL099A',
 PART_NUMBER='AL099390004',
 VALUE='ISL99390FRZ-TR5935',
 PRIM_FILE='./archive_libs/logical/isl99390frztr5935/chips/chips.prt';

PART_NAME
 PU25 'RAA229620GNPHA0-RAA229620GNP#HA0,SMLF,IC,ARF0TGP40A':;

SECTION_NUMBER 1
 '@T6G_MB_LIB.T6G(SCH_1):PAGE185_I133@PURE_QUANTA.RAA229620GNPHA0(CHIPS)':
 C_PATH='@t6g_mb_lib.t6g(sch_1):page185_i133@pure_quanta.raa229620gnpha0(chips)',
 P_PATH='@t6g_mb_lib.t6g(sch_1):page210_i133@pure_quanta.raa229620gnpha0(chips)',
 PATH='I133',
 DRAWING='@T6G_MB_LIB.T6G(SCH_1):PAGE185',
 SEC_TYPE='',
 PART_TYPE='SMLF',
 MATERIAL='IC',
 PHYS_PAGE='210',
 XY='(-1075,5125)',
 ROT='0',
 VER='1',
 LOCATION='PU25',
 SEC='1',
 CDS_LIB='pure_quanta',
 CDS_PART_NAME='RAA229620GNPHA0-RAA229620GNP#HA0,SMLF,IC,ARF0TGP40A',
 PART_NUMBER='ARF0TGP4002',
 VALUE='RAA229620GNP#HA0',
 PRIM_FILE='./archive_libs/logical/raa229620gnpha0/chips/chips.prt';

PART_NAME
 PU26 'ISL99390FRZTR5935-ISL99390FRZ-TR5935,SMLF,IC,AL099A':;

SECTION_NUMBER 1
 '@T6G_MB_LIB.T6G(SCH_1):PAGE186_I91@PURE_QUANTA.ISL99390FRZTR5935(CHIPS)':
 C_PATH='@t6g_mb_lib.t6g(sch_1):page186_i91@pure_quanta.isl99390frztr5935(chips)~
',
 P_PATH='@t6g_mb_lib.t6g(sch_1):page211_i91@pure_quanta.isl99390frztr5935(chips)~
',
 PATH='I91',
 DRAWING='@T6G_MB_LIB.T6G(SCH_1):PAGE186',
 PART_TYPE='SMLF',
 MATERIAL='IC',
 PHYS_PAGE='211',
 XY='(-6100,1700)',
 ROT='0',
 VER='1',
 LOCATION='PU26',
 CDS_LIB='pure_quanta',
 CDS_PART_NAME='ISL99390FRZTR5935-ISL99390FRZ-TR5935,SMLF,IC,AL099A',
 PART_NUMBER='AL099390004',
 VALUE='ISL99390FRZ-TR5935',
 PRIM_FILE='./archive_libs/logical/isl99390frztr5935/chips/chips.prt';

PART_NAME
 PU27 'ISL99390FRZTR5935-ISL99390FRZ-TR5935,SMLF,IC,AL099A':;

SECTION_NUMBER 1
 '@T6G_MB_LIB.T6G(SCH_1):PAGE187_I39@PURE_QUANTA.ISL99390FRZTR5935(CHIPS)':
 C_PATH='@t6g_mb_lib.t6g(sch_1):page187_i39@pure_quanta.isl99390frztr5935(chips)~
',
 P_PATH='@t6g_mb_lib.t6g(sch_1):page212_i39@pure_quanta.isl99390frztr5935(chips)~
',
 PATH='I39',
 DRAWING='@T6G_MB_LIB.T6G(SCH_1):PAGE187',
 PART_TYPE='SMLF',
 MATERIAL='IC',
 PHYS_PAGE='212',
 XY='(-5750,4875)',
 ROT='0',
 VER='1',
 LOCATION='PU27',
 CDS_LIB='pure_quanta',
 CDS_PART_NAME='ISL99390FRZTR5935-ISL99390FRZ-TR5935,SMLF,IC,AL099A',
 PART_NUMBER='AL099390004',
 VALUE='ISL99390FRZ-TR5935',
 PRIM_FILE='./archive_libs/logical/isl99390frztr5935/chips/chips.prt';

PART_NAME
 PU28 'ISL99390FRZTR5935-ISL99390FRZ-TR5935,SMLF,IC,AL099A':;

SECTION_NUMBER 1
 '@T6G_MB_LIB.T6G(SCH_1):PAGE187_I9@PURE_QUANTA.ISL99390FRZTR5935(CHIPS)':
 C_PATH='@t6g_mb_lib.t6g(sch_1):page187_i9@pure_quanta.isl99390frztr5935(chips)',
 P_PATH='@t6g_mb_lib.t6g(sch_1):page212_i9@pure_quanta.isl99390frztr5935(chips)',
 PATH='I9',
 DRAWING='@T6G_MB_LIB.T6G(SCH_1):PAGE187',
 PART_TYPE='SMLF',
 MATERIAL='IC',
 PHYS_PAGE='212',
 XY='(-5675,1575)',
 ROT='0',
 VER='1',
 LOCATION='PU28',
 CDS_LIB='pure_quanta',
 CDS_PART_NAME='ISL99390FRZTR5935-ISL99390FRZ-TR5935,SMLF,IC,AL099A',
 PART_NUMBER='AL099390004',
 VALUE='ISL99390FRZ-TR5935',
 PRIM_FILE='./archive_libs/logical/isl99390frztr5935/chips/chips.prt';

PART_NAME
 PU29 'ISL99390FRZTR5935-ISL99390FRZ-TR5935,SMLF,IC,AL099A':;

SECTION_NUMBER 1
 '@T6G_MB_LIB.T6G(SCH_1):PAGE188_I18@PURE_QUANTA.ISL99390FRZTR5935(CHIPS)':
 C_PATH='@t6g_mb_lib.t6g(sch_1):page188_i18@pure_quanta.isl99390frztr5935(chips)~
',
 P_PATH='@t6g_mb_lib.t6g(sch_1):page213_i18@pure_quanta.isl99390frztr5935(chips)~
',
 PATH='I18',
 DRAWING='@T6G_MB_LIB.T6G(SCH_1):PAGE188',
 PART_TYPE='SMLF',
 MATERIAL='IC',
 PHYS_PAGE='213',
 XY='(-5700,4850)',
 ROT='0',
 VER='1',
 LOCATION='PU29',
 CDS_LIB='pure_quanta',
 CDS_PART_NAME='ISL99390FRZTR5935-ISL99390FRZ-TR5935,SMLF,IC,AL099A',
 PART_NUMBER='AL099390004',
 VALUE='ISL99390FRZ-TR5935',
 PRIM_FILE='./archive_libs/logical/isl99390frztr5935/chips/chips.prt';

PART_NAME
 PU30 'ISL99390FRZTR5935-ISL99390FRZ-TR5935,SMLF,IC,AL099A':;

SECTION_NUMBER 1
 '@T6G_MB_LIB.T6G(SCH_1):PAGE190_I17@PURE_QUANTA.ISL99390FRZTR5935(CHIPS)':
 C_PATH='@t6g_mb_lib.t6g(sch_1):page190_i17@pure_quanta.isl99390frztr5935(chips)~
',
 P_PATH='@t6g_mb_lib.t6g(sch_1):page215_i17@pure_quanta.isl99390frztr5935(chips)~
',
 PATH='I17',
 DRAWING='@T6G_MB_LIB.T6G(SCH_1):PAGE190',
 PART_TYPE='SMLF',
 MATERIAL='IC',
 PHYS_PAGE='215',
 XY='(-6050,4750)',
 ROT='0',
 VER='1',
 LOCATION='PU30',
 CDS_LIB='pure_quanta',
 CDS_PART_NAME='ISL99390FRZTR5935-ISL99390FRZ-TR5935,SMLF,IC,AL099A',
 PART_NUMBER='AL099390004',
 VALUE='ISL99390FRZ-TR5935',
 PRIM_FILE='./archive_libs/logical/isl99390frztr5935/chips/chips.prt';

PART_NAME
 PU31 'ISL99390FRZTR5935-ISL99390FRZ-TR5935,SMLF,IC,AL099A':;

SECTION_NUMBER 1
 '@T6G_MB_LIB.T6G(SCH_1):PAGE190_I86@PURE_QUANTA.ISL99390FRZTR5935(CHIPS)':
 C_PATH='@t6g_mb_lib.t6g(sch_1):page190_i86@pure_quanta.isl99390frztr5935(chips)~
',
 P_PATH='@t6g_mb_lib.t6g(sch_1):page215_i86@pure_quanta.isl99390frztr5935(chips)~
',
 PATH='I86',
 DRAWING='@T6G_MB_LIB.T6G(SCH_1):PAGE190',
 PART_TYPE='SMLF',
 MATERIAL='IC',
 PHYS_PAGE='215',
 XY='(-6025,1975)',
 ROT='0',
 VER='1',
 LOCATION='PU31',
 CDS_LIB='pure_quanta',
 CDS_PART_NAME='ISL99390FRZTR5935-ISL99390FRZ-TR5935,SMLF,IC,AL099A',
 PART_NUMBER='AL099390004',
 VALUE='ISL99390FRZ-TR5935',
 PRIM_FILE='./archive_libs/logical/isl99390frztr5935/chips/chips.prt';

PART_NAME
 PU32 'ISL99390FRZTR5935-ISL99390FRZ-TR5935,SMLF,IC,AL099A':;

SECTION_NUMBER 1
 '@T6G_MB_LIB.T6G(SCH_1):PAGE191_I38@PURE_QUANTA.ISL99390FRZTR5935(CHIPS)':
 C_PATH='@t6g_mb_lib.t6g(sch_1):page191_i38@pure_quanta.isl99390frztr5935(chips)~
',
 P_PATH='@t6g_mb_lib.t6g(sch_1):page216_i38@pure_quanta.isl99390frztr5935(chips)~
',
 PATH='I38',
 DRAWING='@T6G_MB_LIB.T6G(SCH_1):PAGE191',
 PART_TYPE='SMLF',
 MATERIAL='IC',
 PHYS_PAGE='216',
 XY='(-5850,4500)',
 ROT='0',
 VER='1',
 LOCATION='PU32',
 CDS_LIB='pure_quanta',
 CDS_PART_NAME='ISL99390FRZTR5935-ISL99390FRZ-TR5935,SMLF,IC,AL099A',
 PART_NUMBER='AL099390004',
 VALUE='ISL99390FRZ-TR5935',
 PRIM_FILE='./archive_libs/logical/isl99390frztr5935/chips/chips.prt';

PART_NAME
 PU33 'ISL99390FRZTR5935-ISL99390FRZ-TR5935,SMLF,IC,AL099A':;

SECTION_NUMBER 1
 '@T6G_MB_LIB.T6G(SCH_1):PAGE195_I19@PURE_QUANTA.ISL99390FRZTR5935(CHIPS)':
 C_PATH='@t6g_mb_lib.t6g(sch_1):page195_i19@pure_quanta.isl99390frztr5935(chips)~
',
 P_PATH='@t6g_mb_lib.t6g(sch_1):page220_i19@pure_quanta.isl99390frztr5935(chips)~
',
 PATH='I19',
 DRAWING='@T6G_MB_LIB.T6G(SCH_1):PAGE195',
 PART_TYPE='SMLF',
 MATERIAL='IC',
 PHYS_PAGE='220',
 XY='(3200,2225)',
 ROT='0',
 VER='1',
 LOCATION='PU33',
 CDS_LIB='pure_quanta',
 CDS_PART_NAME='ISL99390FRZTR5935-ISL99390FRZ-TR5935,SMLF,IC,AL099A',
 PART_NUMBER='AL099390004',
 VALUE='ISL99390FRZ-TR5935',
 PRIM_FILE='./archive_libs/logical/isl99390frztr5935/chips/chips.prt';

PART_NAME
 PU34 'RAA229620GNPHA0-RAA229620GNP#HA0,SMLF,IC,ARF0TGP40A':;

SECTION_NUMBER 1
 '@T6G_MB_LIB.T6G(SCH_1):PAGE192_I128@PURE_QUANTA.RAA229620GNPHA0(CHIPS)':
 C_PATH='@t6g_mb_lib.t6g(sch_1):page192_i128@pure_quanta.raa229620gnpha0(chips)',
 P_PATH='@t6g_mb_lib.t6g(sch_1):page217_i128@pure_quanta.raa229620gnpha0(chips)',
 PATH='I128',
 DRAWING='@T6G_MB_LIB.T6G(SCH_1):PAGE192',
 SEC_TYPE='',
 PART_TYPE='SMLF',
 MATERIAL='IC',
 PHYS_PAGE='217',
 XY='(-475,4475)',
 ROT='0',
 VER='1',
 LOCATION='PU34',
 SEC='1',
 CDS_LIB='pure_quanta',
 CDS_PART_NAME='RAA229620GNPHA0-RAA229620GNP#HA0,SMLF,IC,ARF0TGP40A',
 PART_NUMBER='ARF0TGP4002',
 VALUE='RAA229620GNP#HA0',
 PRIM_FILE='./archive_libs/logical/raa229620gnpha0/chips/chips.prt';

PART_NAME
 PU35 'ISL99390FRZTR5935-ISL99390FRZ-TR5935,SMLF,IC,AL099A':;

SECTION_NUMBER 1
 '@T6G_MB_LIB.T6G(SCH_1):PAGE193_I91@PURE_QUANTA.ISL99390FRZTR5935(CHIPS)':
 C_PATH='@t6g_mb_lib.t6g(sch_1):page193_i91@pure_quanta.isl99390frztr5935(chips)~
',
 P_PATH='@t6g_mb_lib.t6g(sch_1):page218_i91@pure_quanta.isl99390frztr5935(chips)~
',
 PATH='I91',
 DRAWING='@T6G_MB_LIB.T6G(SCH_1):PAGE193',
 PART_TYPE='SMLF',
 MATERIAL='IC',
 PHYS_PAGE='218',
 XY='(-6800,4600)',
 ROT='0',
 VER='1',
 LOCATION='PU35',
 CDS_LIB='pure_quanta',
 CDS_PART_NAME='ISL99390FRZTR5935-ISL99390FRZ-TR5935,SMLF,IC,AL099A',
 PART_NUMBER='AL099390004',
 VALUE='ISL99390FRZ-TR5935',
 PRIM_FILE='./archive_libs/logical/isl99390frztr5935/chips/chips.prt';

PART_NAME
 PU36 'ISL99390FRZTR5935-ISL99390FRZ-TR5935,SMLF,IC,AL099A':;

SECTION_NUMBER 1
 '@T6G_MB_LIB.T6G(SCH_1):PAGE194_I21@PURE_QUANTA.ISL99390FRZTR5935(CHIPS)':
 C_PATH='@t6g_mb_lib.t6g(sch_1):page194_i21@pure_quanta.isl99390frztr5935(chips)~
',
 P_PATH='@t6g_mb_lib.t6g(sch_1):page219_i21@pure_quanta.isl99390frztr5935(chips)~
',
 PATH='I21',
 DRAWING='@T6G_MB_LIB.T6G(SCH_1):PAGE194',
 PART_TYPE='SMLF',
 MATERIAL='IC',
 PHYS_PAGE='219',
 XY='(3275,1475)',
 ROT='0',
 VER='1',
 LOCATION='PU36',
 CDS_LIB='pure_quanta',
 CDS_PART_NAME='ISL99390FRZTR5935-ISL99390FRZ-TR5935,SMLF,IC,AL099A',
 PART_NUMBER='AL099390004',
 VALUE='ISL99390FRZ-TR5935',
 PRIM_FILE='./archive_libs/logical/isl99390frztr5935/chips/chips.prt';

PART_NAME
 PU37 'ISL99390FRZTR5935-ISL99390FRZ-TR5935,SMLF,IC,AL099A':;

SECTION_NUMBER 1
 '@T6G_MB_LIB.T6G(SCH_1):PAGE194_I72@PURE_QUANTA.ISL99390FRZTR5935(CHIPS)':
 C_PATH='@t6g_mb_lib.t6g(sch_1):page194_i72@pure_quanta.isl99390frztr5935(chips)~
',
 P_PATH='@t6g_mb_lib.t6g(sch_1):page219_i72@pure_quanta.isl99390frztr5935(chips)~
',
 PATH='I72',
 DRAWING='@T6G_MB_LIB.T6G(SCH_1):PAGE194',
 PART_TYPE='SMLF',
 MATERIAL='IC',
 PHYS_PAGE='219',
 XY='(3300,4300)',
 ROT='0',
 VER='1',
 LOCATION='PU37',
 CDS_LIB='pure_quanta',
 CDS_PART_NAME='ISL99390FRZTR5935-ISL99390FRZ-TR5935,SMLF,IC,AL099A',
 PART_NUMBER='AL099390004',
 VALUE='ISL99390FRZ-TR5935',
 PRIM_FILE='./archive_libs/logical/isl99390frztr5935/chips/chips.prt';

PART_NAME
 PU38 'ISL99390FRZTR5935-ISL99390FRZ-TR5935,SMLF,IC,AL099A':;

SECTION_NUMBER 1
 '@T6G_MB_LIB.T6G(SCH_1):PAGE195_I73@PURE_QUANTA.ISL99390FRZTR5935(CHIPS)':
 C_PATH='@t6g_mb_lib.t6g(sch_1):page195_i73@pure_quanta.isl99390frztr5935(chips)~
',
 P_PATH='@t6g_mb_lib.t6g(sch_1):page220_i73@pure_quanta.isl99390frztr5935(chips)~
',
 PATH='I73',
 DRAWING='@T6G_MB_LIB.T6G(SCH_1):PAGE195',
 PART_TYPE='SMLF',
 MATERIAL='IC',
 PHYS_PAGE='220',
 XY='(3150,4850)',
 ROT='0',
 VER='1',
 LOCATION='PU38',
 CDS_LIB='pure_quanta',
 CDS_PART_NAME='ISL99390FRZTR5935-ISL99390FRZ-TR5935,SMLF,IC,AL099A',
 PART_NUMBER='AL099390004',
 VALUE='ISL99390FRZ-TR5935',
 PRIM_FILE='./archive_libs/logical/isl99390frztr5935/chips/chips.prt';

PART_NAME
 PU39 'ISL99390FRZTR5935-ISL99390FRZ-TR5935,SMLF,IC,AL099A':;

SECTION_NUMBER 1
 '@T6G_MB_LIB.T6G(SCH_1):PAGE197_I39@PURE_QUANTA.ISL99390FRZTR5935(CHIPS)':
 C_PATH='@t6g_mb_lib.t6g(sch_1):page197_i39@pure_quanta.isl99390frztr5935(chips)~
',
 P_PATH='@t6g_mb_lib.t6g(sch_1):page222_i39@pure_quanta.isl99390frztr5935(chips)~
',
 PATH='I39',
 DRAWING='@T6G_MB_LIB.T6G(SCH_1):PAGE197',
 PART_TYPE='SMLF',
 MATERIAL='IC',
 PHYS_PAGE='222',
 XY='(2650,5000)',
 ROT='0',
 VER='1',
 LOCATION='PU39',
 CDS_LIB='pure_quanta',
 CDS_PART_NAME='ISL99390FRZTR5935-ISL99390FRZ-TR5935,SMLF,IC,AL099A',
 PART_NUMBER='AL099390004',
 VALUE='ISL99390FRZ-TR5935',
 PRIM_FILE='./archive_libs/logical/isl99390frztr5935/chips/chips.prt';

PART_NAME
 PU40 'ISL99390FRZTR5935-ISL99390FRZ-TR5935,SMLF,IC,AL099A':;

SECTION_NUMBER 1
 '@T6G_MB_LIB.T6G(SCH_1):PAGE197_I84@PURE_QUANTA.ISL99390FRZTR5935(CHIPS)':
 C_PATH='@t6g_mb_lib.t6g(sch_1):page197_i84@pure_quanta.isl99390frztr5935(chips)~
',
 P_PATH='@t6g_mb_lib.t6g(sch_1):page222_i84@pure_quanta.isl99390frztr5935(chips)~
',
 PATH='I84',
 DRAWING='@T6G_MB_LIB.T6G(SCH_1):PAGE197',
 PART_TYPE='SMLF',
 MATERIAL='IC',
 PHYS_PAGE='222',
 XY='(2650,2250)',
 ROT='0',
 VER='1',
 LOCATION='PU40',
 CDS_LIB='pure_quanta',
 CDS_PART_NAME='ISL99390FRZTR5935-ISL99390FRZ-TR5935,SMLF,IC,AL099A',
 PART_NUMBER='AL099390004',
 VALUE='ISL99390FRZ-TR5935',
 PRIM_FILE='./archive_libs/logical/isl99390frztr5935/chips/chips.prt';

PART_NAME
 PU42 'RAA229620GNPHA0-RAA229620GNP#HA0,SMLF,IC,ARF0TGP40A':;

SECTION_NUMBER 1
 '@T6G_MB_LIB.T6G(SCH_1):PAGE168_I135@PURE_QUANTA.RAA229620GNPHA0(CHIPS)':
 C_PATH='@t6g_mb_lib.t6g(sch_1):page168_i135@pure_quanta.raa229620gnpha0(chips)',
 P_PATH='@t6g_mb_lib.t6g(sch_1):page193_i135@pure_quanta.raa229620gnpha0(chips)',
 PATH='I135',
 DRAWING='@T6G_MB_LIB.T6G(SCH_1):PAGE168',
 SEC_TYPE='',
 PART_TYPE='SMLF',
 MATERIAL='IC',
 PHYS_PAGE='193',
 XY='(-3900,3750)',
 ROT='0',
 VER='1',
 LOCATION='PU42',
 SEC='1',
 CDS_LIB='pure_quanta',
 CDS_PART_NAME='RAA229620GNPHA0-RAA229620GNP#HA0,SMLF,IC,ARF0TGP40A',
 PART_NUMBER='ARF0TGP4002',
 VALUE='RAA229620GNP#HA0',
 PRIM_FILE='./archive_libs/logical/raa229620gnpha0/chips/chips.prt';

PART_NAME
 PU43 'ISL99390FRZTR5935-ISL99390FRZ-TR5935,SMLF,IC,AL099A':;

SECTION_NUMBER 1
 '@T6G_MB_LIB.T6G(SCH_1):PAGE169_I16@PURE_QUANTA.ISL99390FRZTR5935(CHIPS)':
 C_PATH='@t6g_mb_lib.t6g(sch_1):page169_i16@pure_quanta.isl99390frztr5935(chips)~
',
 P_PATH='@t6g_mb_lib.t6g(sch_1):page194_i16@pure_quanta.isl99390frztr5935(chips)~
',
 PATH='I16',
 DRAWING='@T6G_MB_LIB.T6G(SCH_1):PAGE169',
 PART_TYPE='SMLF',
 MATERIAL='IC',
 PHYS_PAGE='194',
 XY='(-6175,1600)',
 ROT='0',
 VER='1',
 LOCATION='PU43',
 CDS_LIB='pure_quanta',
 CDS_PART_NAME='ISL99390FRZTR5935-ISL99390FRZ-TR5935,SMLF,IC,AL099A',
 PART_NUMBER='AL099390004',
 VALUE='ISL99390FRZ-TR5935',
 PRIM_FILE='./archive_libs/logical/isl99390frztr5935/chips/chips.prt';

PART_NAME
 PU44 'ISL99390FRZTR5935-ISL99390FRZ-TR5935,SMLF,IC,AL099A':;

SECTION_NUMBER 1
 '@T6G_MB_LIB.T6G(SCH_1):PAGE200_I22@PURE_QUANTA.ISL99390FRZTR5935(CHIPS)':
 C_PATH='@t6g_mb_lib.t6g(sch_1):page200_i22@pure_quanta.isl99390frztr5935(chips)~
',
 P_PATH='@t6g_mb_lib.t6g(sch_1):page225_i22@pure_quanta.isl99390frztr5935(chips)~
',
 PATH='I22',
 DRAWING='@T6G_MB_LIB.T6G(SCH_1):PAGE200',
 PART_TYPE='SMLF',
 MATERIAL='IC',
 PHYS_PAGE='225',
 XY='(-6050,4625)',
 ROT='0',
 VER='1',
 LOCATION='PU44',
 CDS_LIB='pure_quanta',
 CDS_PART_NAME='ISL99390FRZTR5935-ISL99390FRZ-TR5935,SMLF,IC,AL099A',
 PART_NUMBER='AL099390004',
 VALUE='ISL99390FRZ-TR5935',
 PRIM_FILE='./archive_libs/logical/isl99390frztr5935/chips/chips.prt';

PART_NAME
 PU45 'ISL99390FRZTR5935-ISL99390FRZ-TR5935,SMLF,IC,AL099A':;

SECTION_NUMBER 1
 '@T6G_MB_LIB.T6G(SCH_1):PAGE200_I92@PURE_QUANTA.ISL99390FRZTR5935(CHIPS)':
 C_PATH='@t6g_mb_lib.t6g(sch_1):page200_i92@pure_quanta.isl99390frztr5935(chips)~
',
 P_PATH='@t6g_mb_lib.t6g(sch_1):page225_i92@pure_quanta.isl99390frztr5935(chips)~
',
 PATH='I92',
 DRAWING='@T6G_MB_LIB.T6G(SCH_1):PAGE200',
 PART_TYPE='SMLF',
 MATERIAL='IC',
 PHYS_PAGE='225',
 XY='(-6000,1700)',
 ROT='0',
 VER='1',
 LOCATION='PU45',
 CDS_LIB='pure_quanta',
 CDS_PART_NAME='ISL99390FRZTR5935-ISL99390FRZ-TR5935,SMLF,IC,AL099A',
 PART_NUMBER='AL099390004',
 VALUE='ISL99390FRZ-TR5935',
 PRIM_FILE='./archive_libs/logical/isl99390frztr5935/chips/chips.prt';

PART_NAME
 PU46 'ISL99390FRZTR5935-ISL99390FRZ-TR5935,SMLF,IC,AL099A':;

SECTION_NUMBER 1
 '@T6G_MB_LIB.T6G(SCH_1):PAGE170_I38@PURE_QUANTA.ISL99390FRZTR5935(CHIPS)':
 C_PATH='@t6g_mb_lib.t6g(sch_1):page170_i38@pure_quanta.isl99390frztr5935(chips)~
',
 P_PATH='@t6g_mb_lib.t6g(sch_1):page195_i38@pure_quanta.isl99390frztr5935(chips)~
',
 PATH='I38',
 DRAWING='@T6G_MB_LIB.T6G(SCH_1):PAGE170',
 PART_TYPE='SMLF',
 MATERIAL='IC',
 PHYS_PAGE='195',
 XY='(-5850,4800)',
 ROT='0',
 VER='1',
 LOCATION='PU46',
 CDS_LIB='pure_quanta',
 CDS_PART_NAME='ISL99390FRZTR5935-ISL99390FRZ-TR5935,SMLF,IC,AL099A',
 PART_NUMBER='AL099390004',
 VALUE='ISL99390FRZ-TR5935',
 PRIM_FILE='./archive_libs/logical/isl99390frztr5935/chips/chips.prt';

PART_NAME
 PU47 'ISL99390FRZTR5935-ISL99390FRZ-TR5935,SMLF,IC,AL099A':;

SECTION_NUMBER 1
 '@T6G_MB_LIB.T6G(SCH_1):PAGE170_I9@PURE_QUANTA.ISL99390FRZTR5935(CHIPS)':
 C_PATH='@t6g_mb_lib.t6g(sch_1):page170_i9@pure_quanta.isl99390frztr5935(chips)',
 P_PATH='@t6g_mb_lib.t6g(sch_1):page195_i9@pure_quanta.isl99390frztr5935(chips)',
 PATH='I9',
 DRAWING='@T6G_MB_LIB.T6G(SCH_1):PAGE170',
 PART_TYPE='SMLF',
 MATERIAL='IC',
 PHYS_PAGE='195',
 XY='(-5775,1500)',
 ROT='0',
 VER='1',
 LOCATION='PU47',
 CDS_LIB='pure_quanta',
 CDS_PART_NAME='ISL99390FRZTR5935-ISL99390FRZ-TR5935,SMLF,IC,AL099A',
 PART_NUMBER='AL099390004',
 VALUE='ISL99390FRZ-TR5935',
 PRIM_FILE='./archive_libs/logical/isl99390frztr5935/chips/chips.prt';

PART_NAME
 PU48 'ISL99390FRZTR5935-ISL99390FRZ-TR5935,SMLF,IC,AL099A':;

SECTION_NUMBER 1
 '@T6G_MB_LIB.T6G(SCH_1):PAGE171_I18@PURE_QUANTA.ISL99390FRZTR5935(CHIPS)':
 C_PATH='@t6g_mb_lib.t6g(sch_1):page171_i18@pure_quanta.isl99390frztr5935(chips)~
',
 P_PATH='@t6g_mb_lib.t6g(sch_1):page196_i18@pure_quanta.isl99390frztr5935(chips)~
',
 PATH='I18',
 DRAWING='@T6G_MB_LIB.T6G(SCH_1):PAGE171',
 PART_TYPE='SMLF',
 MATERIAL='IC',
 PHYS_PAGE='196',
 XY='(-5700,4575)',
 ROT='0',
 VER='1',
 LOCATION='PU48',
 CDS_LIB='pure_quanta',
 CDS_PART_NAME='ISL99390FRZTR5935-ISL99390FRZ-TR5935,SMLF,IC,AL099A',
 PART_NUMBER='AL099390004',
 VALUE='ISL99390FRZ-TR5935',
 PRIM_FILE='./archive_libs/logical/isl99390frztr5935/chips/chips.prt';

PART_NAME
 PU49 'ISL99390FRZTR5935-ISL99390FRZ-TR5935,SMLF,IC,AL099A':;

SECTION_NUMBER 1
 '@T6G_MB_LIB.T6G(SCH_1):PAGE173_I41@PURE_QUANTA.ISL99390FRZTR5935(CHIPS)':
 C_PATH='@t6g_mb_lib.t6g(sch_1):page173_i41@pure_quanta.isl99390frztr5935(chips)~
',
 P_PATH='@t6g_mb_lib.t6g(sch_1):page198_i41@pure_quanta.isl99390frztr5935(chips)~
',
 PATH='I41',
 DRAWING='@T6G_MB_LIB.T6G(SCH_1):PAGE173',
 PART_TYPE='SMLF',
 MATERIAL='IC',
 PHYS_PAGE='198',
 XY='(-5825,5075)',
 ROT='0',
 VER='1',
 LOCATION='PU49',
 CDS_LIB='pure_quanta',
 CDS_PART_NAME='ISL99390FRZTR5935-ISL99390FRZ-TR5935,SMLF,IC,AL099A',
 PART_NUMBER='AL099390004',
 VALUE='ISL99390FRZ-TR5935',
 PRIM_FILE='./archive_libs/logical/isl99390frztr5935/chips/chips.prt';

PART_NAME
 PU50 'ISL99390FRZTR5935-ISL99390FRZ-TR5935,SMLF,IC,AL099A':;

SECTION_NUMBER 1
 '@T6G_MB_LIB.T6G(SCH_1):PAGE173_I86@PURE_QUANTA.ISL99390FRZTR5935(CHIPS)':
 C_PATH='@t6g_mb_lib.t6g(sch_1):page173_i86@pure_quanta.isl99390frztr5935(chips)~
',
 P_PATH='@t6g_mb_lib.t6g(sch_1):page198_i86@pure_quanta.isl99390frztr5935(chips)~
',
 PATH='I86',
 DRAWING='@T6G_MB_LIB.T6G(SCH_1):PAGE173',
 PART_TYPE='SMLF',
 MATERIAL='IC',
 PHYS_PAGE='198',
 XY='(-5800,1975)',
 ROT='0',
 VER='1',
 LOCATION='PU50',
 CDS_LIB='pure_quanta',
 CDS_PART_NAME='ISL99390FRZTR5935-ISL99390FRZ-TR5935,SMLF,IC,AL099A',
 PART_NUMBER='AL099390004',
 VALUE='ISL99390FRZ-TR5935',
 PRIM_FILE='./archive_libs/logical/isl99390frztr5935/chips/chips.prt';

PART_NAME
 PU51 'ISL99390FRZTR5935-ISL99390FRZ-TR5935,SMLF,IC,AL099A':;

SECTION_NUMBER 1
 '@T6G_MB_LIB.T6G(SCH_1):PAGE174_I38@PURE_QUANTA.ISL99390FRZTR5935(CHIPS)':
 C_PATH='@t6g_mb_lib.t6g(sch_1):page174_i38@pure_quanta.isl99390frztr5935(chips)~
',
 P_PATH='@t6g_mb_lib.t6g(sch_1):page199_i38@pure_quanta.isl99390frztr5935(chips)~
',
 PATH='I38',
 DRAWING='@T6G_MB_LIB.T6G(SCH_1):PAGE174',
 PART_TYPE='SMLF',
 MATERIAL='IC',
 PHYS_PAGE='199',
 XY='(-5725,4225)',
 ROT='0',
 VER='1',
 LOCATION='PU51',
 CDS_LIB='pure_quanta',
 CDS_PART_NAME='ISL99390FRZTR5935-ISL99390FRZ-TR5935,SMLF,IC,AL099A',
 PART_NUMBER='AL099390004',
 VALUE='ISL99390FRZ-TR5935',
 PRIM_FILE='./archive_libs/logical/isl99390frztr5935/chips/chips.prt';

PART_NAME
 PU52 'ISL99390FRZTR5935-ISL99390FRZ-TR5935,SMLF,IC,AL099A':;

SECTION_NUMBER 1
 '@T6G_MB_LIB.T6G(SCH_1):PAGE198_I73@PURE_QUANTA.ISL99390FRZTR5935(CHIPS)':
 C_PATH='@t6g_mb_lib.t6g(sch_1):page198_i73@pure_quanta.isl99390frztr5935(chips)~
',
 P_PATH='@t6g_mb_lib.t6g(sch_1):page223_i73@pure_quanta.isl99390frztr5935(chips)~
',
 PATH='I73',
 DRAWING='@T6G_MB_LIB.T6G(SCH_1):PAGE198',
 PART_TYPE='SMLF',
 MATERIAL='IC',
 PHYS_PAGE='223',
 XY='(-9350,5100)',
 ROT='0',
 VER='1',
 LOCATION='PU52',
 CDS_LIB='pure_quanta',
 CDS_PART_NAME='ISL99390FRZTR5935-ISL99390FRZ-TR5935,SMLF,IC,AL099A',
 PART_NUMBER='AL099390004',
 VALUE='ISL99390FRZ-TR5935',
 PRIM_FILE='./archive_libs/logical/isl99390frztr5935/chips/chips.prt';

PART_NAME
 PU53 'ISL99390FRZTR5935-ISL99390FRZ-TR5935,SMLF,IC,AL099A':;

SECTION_NUMBER 1
 '@T6G_MB_LIB.T6G(SCH_1):PAGE198_I15@PURE_QUANTA.ISL99390FRZTR5935(CHIPS)':
 C_PATH='@t6g_mb_lib.t6g(sch_1):page198_i15@pure_quanta.isl99390frztr5935(chips)~
',
 P_PATH='@t6g_mb_lib.t6g(sch_1):page223_i15@pure_quanta.isl99390frztr5935(chips)~
',
 PATH='I15',
 DRAWING='@T6G_MB_LIB.T6G(SCH_1):PAGE198',
 PART_TYPE='SMLF',
 MATERIAL='IC',
 PHYS_PAGE='223',
 XY='(-9350,2300)',
 ROT='0',
 VER='1',
 LOCATION='PU53',
 CDS_LIB='pure_quanta',
 CDS_PART_NAME='ISL99390FRZTR5935-ISL99390FRZ-TR5935,SMLF,IC,AL099A',
 PART_NUMBER='AL099390004',
 VALUE='ISL99390FRZ-TR5935',
 PRIM_FILE='./archive_libs/logical/isl99390frztr5935/chips/chips.prt';

PART_NAME
 PU54 'RAA229621GNPHA0-RAA229621GNP#HA0,SMLF,IC,ARF0TGP40A':;

SECTION_NUMBER 1
 '@T6G_MB_LIB.T6G(SCH_1):PAGE199_I86@PURE_QUANTA.RAA229621GNPHA0(CHIPS)':
 C_PATH='@t6g_mb_lib.t6g(sch_1):page199_i86@pure_quanta.raa229621gnpha0(chips)',
 P_PATH='@t6g_mb_lib.t6g(sch_1):page224_i86@pure_quanta.raa229621gnpha0(chips)',
 PATH='I86',
 DRAWING='@T6G_MB_LIB.T6G(SCH_1):PAGE199',
 PART_TYPE='SMLF',
 MATERIAL='IC',
 PHYS_PAGE='224',
 XY='(-4400,3375)',
 ROT='0',
 VER='1',
 LOCATION='PU54',
 CDS_LIB='pure_quanta',
 CDS_PART_NAME='RAA229621GNPHA0-RAA229621GNP#HA0,SMLF,IC,ARF0TGP40A',
 PART_NUMBER='ARF0TGP4003',
 VALUE='RAA229621GNP#HA0',
 PRIM_FILE='./archive_libs/logical/raa229621gnpha0/chips/chips.prt';

PART_NAME
 PU55 'MPQ8633AGLEC807Z-MPQ8633AGLE-C807-Z,SMLF,IC,AL0086A':;

SECTION_NUMBER 1
 '@T6G_MB_LIB.T6G(SCH_1):PAGE167_I41@PURE_QUANTA.MPQ8633AGLEC807Z(CHIPS)':
 C_PATH='@t6g_mb_lib.t6g(sch_1):page167_i41@pure_quanta.mpq8633aglec807z(chips)',
 P_PATH='@t6g_mb_lib.t6g(sch_1):page192_i41@pure_quanta.mpq8633aglec807z(chips)',
 PATH='I41',
 DRAWING='@T6G_MB_LIB.T6G(SCH_1):PAGE167',
 SEC_TYPE='',
 PART_TYPE='SMLF',
 MATERIAL='IC',
 PHYS_PAGE='192',
 XY='(-6875,3425)',
 ROT='0',
 VER='1',
 LOCATION='PU55',
 SEC='1',
 CDS_LIB='pure_quanta',
 CDS_PART_NAME='MPQ8633AGLEC807Z-MPQ8633AGLE-C807-Z,SMLF,IC,AL0086A',
 PART_NUMBER='AL008633007',
 VALUE='MPQ8633AGLE-C807-Z',
 PRIM_FILE='./archive_libs/logical/mpq8633aglec807z/chips/chips.prt';

PART_NAME
 PU57 'MPQ8633BGLEC838Z-MPQ8633BGLE-C838-Z,SMLF,IC,AL0086A':;

SECTION_NUMBER 1
 '@T6G_MB_LIB.T6G(SCH_1):PAGE184_I18@PURE_QUANTA.MPQ8633BGLEC838Z(CHIPS)':
 C_PATH='@t6g_mb_lib.t6g(sch_1):page184_i18@pure_quanta.mpq8633bglec838z(chips)',
 P_PATH='@t6g_mb_lib.t6g(sch_1):page209_i18@pure_quanta.mpq8633bglec838z(chips)',
 PATH='I18',
 DRAWING='@T6G_MB_LIB.T6G(SCH_1):PAGE184',
 PART_TYPE='SMLF',
 MATERIAL='IC',
 PHYS_PAGE='209',
 XY='(-5750,3400)',
 ROT='0',
 VER='1',
 LOCATION='PU57',
 CDS_LIB='pure_quanta',
 CDS_PART_NAME='MPQ8633BGLEC838Z-MPQ8633BGLE-C838-Z,SMLF,IC,AL0086A',
 PART_NUMBER='AL008633005',
 VALUE='MPQ8633BGLE-C838-Z',
 PRIM_FILE='./archive_libs/logical/mpq8633bglec838z/chips/chips.prt';

PART_NAME
 PU200 'MAX15090BEWIT-MAX15090BEWI+T,SMLF,IC,AL015080B00':
 ROOM='NIC_P3V3_BOM1';

SECTION_NUMBER 1
 '@T6G_MB_LIB.T6G(SCH_1):PAGE343_I89@PURE_QUANTA.MAX15090BEWIT(CHIPS)':
 C_PATH='@t6g_mb_lib.t6g(sch_1):page343_i89@pure_quanta.max15090bewit(chips)',
 P_PATH='@t6g_mb_lib.t6g(sch_1):page140_i89@pure_quanta.max15090bewit(chips)',
 PATH='I89',
 DRAWING='@T6G_MB_LIB.T6G(SCH_1):PAGE343',
 PIN_NAMES_ROTATE='True',
 PART_TYPE='SMLF',
 MATERIAL='IC',
 PHYS_PAGE='140',
 XY='(1575,8625)',
 ROT='0',
 VER='1',
 LOCATION='PU200',
 CDS_LIB='pure_quanta',
 CDS_PART_NAME='MAX15090BEWIT-MAX15090BEWI+T,SMLF,IC,AL015080B00',
 ROOM='NIC_P3V3_BOM1',
 PART_NUMBER='AL015080B00',
 VALUE='MAX15090BEWI+T',
 PRIM_FILE='./archive_libs/logical/max15090bewit/chips/chips.prt';

PART_NAME
 PU201 'MAX15090BEWIT-MAX15090BEWI+T,SMLF,IC,AL015080B00':
 ROOM='NIC_P12V_MAM_TIC_BOM1';

SECTION_NUMBER 1
 '@T6G_MB_LIB.T6G(SCH_1):PAGE343_I67@PURE_QUANTA.MAX15090BEWIT(CHIPS)':
 C_PATH='@t6g_mb_lib.t6g(sch_1):page343_i67@pure_quanta.max15090bewit(chips)',
 P_PATH='@t6g_mb_lib.t6g(sch_1):page140_i67@pure_quanta.max15090bewit(chips)',
 PATH='I67',
 DRAWING='@T6G_MB_LIB.T6G(SCH_1):PAGE343',
 PIN_NAMES_ROTATE='True',
 PART_TYPE='SMLF',
 MATERIAL='IC',
 PHYS_PAGE='140',
 XY='(1450,6300)',
 ROT='0',
 VER='1',
 LOCATION='PU201',
 CDS_LIB='pure_quanta',
 CDS_PART_NAME='MAX15090BEWIT-MAX15090BEWI+T,SMLF,IC,AL015080B00',
 ROOM='NIC_P12V_MAM_TIC_BOM1',
 PART_NUMBER='AL015080B00',
 VALUE='MAX15090BEWI+T',
 PRIM_FILE='./archive_libs/logical/max15090bewit/chips/chips.prt';

PART_NAME
 PU202 'MAX15090BEWIT-MAX15090BEWI+T,SMLF,IC,AL015080B00':
 ROOM='NIC_P3V3_BOM1';

SECTION_NUMBER 1
 '@T6G_MB_LIB.T6G(SCH_1):PAGE338_I113@PURE_QUANTA.MAX15090BEWIT(CHIPS)':
 C_PATH='@t6g_mb_lib.t6g(sch_1):page338_i113@pure_quanta.max15090bewit(chips)',
 P_PATH='@t6g_mb_lib.t6g(sch_1):page134_i113@pure_quanta.max15090bewit(chips)',
 PATH='I113',
 DRAWING='@T6G_MB_LIB.T6G(SCH_1):PAGE338',
 PIN_NAMES_ROTATE='True',
 PART_TYPE='SMLF',
 MATERIAL='IC',
 PHYS_PAGE='134',
 XY='(7850,12775)',
 ROT='0',
 VER='1',
 LOCATION='PU202',
 CDS_LIB='pure_quanta',
 CDS_PART_NAME='MAX15090BEWIT-MAX15090BEWI+T,SMLF,IC,AL015080B00',
 ROOM='NIC_P3V3_BOM1',
 PART_NUMBER='AL015080B00',
 VALUE='MAX15090BEWI+T',
 PRIM_FILE='./archive_libs/logical/max15090bewit/chips/chips.prt';

PART_NAME
 PU203 'MAX15090BEWIT-MAX15090BEWI+T,SMLF,IC,AL015080B00':
 ROOM='NIC_P12V_MAM_TIC_BOM1';

SECTION_NUMBER 1
 '@T6G_MB_LIB.T6G(SCH_1):PAGE338_I50@PURE_QUANTA.MAX15090BEWIT(CHIPS)':
 C_PATH='@t6g_mb_lib.t6g(sch_1):page338_i50@pure_quanta.max15090bewit(chips)',
 P_PATH='@t6g_mb_lib.t6g(sch_1):page134_i50@pure_quanta.max15090bewit(chips)',
 PATH='I50',
 DRAWING='@T6G_MB_LIB.T6G(SCH_1):PAGE338',
 PIN_NAMES_ROTATE='True',
 PART_TYPE='SMLF',
 MATERIAL='IC',
 PHYS_PAGE='134',
 XY='(7625,10725)',
 ROT='0',
 VER='1',
 LOCATION='PU203',
 CDS_LIB='pure_quanta',
 CDS_PART_NAME='MAX15090BEWIT-MAX15090BEWI+T,SMLF,IC,AL015080B00',
 ROOM='NIC_P12V_MAM_TIC_BOM1',
 PART_NUMBER='AL015080B00',
 VALUE='MAX15090BEWI+T',
 PRIM_FILE='./archive_libs/logical/max15090bewit/chips/chips.prt';

PART_NAME
 PU204 'RS31312R-RS31312R,SMLF,IC,AL031312000':
 ROOM='NIC_P12V_MPS_MAM_BOM2';

SECTION_NUMBER 1
 '@T6G_MB_LIB.T6G(SCH_1):PAGE339_I137@PURE_QUANTA.RS31312R(CHIPS)':
 C_PATH='@t6g_mb_lib.t6g(sch_1):page339_i137@pure_quanta.rs31312r(chips)',
 P_PATH='@t6g_mb_lib.t6g(sch_1):page135_i137@pure_quanta.rs31312r(chips)',
 PATH='I137',
 DRAWING='@T6G_MB_LIB.T6G(SCH_1):PAGE339',
 SEC_TYPE='',
 PART_TYPE='SMLF',
 MATERIAL='IC',
 PHYS_PAGE='135',
 XY='(-6400,9475)',
 ROT='0',
 VER='1',
 LOCATION='PU204',
 SEC='1',
 CDS_LIB='pure_quanta',
 CDS_PART_NAME='RS31312R-RS31312R,SMLF,IC,AL031312000',
 ROOM='NIC_P12V_MPS_MAM_BOM2',
 PART_NUMBER='AL031312000',
 VALUE='RS31312R',
 PRIM_FILE='./archive_libs/logical/rs31312r/chips/chips.prt';

PART_NAME
 PU205 'MP5016GQHLZ-MP5016GQH-L-Z,SMLF,IC,AL005016007':
 ROOM='NIC_P3V3_BOM2';

SECTION_NUMBER 1
 '@T6G_MB_LIB.T6G(SCH_1):PAGE339_I113@PURE_QUANTA.MP5016GQHLZ(CHIPS)':
 C_PATH='@t6g_mb_lib.t6g(sch_1):page339_i113@pure_quanta.mp5016gqhlz(chips)',
 P_PATH='@t6g_mb_lib.t6g(sch_1):page135_i113@pure_quanta.mp5016gqhlz(chips)',
 PATH='I113',
 DRAWING='@T6G_MB_LIB.T6G(SCH_1):PAGE339',
 PART_TYPE='SMLF',
 MATERIAL='IC',
 PHYS_PAGE='135',
 XY='(-2400,12525)',
 ROT='0',
 VER='1',
 LOCATION='PU205',
 CDS_LIB='pure_quanta',
 CDS_PART_NAME='MP5016GQHLZ-MP5016GQH-L-Z,SMLF,IC,AL005016007',
 ROOM='NIC_P3V3_BOM2',
 PART_NUMBER='AL005016007',
 VALUE='MP5016GQH-L-Z',
 PRIM_FILE='./archive_libs/logical/mp5016gqhlz/chips/chips.prt';

PART_NAME
 PU206 'RS31312R-RS31312R,SMLF,IC,AL031312000':
 ROOM='NIC_P12V_MPS_MAM_BOM2';

SECTION_NUMBER 1
 '@T6G_MB_LIB.T6G(SCH_1):PAGE344_I82@PURE_QUANTA.RS31312R(CHIPS)':
 C_PATH='@t6g_mb_lib.t6g(sch_1):page344_i82@pure_quanta.rs31312r(chips)',
 P_PATH='@t6g_mb_lib.t6g(sch_1):page141_i82@pure_quanta.rs31312r(chips)',
 PATH='I82',
 DRAWING='@T6G_MB_LIB.T6G(SCH_1):PAGE344',
 SEC_TYPE='',
 PART_TYPE='SMLF',
 MATERIAL='IC',
 PHYS_PAGE='141',
 XY='(-1975,2925)',
 ROT='0',
 VER='1',
 LOCATION='PU206',
 SEC='1',
 CDS_LIB='pure_quanta',
 CDS_PART_NAME='RS31312R-RS31312R,SMLF,IC,AL031312000',
 ROOM='NIC_P12V_MPS_MAM_BOM2',
 PART_NUMBER='AL031312000',
 VALUE='RS31312R',
 PRIM_FILE='./archive_libs/logical/rs31312r/chips/chips.prt';

PART_NAME
 PU207 'MP5016GQHLZ-MP5016GQH-L-Z,SMLF,IC,AL005016007':
 ROOM='NIC_P3V3_BOM2';

SECTION_NUMBER 1
 '@T6G_MB_LIB.T6G(SCH_1):PAGE344_I51@PURE_QUANTA.MP5016GQHLZ(CHIPS)':
 C_PATH='@t6g_mb_lib.t6g(sch_1):page344_i51@pure_quanta.mp5016gqhlz(chips)',
 P_PATH='@t6g_mb_lib.t6g(sch_1):page141_i51@pure_quanta.mp5016gqhlz(chips)',
 PATH='I51',
 DRAWING='@T6G_MB_LIB.T6G(SCH_1):PAGE344',
 PART_TYPE='SMLF',
 MATERIAL='IC',
 PHYS_PAGE='141',
 XY='(1675,6425)',
 ROT='0',
 VER='1',
 LOCATION='PU207',
 CDS_LIB='pure_quanta',
 CDS_PART_NAME='MP5016GQHLZ-MP5016GQH-L-Z,SMLF,IC,AL005016007',
 ROOM='NIC_P3V3_BOM2',
 PART_NUMBER='AL005016007',
 VALUE='MP5016GQH-L-Z',
 PRIM_FILE='./archive_libs/logical/mp5016gqhlz/chips/chips.prt';

PART_NAME
 PU287 'MP5991GLUZ-MP5991GLU-Z,SMLF,IC,AL005991A00':
 ROOM='HSC BOM1';

SECTION_NUMBER 1
 '@T6G_MB_LIB.T6G(SCH_1):PAGE301_I35@PURE_QUANTA.MP5991GLUZ(CHIPS)':
 C_PATH='@t6g_mb_lib.t6g(sch_1):page301_i35@pure_quanta.mp5991gluz(chips)',
 P_PATH='@t6g_mb_lib.t6g(sch_1):page263_i35@pure_quanta.mp5991gluz(chips)',
 PATH='I35',
 DRAWING='@T6G_MB_LIB.T6G(SCH_1):PAGE301',
 SEC_TYPE='',
 PART_TYPE='SMLF',
 MATERIAL='IC',
 PHYS_PAGE='263',
 XY='(0,1475)',
 ROT='0',
 VER='1',
 LOCATION='PU287',
 SEC='1',
 CDS_LIB='pure_quanta',
 CDS_PART_NAME='MP5991GLUZ-MP5991GLU-Z,SMLF,IC,AL005991A00',
 ROOM='HSC BOM1',
 PART_NUMBER='AL005991A00',
 VALUE='MP5991GLU-Z',
 PRIM_FILE='./archive_libs/logical/mp5991gluz/chips/chips.prt';

PART_NAME
 PU288 'MP5991GLUZ-MP5991GLU-Z,SMLF,IC,AL005991A00':
 ROOM='HSC BOM1';

SECTION_NUMBER 1
 '@T6G_MB_LIB.T6G(SCH_1):PAGE301_I16@PURE_QUANTA.MP5991GLUZ(CHIPS)':
 C_PATH='@t6g_mb_lib.t6g(sch_1):page301_i16@pure_quanta.mp5991gluz(chips)',
 P_PATH='@t6g_mb_lib.t6g(sch_1):page263_i16@pure_quanta.mp5991gluz(chips)',
 PATH='I16',
 DRAWING='@T6G_MB_LIB.T6G(SCH_1):PAGE301',
 SEC_TYPE='',
 PART_TYPE='SMLF',
 MATERIAL='IC',
 PHYS_PAGE='263',
 XY='(0,-1325)',
 ROT='0',
 VER='1',
 LOCATION='PU288',
 SEC='1',
 CDS_LIB='pure_quanta',
 CDS_PART_NAME='MP5991GLUZ-MP5991GLU-Z,SMLF,IC,AL005991A00',
 ROOM='HSC BOM1',
 PART_NUMBER='AL005991A00',
 VALUE='MP5991GLU-Z',
 PRIM_FILE='./archive_libs/logical/mp5991gluz/chips/chips.prt';

PART_NAME
 PU289 'MP5990GMA1111Z-MP5990GMA-1111-Z,SMLF,IC,AR0F0TP4023':
 ROOM='HSC BOM1';

SECTION_NUMBER 1
 '@T6G_MB_LIB.T6G(SCH_1):PAGE267_I58@PURE_QUANTA.MP5990GMA1111Z(CHIPS)':
 C_PATH='@t6g_mb_lib.t6g(sch_1):page267_i58@pure_quanta.mp5990gma1111z(chips)',
 P_PATH='@t6g_mb_lib.t6g(sch_1):page262_i58@pure_quanta.mp5990gma1111z(chips)',
 PATH='I58',
 DRAWING='@T6G_MB_LIB.T6G(SCH_1):PAGE267',
 PART_TYPE='SMLF',
 MATERIAL='IC',
 PHYS_PAGE='262',
 XY='(-11400,3050)',
 ROT='0',
 VER='1',
 LOCATION='PU289',
 CDS_LIB='pure_quanta',
 CDS_PART_NAME='MP5990GMA1111Z-MP5990GMA-1111-Z,SMLF,IC,AR0F0TP4023',
 ROOM='HSC BOM1',
 PART_NUMBER='AR0F0TP4023',
 VALUE='MP5990GMA-1111-Z',
 PRIM_FILE='./archive_libs/logical/mp5990gma1111z/chips/chips.prt';

PART_NAME
 PU292 'RS31312R-RS31312R,SMLF,IC,AL031312000':
 ROOM='E1S_P12V_MPS_MAM_BOM2';

SECTION_NUMBER 1
 '@T6G_MB_LIB.T6G(SCH_1):PAGE323_I76@PURE_QUANTA.RS31312R(CHIPS)':
 C_PATH='@t6g_mb_lib.t6g(sch_1):page323_i76@pure_quanta.rs31312r(chips)',
 P_PATH='@t6g_mb_lib.t6g(sch_1):page147_i76@pure_quanta.rs31312r(chips)',
 PATH='I76',
 DRAWING='@T6G_MB_LIB.T6G(SCH_1):PAGE323',
 SEC_TYPE='',
 PART_TYPE='SMLF',
 MATERIAL='IC',
 PHYS_PAGE='147',
 XY='(50,1300)',
 ROT='0',
 VER='1',
 LOCATION='PU292',
 SEC='1',
 CDS_LIB='pure_quanta',
 CDS_PART_NAME='RS31312R-RS31312R,SMLF,IC,AL031312000',
 ROOM='E1S_P12V_MPS_MAM_BOM2',
 PART_NUMBER='AL031312000',
 VALUE='RS31312R',
 PRIM_FILE='./archive_libs/logical/rs31312r/chips/chips.prt';

PART_NAME
 PU293 'MP5016GQHLZ-MP5016GQH-L-Z,SMLF,IC,AL005016007':
 ROOM='E1S_P3V3_BOM2';

SECTION_NUMBER 1
 '@T6G_MB_LIB.T6G(SCH_1):PAGE323_I31@PURE_QUANTA.MP5016GQHLZ(CHIPS)':
 C_PATH='@t6g_mb_lib.t6g(sch_1):page323_i31@pure_quanta.mp5016gqhlz(chips)',
 P_PATH='@t6g_mb_lib.t6g(sch_1):page147_i31@pure_quanta.mp5016gqhlz(chips)',
 PATH='I31',
 DRAWING='@T6G_MB_LIB.T6G(SCH_1):PAGE323',
 PART_TYPE='SMLF',
 MATERIAL='IC',
 PHYS_PAGE='147',
 XY='(2200,-1400)',
 ROT='0',
 VER='1',
 LOCATION='PU293',
 CDS_LIB='pure_quanta',
 CDS_PART_NAME='MP5016GQHLZ-MP5016GQH-L-Z,SMLF,IC,AL005016007',
 ROOM='E1S_P3V3_BOM2',
 PART_NUMBER='AL005016007',
 VALUE='MP5016GQH-L-Z',
 PRIM_FILE='./archive_libs/logical/mp5016gqhlz/chips/chips.prt';

PART_NAME
 PU294 'MAX15090BEWIT-MAX15090BEWI+T,SMLF,IC,AL015080B00':
 ROOM='E1S_P12V_MAM_TIC_BOM1';

SECTION_NUMBER 1
 '@T6G_MB_LIB.T6G(SCH_1):PAGE324_I66@PURE_QUANTA.MAX15090BEWIT(CHIPS)':
 C_PATH='@t6g_mb_lib.t6g(sch_1):page324_i66@pure_quanta.max15090bewit(chips)',
 P_PATH='@t6g_mb_lib.t6g(sch_1):page146_i66@pure_quanta.max15090bewit(chips)',
 PATH='I66',
 DRAWING='@T6G_MB_LIB.T6G(SCH_1):PAGE324',
 PIN_NAMES_ROTATE='TRUE',
 PART_TYPE='SMLF',
 MATERIAL='IC',
 PHYS_PAGE='146',
 XY='(1475,650)',
 ROT='0',
 VER='1',
 LOCATION='PU294',
 CDS_LIB='pure_quanta',
 CDS_PART_NAME='MAX15090BEWIT-MAX15090BEWI+T,SMLF,IC,AL015080B00',
 ROOM='E1S_P12V_MAM_TIC_BOM1',
 PART_NUMBER='AL015080B00',
 VALUE='MAX15090BEWI+T',
 PRIM_FILE='./archive_libs/logical/max15090bewit/chips/chips.prt';

PART_NAME
 PU295 'MAX15090BEWIT-MAX15090BEWI+T,SMLF,IC,AL015080B00':
 ROOM='E1S_P3V3_BOM1';

SECTION_NUMBER 1
 '@T6G_MB_LIB.T6G(SCH_1):PAGE324_I88@PURE_QUANTA.MAX15090BEWIT(CHIPS)':
 C_PATH='@t6g_mb_lib.t6g(sch_1):page324_i88@pure_quanta.max15090bewit(chips)',
 P_PATH='@t6g_mb_lib.t6g(sch_1):page146_i88@pure_quanta.max15090bewit(chips)',
 PATH='I88',
 DRAWING='@T6G_MB_LIB.T6G(SCH_1):PAGE324',
 PIN_NAMES_ROTATE='TRUE',
 PART_TYPE='SMLF',
 MATERIAL='IC',
 PHYS_PAGE='146',
 XY='(1475,-2050)',
 ROT='0',
 VER='1',
 LOCATION='PU295',
 CDS_LIB='pure_quanta',
 CDS_PART_NAME='MAX15090BEWIT-MAX15090BEWI+T,SMLF,IC,AL015080B00',
 ROOM='E1S_P3V3_BOM1',
 PART_NUMBER='AL015080B00',
 VALUE='MAX15090BEWI+T',
 PRIM_FILE='./archive_libs/logical/max15090bewit/chips/chips.prt';

PART_NAME
 PU296 'MP5991GLUZ-MP5991GLU-Z,SMLF,IC,AL005991A00':
 ROOM='HSC BOM1';

SECTION_NUMBER 1
 '@T6G_MB_LIB.T6G(SCH_1):PAGE325_I35@PURE_QUANTA.MP5991GLUZ(CHIPS)':
 C_PATH='@t6g_mb_lib.t6g(sch_1):page325_i35@pure_quanta.mp5991gluz(chips)',
 P_PATH='@t6g_mb_lib.t6g(sch_1):page264_i35@pure_quanta.mp5991gluz(chips)',
 PATH='I35',
 DRAWING='@T6G_MB_LIB.T6G(SCH_1):PAGE325',
 SEC_TYPE='',
 PART_TYPE='SMLF',
 MATERIAL='IC',
 PHYS_PAGE='264',
 XY='(25,1575)',
 ROT='0',
 VER='1',
 LOCATION='PU296',
 SEC='1',
 CDS_LIB='pure_quanta',
 CDS_PART_NAME='MP5991GLUZ-MP5991GLU-Z,SMLF,IC,AL005991A00',
 ROOM='HSC BOM1',
 PART_NUMBER='AL005991A00',
 VALUE='MP5991GLU-Z',
 PRIM_FILE='./archive_libs/logical/mp5991gluz/chips/chips.prt';

PART_NAME
 PU297 'MP5991GLUZ-MP5991GLU-Z,SMLF,IC,AL005991A00':
 ROOM='HSC BOM1';

SECTION_NUMBER 1
 '@T6G_MB_LIB.T6G(SCH_1):PAGE325_I17@PURE_QUANTA.MP5991GLUZ(CHIPS)':
 C_PATH='@t6g_mb_lib.t6g(sch_1):page325_i17@pure_quanta.mp5991gluz(chips)',
 P_PATH='@t6g_mb_lib.t6g(sch_1):page264_i17@pure_quanta.mp5991gluz(chips)',
 PATH='I17',
 DRAWING='@T6G_MB_LIB.T6G(SCH_1):PAGE325',
 SEC_TYPE='',
 PART_TYPE='SMLF',
 MATERIAL='IC',
 PHYS_PAGE='264',
 XY='(25,-1200)',
 ROT='0',
 VER='1',
 LOCATION='PU297',
 SEC='1',
 CDS_LIB='pure_quanta',
 CDS_PART_NAME='MP5991GLUZ-MP5991GLU-Z,SMLF,IC,AL005991A00',
 ROOM='HSC BOM1',
 PART_NUMBER='AL005991A00',
 VALUE='MP5991GLU-Z',
 PRIM_FILE='./archive_libs/logical/mp5991gluz/chips/chips.prt';

PART_NAME
 PU299 'RS31312R-RS31312R,SMLF,IC,AL031312000':
 ROOM='SCM_P12V_MPS_BOM2';

SECTION_NUMBER 1
 '@T6G_MB_LIB.T6G(SCH_1):PAGE350_I95@PURE_QUANTA.RS31312R(CHIPS)':
 C_PATH='@t6g_mb_lib.t6g(sch_1):page350_i95@pure_quanta.rs31312r(chips)',
 P_PATH='@t6g_mb_lib.t6g(sch_1):page152_i95@pure_quanta.rs31312r(chips)',
 PATH='I95',
 DRAWING='@T6G_MB_LIB.T6G(SCH_1):PAGE350',
 SEC_TYPE='',
 PART_TYPE='SMLF',
 MATERIAL='IC',
 PHYS_PAGE='152',
 XY='(1625,12025)',
 ROT='0',
 VER='1',
 LOCATION='PU299',
 SEC='1',
 CDS_LIB='pure_quanta',
 CDS_PART_NAME='RS31312R-RS31312R,SMLF,IC,AL031312000',
 ROOM='SCM_P12V_MPS_BOM2',
 PART_NUMBER='AL031312000',
 VALUE='RS31312R',
 PRIM_FILE='./archive_libs/logical/rs31312r/chips/chips.prt';

PART_NAME
 PU300 'MAX15090BEWIT-MAX15090BEWI+T,SMLF,IC,AL015080B00':
 ROOM='SCM_P12V_MAM_BOM1';

SECTION_NUMBER 1
 '@T6G_MB_LIB.T6G(SCH_1):PAGE350_I86@PURE_QUANTA.MAX15090BEWIT(CHIPS)':
 C_PATH='@t6g_mb_lib.t6g(sch_1):page350_i86@pure_quanta.max15090bewit(chips)',
 P_PATH='@t6g_mb_lib.t6g(sch_1):page152_i86@pure_quanta.max15090bewit(chips)',
 PATH='I86',
 DRAWING='@T6G_MB_LIB.T6G(SCH_1):PAGE350',
 PIN_NAMES_ROTATE='TRUE',
 PART_TYPE='SMLF',
 MATERIAL='IC',
 PHYS_PAGE='152',
 XY='(2275,14900)',
 ROT='0',
 VER='1',
 LOCATION='PU300',
 CDS_LIB='pure_quanta',
 CDS_PART_NAME='MAX15090BEWIT-MAX15090BEWI+T,SMLF,IC,AL015080B00',
 ROOM='SCM_P12V_MAM_BOM1',
 PART_NUMBER='AL015080B00',
 VALUE='MAX15090BEWI+T',
 PRIM_FILE='./archive_libs/logical/max15090bewit/chips/chips.prt';

PART_NAME
 PU6000 'MPQ8626GDZ-MPQ8626GD-Z,SMLF,IC,AL008626000':;

SECTION_NUMBER 1
 '@T6G_MB_LIB.T6G(SCH_1):PAGE315_I18@PURE_QUANTA.MPQ8626GDZ(CHIPS)':
 C_PATH='@t6g_mb_lib.t6g(sch_1):page315_i18@pure_quanta.mpq8626gdz(chips)',
 P_PATH='@t6g_mb_lib.t6g(sch_1):page269_i18@pure_quanta.mpq8626gdz(chips)',
 PATH='I18',
 DRAWING='@T6G_MB_LIB.T6G(SCH_1):PAGE315',
 SEC_TYPE='',
 PART_TYPE='SMLF',
 MATERIAL='IC',
 PHYS_PAGE='269',
 XY='(-1075,1850)',
 ROT='0',
 VER='1',
 LOCATION='PU6000',
 SEC='1',
 CDS_LIB='pure_quanta',
 CDS_PART_NAME='MPQ8626GDZ-MPQ8626GD-Z,SMLF,IC,AL008626000',
 PART_NUMBER='AL008626000',
 VALUE='MPQ8626GD-Z',
 PRIM_FILE='./archive_libs/logical/mpq8626gdz/chips/chips.prt';

PART_NAME
 PU6001 'MPQ8626GDZ-MPQ8626GD-Z,SMLF,IC,AL008626000':;

SECTION_NUMBER 1
 '@T6G_MB_LIB.T6G(SCH_1):PAGE380_I16@PURE_QUANTA.MPQ8626GDZ(CHIPS)':
 C_PATH='@t6g_mb_lib.t6g(sch_1):page380_i16@pure_quanta.mpq8626gdz(chips)',
 P_PATH='@t6g_mb_lib.t6g(sch_1):page270_i16@pure_quanta.mpq8626gdz(chips)',
 PATH='I16',
 DRAWING='@T6G_MB_LIB.T6G(SCH_1):PAGE380',
 SEC_TYPE='',
 PART_TYPE='SMLF',
 MATERIAL='IC',
 PHYS_PAGE='270',
 XY='(-4650,1825)',
 ROT='0',
 VER='1',
 LOCATION='PU6001',
 SEC='1',
 CDS_LIB='pure_quanta',
 CDS_PART_NAME='MPQ8626GDZ-MPQ8626GD-Z,SMLF,IC,AL008626000',
 PART_NUMBER='AL008626000',
 VALUE='MPQ8626GD-Z',
 PRIM_FILE='./archive_libs/logical/mpq8626gdz/chips/chips.prt';

PART_NAME
 PU6500 'MPQ8633BGLEC838Z-MPQ8633BGLE-C838-Z,SMLF,IC,AL0086A':;

SECTION_NUMBER 1
 '@T6G_MB_LIB.T6G(SCH_1):PAGE469_I51@PURE_QUANTA.MPQ8633BGLEC838Z(CHIPS)':
 C_PATH='@t6g_mb_lib.t6g(sch_1):page469_i51@pure_quanta.mpq8633bglec838z(chips)',
 P_PATH='@t6g_mb_lib.t6g(sch_1):page360_i51@pure_quanta.mpq8633bglec838z(chips)',
 PATH='I51',
 DRAWING='@T6G_MB_LIB.T6G(SCH_1):PAGE469',
 PART_TYPE='SMLF',
 MATERIAL='IC',
 PHYS_PAGE='360',
 XY='(-5625,3225)',
 ROT='0',
 VER='1',
 LOCATION='PU6500',
 CDS_LIB='pure_quanta',
 CDS_PART_NAME='MPQ8633BGLEC838Z-MPQ8633BGLE-C838-Z,SMLF,IC,AL0086A',
 PART_NUMBER='AL008633005',
 VALUE='MPQ8633BGLE-C838-Z',
 PRIM_FILE='./archive_libs/logical/mpq8633bglec838z/chips/chips.prt';

PART_NAME
 PU6501 'MPQ8633BGLEC838Z-MPQ8633BGLE-C838-Z,SMLF,IC,AL0086A':;

SECTION_NUMBER 1
 '@T6G_MB_LIB.T6G(SCH_1):PAGE470_I51@PURE_QUANTA.MPQ8633BGLEC838Z(CHIPS)':
 C_PATH='@t6g_mb_lib.t6g(sch_1):page470_i51@pure_quanta.mpq8633bglec838z(chips)',
 P_PATH='@t6g_mb_lib.t6g(sch_1):page361_i51@pure_quanta.mpq8633bglec838z(chips)',
 PATH='I51',
 DRAWING='@T6G_MB_LIB.T6G(SCH_1):PAGE470',
 PART_TYPE='SMLF',
 MATERIAL='IC',
 PHYS_PAGE='361',
 XY='(-5675,3275)',
 ROT='0',
 VER='1',
 LOCATION='PU6501',
 CDS_LIB='pure_quanta',
 CDS_PART_NAME='MPQ8633BGLEC838Z-MPQ8633BGLE-C838-Z,SMLF,IC,AL0086A',
 PART_NUMBER='AL008633005',
 VALUE='MPQ8633BGLE-C838-Z',
 PRIM_FILE='./archive_libs/logical/mpq8633bglec838z/chips/chips.prt';

PART_NAME
 PU6502 'ISL69260IRAZT-ISL69260IRAZ-T,SMLF,IC,AL069260000':;

SECTION_NUMBER 1
 '@T6G_MB_LIB.T6G(SCH_1):PAGE475_I42@PURE_QUANTA.ISL69260IRAZT(CHIPS)':
 C_PATH='@t6g_mb_lib.t6g(sch_1):page475_i42@pure_quanta.isl69260irazt(chips)',
 P_PATH='@t6g_mb_lib.t6g(sch_1):page362_i42@pure_quanta.isl69260irazt(chips)',
 PATH='I42',
 DRAWING='@T6G_MB_LIB.T6G(SCH_1):PAGE475',
 SEC_TYPE='',
 PART_TYPE='SMLF',
 MATERIAL='IC',
 PHYS_PAGE='362',
 XY='(-6575,5125)',
 ROT='0',
 VER='1',
 LOCATION='PU6502',
 SEC='1',
 CDS_LIB='pure_quanta',
 CDS_PART_NAME='ISL69260IRAZT-ISL69260IRAZ-T,SMLF,IC,AL069260000',
 PART_NUMBER='AL069260000',
 VALUE='ISL69260IRAZ-T',
 PRIM_FILE='./archive_libs/logical/isl69260irazt/chips/chips.prt';

PART_NAME
 PU6503 'ISL99390FRZTR5935-ISL99390FRZ-TR5935,SMLF,IC,AL099A':;

SECTION_NUMBER 1
 '@T6G_MB_LIB.T6G(SCH_1):PAGE476_I53@PURE_QUANTA.ISL99390FRZTR5935(CHIPS)':
 C_PATH='@t6g_mb_lib.t6g(sch_1):page476_i53@pure_quanta.isl99390frztr5935(chips)~
',
 P_PATH='@t6g_mb_lib.t6g(sch_1):page363_i53@pure_quanta.isl99390frztr5935(chips)~
',
 PATH='I53',
 DRAWING='@T6G_MB_LIB.T6G(SCH_1):PAGE476',
 SEC_TYPE='',
 BOM_COST='VR_DIMM ',
 PART_TYPE='SMLF',
 MATERIAL='IC',
 PHYS_PAGE='363',
 XY='(-4100,-6450)',
 ROT='0',
 VER='1',
 LOCATION='PU6503',
 SEC='1',
 CDS_LIB='pure_quanta',
 CDS_PART_NAME='ISL99390FRZTR5935-ISL99390FRZ-TR5935,SMLF,IC,AL099A',
 PART_NUMBER='AL099390004',
 VALUE='ISL99390FRZ-TR5935',
 PRIM_FILE='./archive_libs/logical/isl99390frztr5935/chips/chips.prt';

PART_NAME
 PU6504 'ISL99390FRZTR5935-ISL99390FRZ-TR5935,SMLF,IC,AL099A':;

SECTION_NUMBER 1
 '@T6G_MB_LIB.T6G(SCH_1):PAGE476_I270@PURE_QUANTA.ISL99390FRZTR5935(CHIPS)':
 C_PATH='@t6g_mb_lib.t6g(sch_1):page476_i270@pure_quanta.isl99390frztr5935(chips~
)',
 P_PATH='@t6g_mb_lib.t6g(sch_1):page363_i270@pure_quanta.isl99390frztr5935(chips~
)',
 PATH='I270',
 DRAWING='@T6G_MB_LIB.T6G(SCH_1):PAGE476',
 SEC_TYPE='',
 BOM_COST='VR_DIMM ',
 PART_TYPE='SMLF',
 MATERIAL='IC',
 PHYS_PAGE='363',
 XY='(-3975,-9350)',
 ROT='0',
 VER='1',
 LOCATION='PU6504',
 SEC='1',
 CDS_LIB='pure_quanta',
 CDS_PART_NAME='ISL99390FRZTR5935-ISL99390FRZ-TR5935,SMLF,IC,AL099A',
 PART_NUMBER='AL099390004',
 VALUE='ISL99390FRZ-TR5935',
 PRIM_FILE='./archive_libs/logical/isl99390frztr5935/chips/chips.prt';

PART_NAME
 PU6510 'ISL69260IRAZT-ISL69260IRAZ-T,SMLF,IC,AL069260000':;

SECTION_NUMBER 1
 '@T6G_MB_LIB.T6G(SCH_1):PAGE477_I88@PURE_QUANTA.ISL69260IRAZT(CHIPS)':
 C_PATH='@t6g_mb_lib.t6g(sch_1):page477_i88@pure_quanta.isl69260irazt(chips)',
 P_PATH='@t6g_mb_lib.t6g(sch_1):page364_i88@pure_quanta.isl69260irazt(chips)',
 PATH='I88',
 DRAWING='@T6G_MB_LIB.T6G(SCH_1):PAGE477',
 SEC_TYPE='',
 PART_TYPE='SMLF',
 MATERIAL='IC',
 PHYS_PAGE='364',
 XY='(-4125,3425)',
 ROT='0',
 VER='1',
 LOCATION='PU6510',
 SEC='1',
 CDS_LIB='pure_quanta',
 CDS_PART_NAME='ISL69260IRAZT-ISL69260IRAZ-T,SMLF,IC,AL069260000',
 PART_NUMBER='AL069260000',
 VALUE='ISL69260IRAZ-T',
 PRIM_FILE='./archive_libs/logical/isl69260irazt/chips/chips.prt';

PART_NAME
 PU6511 'ISL99390FRZTR5935-ISL99390FRZ-TR5935,SMLF,IC,AL099A':;

SECTION_NUMBER 1
 '@T6G_MB_LIB.T6G(SCH_1):PAGE478_I51@PURE_QUANTA.ISL99390FRZTR5935(CHIPS)':
 C_PATH='@t6g_mb_lib.t6g(sch_1):page478_i51@pure_quanta.isl99390frztr5935(chips)~
',
 P_PATH='@t6g_mb_lib.t6g(sch_1):page365_i51@pure_quanta.isl99390frztr5935(chips)~
',
 PATH='I51',
 DRAWING='@T6G_MB_LIB.T6G(SCH_1):PAGE478',
 SEC_TYPE='',
 BOM_COST='VR_DIMM ',
 PART_TYPE='SMLF',
 MATERIAL='IC',
 PHYS_PAGE='365',
 XY='(-7075,4350)',
 ROT='0',
 VER='1',
 LOCATION='PU6511',
 SEC='1',
 CDS_LIB='pure_quanta',
 CDS_PART_NAME='ISL99390FRZTR5935-ISL99390FRZ-TR5935,SMLF,IC,AL099A',
 PART_NUMBER='AL099390004',
 VALUE='ISL99390FRZ-TR5935',
 PRIM_FILE='./archive_libs/logical/isl99390frztr5935/chips/chips.prt';

PART_NAME
 PU6512 'ISL99390FRZTR5935-ISL99390FRZ-TR5935,SMLF,IC,AL099A':;

SECTION_NUMBER 1
 '@T6G_MB_LIB.T6G(SCH_1):PAGE478_I12@PURE_QUANTA.ISL99390FRZTR5935(CHIPS)':
 C_PATH='@t6g_mb_lib.t6g(sch_1):page478_i12@pure_quanta.isl99390frztr5935(chips)~
',
 P_PATH='@t6g_mb_lib.t6g(sch_1):page365_i12@pure_quanta.isl99390frztr5935(chips)~
',
 PATH='I12',
 DRAWING='@T6G_MB_LIB.T6G(SCH_1):PAGE478',
 SEC_TYPE='',
 BOM_COST='VR_DIMM ',
 PART_TYPE='SMLF',
 MATERIAL='IC',
 PHYS_PAGE='365',
 XY='(-6950,1450)',
 ROT='0',
 VER='1',
 LOCATION='PU6512',
 SEC='1',
 CDS_LIB='pure_quanta',
 CDS_PART_NAME='ISL99390FRZTR5935-ISL99390FRZ-TR5935,SMLF,IC,AL099A',
 PART_NUMBER='AL099390004',
 VALUE='ISL99390FRZ-TR5935',
 PRIM_FILE='./archive_libs/logical/isl99390frztr5935/chips/chips.prt';

PART_NAME
 Q1 'MOSFET_NCH_DUAL-PJT138K,SMLF,IC,BAM138K0003':;

SECTION_NUMBER 1
 '@T6G_MB_LIB.T6G(SCH_1):PAGE273_I97@PURE_QUANTA.MOSFET_NCH_DUAL(CHIPS)':
 C_PATH='@t6g_mb_lib.t6g(sch_1):page273_i97@pure_quanta.mosfet_nch_dual(chips)',
 P_PATH='@t6g_mb_lib.t6g(sch_1):page188_i97@pure_quanta.mosfet_nch_dual(chips)',
 PATH='I97',
 DRAWING='@T6G_MB_LIB.T6G(SCH_1):PAGE273',
 SEC_TYPE='',
 PART_TYPE='SMLF',
 MATERIAL='IC',
 PHYS_PAGE='188',
 XY='(-1500,2550)',
 ROT='0',
 VER='1',
 LOCATION='Q1',
 SEC='1',
 CDS_LIB='pure_quanta',
 CDS_PART_NAME='MOSFET_NCH_DUAL-PJT138K,SMLF,IC,BAM138K0003',
 PART_NUMBER='BAM138K0003',
 VALUE='PJT138K',
 PRIM_FILE='./archive_libs/logical/mosfet_nch_dual/chips/chips.prt';

SECTION_NUMBER 2
 '@T6G_MB_LIB.T6G(SCH_1):PAGE273_I98@PURE_QUANTA.MOSFET_NCH_DUAL(CHIPS)':
 C_PATH='@t6g_mb_lib.t6g(sch_1):page273_i98@pure_quanta.mosfet_nch_dual(chips)',
 P_PATH='@t6g_mb_lib.t6g(sch_1):page188_i98@pure_quanta.mosfet_nch_dual(chips)',
 PATH='I98',
 DRAWING='@T6G_MB_LIB.T6G(SCH_1):PAGE273',
 SEC_TYPE='',
 PART_TYPE='SMLF',
 MATERIAL='IC',
 PHYS_PAGE='188',
 XY='(250,2900)',
 ROT='0',
 VER='2',
 LOCATION='Q1',
 SEC='2',
 CDS_LIB='pure_quanta',
 CDS_PART_NAME='MOSFET_NCH_DUAL-PJT138K,SMLF,IC,BAM138K0003',
 PART_NUMBER='BAM138K0003',
 VALUE='PJT138K',
 PRIM_FILE='./archive_libs/logical/mosfet_nch_dual/chips/chips.prt';

PART_NAME
 Q2 'MOSFET_DUAL_6P-2N7002KDW,SMLF,IC,BAM70020047':;

SECTION_NUMBER 1
 '@T6G_MB_LIB.T6G(SCH_1):PAGE143_I16@PURE_QUANTA.MOSFET_DUAL_6P(CHIPS)':
 C_PATH='@t6g_mb_lib.t6g(sch_1):page143_i16@pure_quanta.mosfet_dual_6p(chips)',
 P_PATH='@t6g_mb_lib.t6g(sch_1):page166_i16@pure_quanta.mosfet_dual_6p(chips)',
 PATH='I16',
 DRAWING='@T6G_MB_LIB.T6G(SCH_1):PAGE143',
 PART_TYPE='SMLF',
 MATERIAL='IC',
 PHYS_PAGE='166',
 XY='(-4400,5125)',
 ROT='0',
 VER='1',
 LOCATION='Q2',
 CDS_LIB='pure_quanta',
 CDS_PART_NAME='MOSFET_DUAL_6P-2N7002KDW,SMLF,IC,BAM70020047',
 PART_NUMBER='BAM70020047',
 VALUE='2N7002KDW',
 PRIM_FILE='./archive_libs/logical/mosfet_dual_6p/chips/chips.prt';

PART_NAME
 Q3 'MOSFET_NCH_DUAL-PJT138K,SMLF,IC,BAM138K0003':;

SECTION_NUMBER 1
 '@T6G_MB_LIB.T6G(SCH_1):PAGE273_I107@PURE_QUANTA.MOSFET_NCH_DUAL(CHIPS)':
 C_PATH='@t6g_mb_lib.t6g(sch_1):page273_i107@pure_quanta.mosfet_nch_dual(chips)',
 P_PATH='@t6g_mb_lib.t6g(sch_1):page188_i107@pure_quanta.mosfet_nch_dual(chips)',
 PATH='I107',
 DRAWING='@T6G_MB_LIB.T6G(SCH_1):PAGE273',
 SEC_TYPE='',
 PART_TYPE='SMLF',
 MATERIAL='IC',
 PHYS_PAGE='188',
 XY='(-1125,4025)',
 ROT='0',
 VER='1',
 LOCATION='Q3',
 SEC='1',
 CDS_LIB='pure_quanta',
 CDS_PART_NAME='MOSFET_NCH_DUAL-PJT138K,SMLF,IC,BAM138K0003',
 PART_NUMBER='BAM138K0003',
 VALUE='PJT138K',
 PRIM_FILE='./archive_libs/logical/mosfet_nch_dual/chips/chips.prt';

SECTION_NUMBER 2
 '@T6G_MB_LIB.T6G(SCH_1):PAGE273_I108@PURE_QUANTA.MOSFET_NCH_DUAL(CHIPS)':
 C_PATH='@t6g_mb_lib.t6g(sch_1):page273_i108@pure_quanta.mosfet_nch_dual(chips)',
 P_PATH='@t6g_mb_lib.t6g(sch_1):page188_i108@pure_quanta.mosfet_nch_dual(chips)',
 PATH='I108',
 DRAWING='@T6G_MB_LIB.T6G(SCH_1):PAGE273',
 SEC_TYPE='',
 PART_TYPE='SMLF',
 MATERIAL='IC',
 PHYS_PAGE='188',
 XY='(-325,4075)',
 ROT='0',
 VER='2',
 LOCATION='Q3',
 SEC='2',
 CDS_LIB='pure_quanta',
 CDS_PART_NAME='MOSFET_NCH_DUAL-PJT138K,SMLF,IC,BAM138K0003',
 PART_NUMBER='BAM138K0003',
 VALUE='PJT138K',
 PRIM_FILE='./archive_libs/logical/mosfet_nch_dual/chips/chips.prt';

PART_NAME
 Q4 'MOSFET_DUAL_6P-2N7002KDW,SMLF,IC,BAM70020047':;

SECTION_NUMBER 1
 '@T6G_MB_LIB.T6G(SCH_1):PAGE132_I12@PURE_QUANTA.MOSFET_DUAL_6P(CHIPS)':
 C_PATH='@t6g_mb_lib.t6g(sch_1):page132_i12@pure_quanta.mosfet_dual_6p(chips)',
 P_PATH='@t6g_mb_lib.t6g(sch_1):page155_i12@pure_quanta.mosfet_dual_6p(chips)',
 PATH='I12',
 DRAWING='@T6G_MB_LIB.T6G(SCH_1):PAGE132',
 PART_TYPE='SMLF',
 MATERIAL='IC',
 PHYS_PAGE='155',
 XY='(-2475,4450)',
 ROT='0',
 VER='1',
 LOCATION='Q4',
 CDS_LIB='pure_quanta',
 CDS_PART_NAME='MOSFET_DUAL_6P-2N7002KDW,SMLF,IC,BAM70020047',
 PART_NUMBER='BAM70020047',
 VALUE='2N7002KDW',
 PRIM_FILE='./archive_libs/logical/mosfet_dual_6p/chips/chips.prt';

PART_NAME
 Q8 'MOSFET_DUAL_6P-2N7002KDW,SMLF,IC,BAM70020047':;

SECTION_NUMBER 1
 '@T6G_MB_LIB.T6G(SCH_1):PAGE156_I104@PURE_QUANTA.MOSFET_DUAL_6P(CHIPS)':
 C_PATH='@t6g_mb_lib.t6g(sch_1):page156_i104@pure_quanta.mosfet_dual_6p(chips)',
 P_PATH='@t6g_mb_lib.t6g(sch_1):page187_i104@pure_quanta.mosfet_dual_6p(chips)',
 PATH='I104',
 DRAWING='@T6G_MB_LIB.T6G(SCH_1):PAGE156',
 PART_TYPE='SMLF',
 MATERIAL='IC',
 PHYS_PAGE='187',
 XY='(-5300,5025)',
 ROT='0',
 VER='1',
 LOCATION='Q8',
 CDS_LIB='pure_quanta',
 CDS_PART_NAME='MOSFET_DUAL_6P-2N7002KDW,SMLF,IC,BAM70020047',
 PART_NUMBER='BAM70020047',
 VALUE='2N7002KDW',
 PRIM_FILE='./archive_libs/logical/mosfet_dual_6p/chips/chips.prt';

PART_NAME
 Q11 'MOSFET_DUAL_6P-2N7002KDW,SMLF,IC,BAM70020047':;

SECTION_NUMBER 1
 '@T6G_MB_LIB.T6G(SCH_1):PAGE143_I19@PURE_QUANTA.MOSFET_DUAL_6P(CHIPS)':
 C_PATH='@t6g_mb_lib.t6g(sch_1):page143_i19@pure_quanta.mosfet_dual_6p(chips)',
 P_PATH='@t6g_mb_lib.t6g(sch_1):page166_i19@pure_quanta.mosfet_dual_6p(chips)',
 PATH='I19',
 DRAWING='@T6G_MB_LIB.T6G(SCH_1):PAGE143',
 PART_TYPE='SMLF',
 MATERIAL='IC',
 PHYS_PAGE='166',
 XY='(-4550,3500)',
 ROT='0',
 VER='1',
 LOCATION='Q11',
 CDS_LIB='pure_quanta',
 CDS_PART_NAME='MOSFET_DUAL_6P-2N7002KDW,SMLF,IC,BAM70020047',
 PART_NUMBER='BAM70020047',
 VALUE='2N7002KDW',
 PRIM_FILE='./archive_libs/logical/mosfet_dual_6p/chips/chips.prt';

PART_NAME
 Q12 'MOSFET_N_GSD-NX138BK,SMLF,IC,BAM01380023':;

SECTION_NUMBER 1
 '@T6G_MB_LIB.T6G(SCH_1):PAGE143_I44@PURE_QUANTA.MOSFET_N_GSD(CHIPS)':
 C_PATH='@t6g_mb_lib.t6g(sch_1):page143_i44@pure_quanta.mosfet_n_gsd(chips)',
 P_PATH='@t6g_mb_lib.t6g(sch_1):page166_i44@pure_quanta.mosfet_n_gsd(chips)',
 PATH='I44',
 DRAWING='@T6G_MB_LIB.T6G(SCH_1):PAGE143',
 PART_TYPE='SMLF',
 MATERIAL='IC',
 PHYS_PAGE='166',
 XY='(-4875,1625)',
 ROT='0',
 VER='1',
 LOCATION='Q12',
 CDS_LIB='pure_quanta',
 CDS_PART_NAME='MOSFET_N_GSD-NX138BK,SMLF,IC,BAM01380023',
 PART_NUMBER='BAM01380023',
 VALUE='NX138BK',
 PRIM_FILE='./archive_libs/logical/mosfet_n_gsd/chips/chips.prt';

PART_NAME
 Q18 'BSS138DW7F-BSS138DW-7-F,SMLF,IC,BAM01380032':;

SECTION_NUMBER 1
 '@T6G_MB_LIB.T6G(SCH_1):PAGE264_I36@PURE_QUANTA.BSS138DW7F(CHIPS)':
 C_PATH='@t6g_mb_lib.t6g(sch_1):page264_i36@pure_quanta.bss138dw7f(chips)',
 P_PATH='@t6g_mb_lib.t6g(sch_1):page259_i36@pure_quanta.bss138dw7f(chips)',
 PATH='I36',
 DRAWING='@T6G_MB_LIB.T6G(SCH_1):PAGE264',
 PART_TYPE='SMLF',
 MATERIAL='IC',
 PHYS_PAGE='259',
 XY='(-5050,5475)',
 ROT='0',
 VER='1',
 LOCATION='Q18',
 CDS_LIB='pure_quanta',
 CDS_PART_NAME='BSS138DW7F-BSS138DW-7-F,SMLF,IC,BAM01380032',
 PART_NUMBER='BAM01380032',
 VALUE='BSS138DW-7-F',
 PRIM_FILE='./archive_libs/logical/bss138dw7f/chips/chips.prt';

PART_NAME
 Q19 'BSS138DW7F-BSS138DW-7-F,SMLF,IC,BAM01380032':;

SECTION_NUMBER 1
 '@T6G_MB_LIB.T6G(SCH_1):PAGE264_I33@PURE_QUANTA.BSS138DW7F(CHIPS)':
 C_PATH='@t6g_mb_lib.t6g(sch_1):page264_i33@pure_quanta.bss138dw7f(chips)',
 P_PATH='@t6g_mb_lib.t6g(sch_1):page259_i33@pure_quanta.bss138dw7f(chips)',
 PATH='I33',
 DRAWING='@T6G_MB_LIB.T6G(SCH_1):PAGE264',
 PART_TYPE='SMLF',
 MATERIAL='IC',
 PHYS_PAGE='259',
 XY='(-4800,4150)',
 ROT='0',
 VER='1',
 LOCATION='Q19',
 CDS_LIB='pure_quanta',
 CDS_PART_NAME='BSS138DW7F-BSS138DW-7-F,SMLF,IC,BAM01380032',
 PART_NUMBER='BAM01380032',
 VALUE='BSS138DW-7-F',
 PRIM_FILE='./archive_libs/logical/bss138dw7f/chips/chips.prt';

PART_NAME
 Q27 'BSS138DW7F-BSS138DW-7-F,SMLF,IC,BAM01380032':;

SECTION_NUMBER 1
 '@T6G_MB_LIB.T6G(SCH_1):PAGE273_I123@PURE_QUANTA.BSS138DW7F(CHIPS)':
 C_PATH='@t6g_mb_lib.t6g(sch_1):page273_i123@pure_quanta.bss138dw7f(chips)',
 P_PATH='@t6g_mb_lib.t6g(sch_1):page188_i123@pure_quanta.bss138dw7f(chips)',
 PATH='I123',
 DRAWING='@T6G_MB_LIB.T6G(SCH_1):PAGE273',
 PART_TYPE='SMLF',
 MATERIAL='IC',
 PHYS_PAGE='188',
 XY='(-5050,2225)',
 ROT='0',
 VER='1',
 LOCATION='Q27',
 CDS_LIB='pure_quanta',
 CDS_PART_NAME='BSS138DW7F-BSS138DW-7-F,SMLF,IC,BAM01380032',
 PART_NUMBER='BAM01380032',
 VALUE='BSS138DW-7-F',
 PRIM_FILE='./archive_libs/logical/bss138dw7f/chips/chips.prt';

PART_NAME
 Q28 'MOSFET_DUAL_6P-2N7002KDW,SMLF,IC,BAM70020047':;

SECTION_NUMBER 1
 '@T6G_MB_LIB.T6G(SCH_1):PAGE84_I48@PURE_QUANTA.MOSFET_DUAL_6P(CHIPS)':
 C_PATH='@t6g_mb_lib.t6g(sch_1):page84_i48@pure_quanta.mosfet_dual_6p(chips)',
 P_PATH='@t6g_mb_lib.t6g(sch_1):page85_i48@pure_quanta.mosfet_dual_6p(chips)',
 PATH='I48',
 DRAWING='@T6G_MB_LIB.T6G(SCH_1):PAGE84',
 PART_TYPE='SMLF',
 MATERIAL='IC',
 PHYS_PAGE='85',
 XY='(-1675,5350)',
 ROT='6',
 VER='1',
 LOCATION='Q28',
 CDS_LIB='pure_quanta',
 CDS_PART_NAME='MOSFET_DUAL_6P-2N7002KDW,SMLF,IC,BAM70020047',
 PART_NUMBER='BAM70020047',
 VALUE='2N7002KDW',
 PRIM_FILE='./archive_libs/logical/mosfet_dual_6p/chips/chips.prt';

PART_NAME
 Q29 'MOSFET_N_GSD-NX138BK,SMLF,IC,BAM01380023':;

SECTION_NUMBER 1
 '@T6G_MB_LIB.T6G(SCH_1):PAGE142_I80@PURE_QUANTA.MOSFET_N_GSD(CHIPS)':
 C_PATH='@t6g_mb_lib.t6g(sch_1):page142_i80@pure_quanta.mosfet_n_gsd(chips)',
 P_PATH='@t6g_mb_lib.t6g(sch_1):page165_i80@pure_quanta.mosfet_n_gsd(chips)',
 PATH='I80',
 DRAWING='@T6G_MB_LIB.T6G(SCH_1):PAGE142',
 PART_TYPE='SMLF',
 MATERIAL='IC',
 PHYS_PAGE='165',
 XY='(-3550,1300)',
 ROT='2',
 VER='1',
 LOCATION='Q29',
 CDS_LIB='pure_quanta',
 CDS_PART_NAME='MOSFET_N_GSD-NX138BK,SMLF,IC,BAM01380023',
 PART_NUMBER='BAM01380023',
 VALUE='NX138BK',
 PRIM_FILE='./archive_libs/logical/mosfet_n_gsd/chips/chips.prt';

PART_NAME
 Q30 'MOSFET_N_GSD-NX138BK,SMLF,IC,BAM01380023':;

SECTION_NUMBER 1
 '@T6G_MB_LIB.T6G(SCH_1):PAGE142_I81@PURE_QUANTA.MOSFET_N_GSD(CHIPS)':
 C_PATH='@t6g_mb_lib.t6g(sch_1):page142_i81@pure_quanta.mosfet_n_gsd(chips)',
 P_PATH='@t6g_mb_lib.t6g(sch_1):page165_i81@pure_quanta.mosfet_n_gsd(chips)',
 PATH='I81',
 DRAWING='@T6G_MB_LIB.T6G(SCH_1):PAGE142',
 PART_TYPE='SMLF',
 MATERIAL='IC',
 PHYS_PAGE='165',
 XY='(-2525,925)',
 ROT='2',
 VER='1',
 LOCATION='Q30',
 CDS_LIB='pure_quanta',
 CDS_PART_NAME='MOSFET_N_GSD-NX138BK,SMLF,IC,BAM01380023',
 PART_NUMBER='BAM01380023',
 VALUE='NX138BK',
 PRIM_FILE='./archive_libs/logical/mosfet_n_gsd/chips/chips.prt';

PART_NAME
 Q37 'MOSFET_NCH_DUAL-PJT138K,SMLF,IC,BAM138K0003':;

SECTION_NUMBER 1
 '@T6G_MB_LIB.T6G(SCH_1):PAGE273_I9@PURE_QUANTA.MOSFET_NCH_DUAL(CHIPS)':
 C_PATH='@t6g_mb_lib.t6g(sch_1):page273_i9@pure_quanta.mosfet_nch_dual(chips)',
 P_PATH='@t6g_mb_lib.t6g(sch_1):page188_i9@pure_quanta.mosfet_nch_dual(chips)',
 PATH='I9',
 DRAWING='@T6G_MB_LIB.T6G(SCH_1):PAGE273',
 PART_TYPE='SMLF',
 MATERIAL='IC',
 PHYS_PAGE='188',
 XY='(-5175,5000)',
 ROT='0',
 VER='1',
 LOCATION='Q37',
 CDS_LIB='pure_quanta',
 CDS_PART_NAME='MOSFET_NCH_DUAL-PJT138K,SMLF,IC,BAM138K0003',
 PART_NUMBER='BAM138K0003',
 VALUE='PJT138K',
 PRIM_FILE='./archive_libs/logical/mosfet_nch_dual/chips/chips.prt';

SECTION_NUMBER 2
 '@T6G_MB_LIB.T6G(SCH_1):PAGE273_I14@PURE_QUANTA.MOSFET_NCH_DUAL(CHIPS)':
 C_PATH='@t6g_mb_lib.t6g(sch_1):page273_i14@pure_quanta.mosfet_nch_dual(chips)',
 P_PATH='@t6g_mb_lib.t6g(sch_1):page188_i14@pure_quanta.mosfet_nch_dual(chips)',
 PATH='I14',
 DRAWING='@T6G_MB_LIB.T6G(SCH_1):PAGE273',
 PART_TYPE='SMLF',
 MATERIAL='IC',
 PHYS_PAGE='188',
 XY='(-4400,5325)',
 ROT='0',
 VER='2',
 LOCATION='Q37',
 CDS_LIB='pure_quanta',
 CDS_PART_NAME='MOSFET_NCH_DUAL-PJT138K,SMLF,IC,BAM138K0003',
 PART_NUMBER='BAM138K0003',
 VALUE='PJT138K',
 PRIM_FILE='./archive_libs/logical/mosfet_nch_dual/chips/chips.prt';

PART_NAME
 Q39 'MOSFET_NCH_GDS_ESD_PROTECTED-2N7002K,SMLF,IC,BAM70A':;

SECTION_NUMBER 1
 '@T6G_MB_LIB.T6G(SCH_1):PAGE350_I9@PURE_QUANTA.MOSFET_NCH_GDS_ESD_PROTECTED(CHIPS)':
 C_PATH='@t6g_mb_lib.t6g(sch_1):page350_i9@pure_quanta.mosfet_nch_gds_esd_protec~
ted(chips)',
 P_PATH='@t6g_mb_lib.t6g(sch_1):page152_i9@pure_quanta.mosfet_nch_gds_esd_protec~
ted(chips)',
 PATH='I9',
 DRAWING='@T6G_MB_LIB.T6G(SCH_1):PAGE350',
 PART_TYPE='SMLF',
 MATERIAL='IC',
 PHYS_PAGE='152',
 XY='(-775,13175)',
 ROT='0',
 VER='1',
 LOCATION='Q39',
 CDS_LIB='pure_quanta',
 CDS_PART_NAME='MOSFET_NCH_GDS_ESD_PROTECTED-2N7002K,SMLF,IC,BAM70A',
 PART_NUMBER='BAM70020002',
 VALUE='2N7002K',
 PRIM_FILE='./archive_libs/logical/mosfet_nch_gds_esd_protected/chips/chips.prt';

PART_NAME
 Q50 'MOSFET_NCH_DUAL-PJT138K,SMLF,IC,BAM138K0003':;

SECTION_NUMBER 1
 '@T6G_MB_LIB.T6G(SCH_1):PAGE84_I65@PURE_QUANTA.MOSFET_NCH_DUAL(CHIPS)':
 C_PATH='@t6g_mb_lib.t6g(sch_1):page84_i65@pure_quanta.mosfet_nch_dual(chips)',
 P_PATH='@t6g_mb_lib.t6g(sch_1):page85_i65@pure_quanta.mosfet_nch_dual(chips)',
 PATH='I65',
 DRAWING='@T6G_MB_LIB.T6G(SCH_1):PAGE84',
 PART_TYPE='SMLF',
 MATERIAL='IC',
 PHYS_PAGE='85',
 XY='(-3300,3575)',
 ROT='0',
 VER='1',
 LOCATION='Q50',
 CDS_LIB='pure_quanta',
 CDS_PART_NAME='MOSFET_NCH_DUAL-PJT138K,SMLF,IC,BAM138K0003',
 PART_NUMBER='BAM138K0003',
 VALUE='PJT138K',
 PRIM_FILE='./archive_libs/logical/mosfet_nch_dual/chips/chips.prt';

SECTION_NUMBER 2
 '@T6G_MB_LIB.T6G(SCH_1):PAGE84_I73@PURE_QUANTA.MOSFET_NCH_DUAL(CHIPS)':
 C_PATH='@t6g_mb_lib.t6g(sch_1):page84_i73@pure_quanta.mosfet_nch_dual(chips)',
 P_PATH='@t6g_mb_lib.t6g(sch_1):page85_i73@pure_quanta.mosfet_nch_dual(chips)',
 PATH='I73',
 DRAWING='@T6G_MB_LIB.T6G(SCH_1):PAGE84',
 PART_TYPE='SMLF',
 MATERIAL='IC',
 PHYS_PAGE='85',
 XY='(-2150,3575)',
 ROT='0',
 VER='2',
 LOCATION='Q50',
 CDS_LIB='pure_quanta',
 CDS_PART_NAME='MOSFET_NCH_DUAL-PJT138K,SMLF,IC,BAM138K0003',
 PART_NUMBER='BAM138K0003',
 VALUE='PJT138K',
 PRIM_FILE='./archive_libs/logical/mosfet_nch_dual/chips/chips.prt';

PART_NAME
 Q54 'MOSFET_NCH_GDS_ESD_PROTECTED-2N7002K,SMLF,IC,BAM70A':;

SECTION_NUMBER 1
 '@T6G_MB_LIB.T6G(SCH_1):PAGE365_I14@PURE_QUANTA.MOSFET_NCH_GDS_ESD_PROTECTED(CHIPS)':
 C_PATH='@t6g_mb_lib.t6g(sch_1):page365_i14@pure_quanta.mosfet_nch_gds_esd_prote~
cted(chips)',
 P_PATH='@t6g_mb_lib.t6g(sch_1):page242_i14@pure_quanta.mosfet_nch_gds_esd_prote~
cted(chips)',
 PATH='I14',
 DRAWING='@T6G_MB_LIB.T6G(SCH_1):PAGE365',
 PART_TYPE='SMLF',
 MATERIAL='IC',
 PHYS_PAGE='242',
 XY='(14000,3450)',
 ROT='0',
 VER='1',
 LOCATION='Q54',
 CDS_LIB='pure_quanta',
 CDS_PART_NAME='MOSFET_NCH_GDS_ESD_PROTECTED-2N7002K,SMLF,IC,BAM70A',
 PART_NUMBER='BAM70020002',
 VALUE='2N7002K',
 PRIM_FILE='./archive_libs/logical/mosfet_nch_gds_esd_protected/chips/chips.prt';

PART_NAME
 Q56 'MOSFET_NCH_1D3S-PSMNR58-30YLH,SMLF,IC,BAMNR580000':;

SECTION_NUMBER 1
 '@T6G_MB_LIB.T6G(SCH_1):PAGE273_I50@PURE_QUANTA.MOSFET_NCH_1D3S(CHIPS)':
 C_PATH='@t6g_mb_lib.t6g(sch_1):page273_i50@pure_quanta.mosfet_nch_1d3s(chips)',
 P_PATH='@t6g_mb_lib.t6g(sch_1):page188_i50@pure_quanta.mosfet_nch_1d3s(chips)',
 PATH='I50',
 DRAWING='@T6G_MB_LIB.T6G(SCH_1):PAGE273',
 PART_TYPE='SMLF',
 MATERIAL='IC',
 PHYS_PAGE='188',
 XY='(75,5250)',
 ROT='7',
 VER='1',
 LOCATION='Q56',
 CDS_LIB='pure_quanta',
 CDS_PART_NAME='MOSFET_NCH_1D3S-PSMNR58-30YLH,SMLF,IC,BAMNR580000',
 PART_NUMBER='BAMNR580000',
 VALUE='PSMNR58-30YLH',
 PRIM_FILE='./archive_libs/logical/mosfet_nch_1d3s/chips/chips.prt';

PART_NAME
 Q57 'MOSFET_NCH_1D3S-PSMNR58-30YLH,SMLF,IC,BAMNR580000':;

SECTION_NUMBER 1
 '@T6G_MB_LIB.T6G(SCH_1):PAGE273_I23@PURE_QUANTA.MOSFET_NCH_1D3S(CHIPS)':
 C_PATH='@t6g_mb_lib.t6g(sch_1):page273_i23@pure_quanta.mosfet_nch_1d3s(chips)',
 P_PATH='@t6g_mb_lib.t6g(sch_1):page188_i23@pure_quanta.mosfet_nch_1d3s(chips)',
 PATH='I23',
 DRAWING='@T6G_MB_LIB.T6G(SCH_1):PAGE273',
 PART_TYPE='SMLF',
 MATERIAL='IC',
 PHYS_PAGE='188',
 XY='(-4000,6900)',
 ROT='7',
 VER='1',
 LOCATION='Q57',
 CDS_LIB='pure_quanta',
 CDS_PART_NAME='MOSFET_NCH_1D3S-PSMNR58-30YLH,SMLF,IC,BAMNR580000',
 PART_NUMBER='BAMNR580000',
 VALUE='PSMNR58-30YLH',
 PRIM_FILE='./archive_libs/logical/mosfet_nch_1d3s/chips/chips.prt';

PART_NAME
 Q61 'MOSFET_N_GSD-NX138BK,SMLF,IC,BAM01380023':;

SECTION_NUMBER 1
 '@T6G_MB_LIB.T6G(SCH_1):PAGE141_I89@PURE_QUANTA.MOSFET_N_GSD(CHIPS)':
 C_PATH='@t6g_mb_lib.t6g(sch_1):page141_i89@pure_quanta.mosfet_n_gsd(chips)',
 P_PATH='@t6g_mb_lib.t6g(sch_1):page164_i89@pure_quanta.mosfet_n_gsd(chips)',
 PATH='I89',
 DRAWING='@T6G_MB_LIB.T6G(SCH_1):PAGE141',
 PART_TYPE='SMLF',
 MATERIAL='IC',
 PHYS_PAGE='164',
 XY='(-6900,2025)',
 ROT='0',
 VER='1',
 LOCATION='Q61',
 CDS_LIB='pure_quanta',
 CDS_PART_NAME='MOSFET_N_GSD-NX138BK,SMLF,IC,BAM01380023',
 PART_NUMBER='BAM01380023',
 VALUE='NX138BK',
 PRIM_FILE='./archive_libs/logical/mosfet_n_gsd/chips/chips.prt';

PART_NAME
 Q62 'MOSFET_N_SMLF-BSS138K,BSS138K,IC,BAM138K0000':;

SECTION_NUMBER 1
 '@T6G_MB_LIB.T6G(SCH_1):PAGE149_I102@PURE_QUANTA.MOSFET_N(CHIPS)':
 C_PATH='@t6g_mb_lib.t6g(sch_1):page149_i102@pure_quanta.mosfet_n(chips)',
 P_PATH='@t6g_mb_lib.t6g(sch_1):page172_i102@pure_quanta.mosfet_n(chips)',
 PATH='I102',
 DRAWING='@T6G_MB_LIB.T6G(SCH_1):PAGE149',
 MANUF_PN='BSS138K',
 PART_TYPE='SMLF',
 MATERIAL='IC',
 PHYS_PAGE='172',
 XY='(-7525,700)',
 ROT='0',
 VER='1',
 PACK_TYPE='SMLF',
 LOCATION='Q62',
 CDS_LIB='pure_quanta',
 CDS_PART_NAME='MOSFET_N_SMLF-BSS138K,BSS138K,IC,BAM138K0000',
 PART_NUMBER='BAM138K0000',
 VALUE='BSS138K',
 PRIM_FILE='./archive_libs/logical/mosfet_n/chips/chips.prt';

PART_NAME
 Q63 'MOSFET_N_SMLF-BSS138K,BSS138K,IC,BAM138K0000':;

SECTION_NUMBER 1
 '@T6G_MB_LIB.T6G(SCH_1):PAGE151_I45@PURE_QUANTA.MOSFET_N(CHIPS)':
 C_PATH='@t6g_mb_lib.t6g(sch_1):page151_i45@pure_quanta.mosfet_n(chips)',
 P_PATH='@t6g_mb_lib.t6g(sch_1):page174_i45@pure_quanta.mosfet_n(chips)',
 PATH='I45',
 DRAWING='@T6G_MB_LIB.T6G(SCH_1):PAGE151',
 MANUF_PN='BSS138K',
 PART_TYPE='SMLF',
 MATERIAL='IC',
 PHYS_PAGE='174',
 XY='(-7650,5075)',
 ROT='0',
 VER='1',
 PACK_TYPE='SMLF',
 LOCATION='Q63',
 CDS_LIB='pure_quanta',
 CDS_PART_NAME='MOSFET_N_SMLF-BSS138K,BSS138K,IC,BAM138K0000',
 PART_NUMBER='BAM138K0000',
 VALUE='BSS138K',
 PRIM_FILE='./archive_libs/logical/mosfet_n/chips/chips.prt';

PART_NAME
 Q64 'MOSFET_N_SMLF-BSS138K,BSS138K,IC,BAM138K0000':;

SECTION_NUMBER 1
 '@T6G_MB_LIB.T6G(SCH_1):PAGE151_I46@PURE_QUANTA.MOSFET_N(CHIPS)':
 C_PATH='@t6g_mb_lib.t6g(sch_1):page151_i46@pure_quanta.mosfet_n(chips)',
 P_PATH='@t6g_mb_lib.t6g(sch_1):page174_i46@pure_quanta.mosfet_n(chips)',
 PATH='I46',
 DRAWING='@T6G_MB_LIB.T6G(SCH_1):PAGE151',
 MANUF_PN='BSS138K',
 PART_TYPE='SMLF',
 MATERIAL='IC',
 PHYS_PAGE='174',
 XY='(-4600,3150)',
 ROT='0',
 VER='1',
 PACK_TYPE='SMLF',
 LOCATION='Q64',
 CDS_LIB='pure_quanta',
 CDS_PART_NAME='MOSFET_N_SMLF-BSS138K,BSS138K,IC,BAM138K0000',
 PART_NUMBER='BAM138K0000',
 VALUE='BSS138K',
 PRIM_FILE='./archive_libs/logical/mosfet_n/chips/chips.prt';

PART_NAME
 Q67 'MOSFET_NCH_DUAL-PJT138K,SMLF,IC,BAM138K0003':;

SECTION_NUMBER 1
 '@T6G_MB_LIB.T6G(SCH_1):PAGE333_I33@PURE_QUANTA.MOSFET_NCH_DUAL(CHIPS)':
 C_PATH='@t6g_mb_lib.t6g(sch_1):page333_i33@pure_quanta.mosfet_nch_dual(chips)',
 P_PATH='@t6g_mb_lib.t6g(sch_1):page127_i33@pure_quanta.mosfet_nch_dual(chips)',
 PATH='I33',
 DRAWING='@T6G_MB_LIB.T6G(SCH_1):PAGE333',
 PART_TYPE='SMLF',
 MATERIAL='IC',
 PHYS_PAGE='127',
 XY='(-3575,7400)',
 ROT='0',
 VER='1',
 LOCATION='Q67',
 CDS_LIB='pure_quanta',
 CDS_PART_NAME='MOSFET_NCH_DUAL-PJT138K,SMLF,IC,BAM138K0003',
 PART_NUMBER='BAM138K0003',
 VALUE='PJT138K',
 PRIM_FILE='./archive_libs/logical/mosfet_nch_dual/chips/chips.prt';

SECTION_NUMBER 2
 '@T6G_MB_LIB.T6G(SCH_1):PAGE333_I82@PURE_QUANTA.MOSFET_NCH_DUAL(CHIPS)':
 C_PATH='@t6g_mb_lib.t6g(sch_1):page333_i82@pure_quanta.mosfet_nch_dual(chips)',
 P_PATH='@t6g_mb_lib.t6g(sch_1):page127_i82@pure_quanta.mosfet_nch_dual(chips)',
 PATH='I82',
 DRAWING='@T6G_MB_LIB.T6G(SCH_1):PAGE333',
 PART_TYPE='SMLF',
 MATERIAL='IC',
 PHYS_PAGE='127',
 XY='(-2425,7700)',
 ROT='0',
 VER='2',
 LOCATION='Q67',
 CDS_LIB='pure_quanta',
 CDS_PART_NAME='MOSFET_NCH_DUAL-PJT138K,SMLF,IC,BAM138K0003',
 PART_NUMBER='BAM138K0003',
 VALUE='PJT138K',
 PRIM_FILE='./archive_libs/logical/mosfet_nch_dual/chips/chips.prt';

PART_NAME
 Q69 'MOSFET_NCH_DUAL-PJT138K,SMLF,IC,BAM138K0003':;

SECTION_NUMBER 1
 '@T6G_MB_LIB.T6G(SCH_1):PAGE333_I117@PURE_QUANTA.MOSFET_NCH_DUAL(CHIPS)':
 C_PATH='@t6g_mb_lib.t6g(sch_1):page333_i117@pure_quanta.mosfet_nch_dual(chips)',
 P_PATH='@t6g_mb_lib.t6g(sch_1):page127_i117@pure_quanta.mosfet_nch_dual(chips)',
 PATH='I117',
 DRAWING='@T6G_MB_LIB.T6G(SCH_1):PAGE333',
 PART_TYPE='SMLF',
 MATERIAL='IC',
 PHYS_PAGE='127',
 XY='(-3525,6000)',
 ROT='0',
 VER='1',
 LOCATION='Q69',
 CDS_LIB='pure_quanta',
 CDS_PART_NAME='MOSFET_NCH_DUAL-PJT138K,SMLF,IC,BAM138K0003',
 PART_NUMBER='BAM138K0003',
 VALUE='PJT138K',
 PRIM_FILE='./archive_libs/logical/mosfet_nch_dual/chips/chips.prt';

SECTION_NUMBER 2
 '@T6G_MB_LIB.T6G(SCH_1):PAGE333_I88@PURE_QUANTA.MOSFET_NCH_DUAL(CHIPS)':
 C_PATH='@t6g_mb_lib.t6g(sch_1):page333_i88@pure_quanta.mosfet_nch_dual(chips)',
 P_PATH='@t6g_mb_lib.t6g(sch_1):page127_i88@pure_quanta.mosfet_nch_dual(chips)',
 PATH='I88',
 DRAWING='@T6G_MB_LIB.T6G(SCH_1):PAGE333',
 PART_TYPE='SMLF',
 MATERIAL='IC',
 PHYS_PAGE='127',
 XY='(-2525,6300)',
 ROT='0',
 VER='2',
 LOCATION='Q69',
 CDS_LIB='pure_quanta',
 CDS_PART_NAME='MOSFET_NCH_DUAL-PJT138K,SMLF,IC,BAM138K0003',
 PART_NUMBER='BAM138K0003',
 VALUE='PJT138K',
 PRIM_FILE='./archive_libs/logical/mosfet_nch_dual/chips/chips.prt';

PART_NAME
 Q70 'MOSFET_NCH_DUAL-PJT138K,SMLF,IC,BAM138K0003':;

SECTION_NUMBER 1
 '@T6G_MB_LIB.T6G(SCH_1):PAGE333_I35@PURE_QUANTA.MOSFET_NCH_DUAL(CHIPS)':
 C_PATH='@t6g_mb_lib.t6g(sch_1):page333_i35@pure_quanta.mosfet_nch_dual(chips)',
 P_PATH='@t6g_mb_lib.t6g(sch_1):page127_i35@pure_quanta.mosfet_nch_dual(chips)',
 PATH='I35',
 DRAWING='@T6G_MB_LIB.T6G(SCH_1):PAGE333',
 PART_TYPE='SMLF',
 MATERIAL='IC',
 PHYS_PAGE='127',
 XY='(-3500,4650)',
 ROT='0',
 VER='1',
 LOCATION='Q70',
 CDS_LIB='pure_quanta',
 CDS_PART_NAME='MOSFET_NCH_DUAL-PJT138K,SMLF,IC,BAM138K0003',
 PART_NUMBER='BAM138K0003',
 VALUE='PJT138K',
 PRIM_FILE='./archive_libs/logical/mosfet_nch_dual/chips/chips.prt';

SECTION_NUMBER 2
 '@T6G_MB_LIB.T6G(SCH_1):PAGE333_I120@PURE_QUANTA.MOSFET_NCH_DUAL(CHIPS)':
 C_PATH='@t6g_mb_lib.t6g(sch_1):page333_i120@pure_quanta.mosfet_nch_dual(chips)',
 P_PATH='@t6g_mb_lib.t6g(sch_1):page127_i120@pure_quanta.mosfet_nch_dual(chips)',
 PATH='I120',
 DRAWING='@T6G_MB_LIB.T6G(SCH_1):PAGE333',
 PART_TYPE='SMLF',
 MATERIAL='IC',
 PHYS_PAGE='127',
 XY='(-2550,4925)',
 ROT='0',
 VER='2',
 LOCATION='Q70',
 CDS_LIB='pure_quanta',
 CDS_PART_NAME='MOSFET_NCH_DUAL-PJT138K,SMLF,IC,BAM138K0003',
 PART_NUMBER='BAM138K0003',
 VALUE='PJT138K',
 PRIM_FILE='./archive_libs/logical/mosfet_nch_dual/chips/chips.prt';

PART_NAME
 Q71 'MOSFET_NCH_DUAL-PJT138K,SMLF,IC,BAM138K0003':;

SECTION_NUMBER 1
 '@T6G_MB_LIB.T6G(SCH_1):PAGE333_I118@PURE_QUANTA.MOSFET_NCH_DUAL(CHIPS)':
 C_PATH='@t6g_mb_lib.t6g(sch_1):page333_i118@pure_quanta.mosfet_nch_dual(chips)',
 P_PATH='@t6g_mb_lib.t6g(sch_1):page127_i118@pure_quanta.mosfet_nch_dual(chips)',
 PATH='I118',
 DRAWING='@T6G_MB_LIB.T6G(SCH_1):PAGE333',
 PART_TYPE='SMLF',
 MATERIAL='IC',
 PHYS_PAGE='127',
 XY='(1050,7525)',
 ROT='0',
 VER='1',
 LOCATION='Q71',
 CDS_LIB='pure_quanta',
 CDS_PART_NAME='MOSFET_NCH_DUAL-PJT138K,SMLF,IC,BAM138K0003',
 PART_NUMBER='BAM138K0003',
 VALUE='PJT138K',
 PRIM_FILE='./archive_libs/logical/mosfet_nch_dual/chips/chips.prt';

SECTION_NUMBER 2
 '@T6G_MB_LIB.T6G(SCH_1):PAGE333_I100@PURE_QUANTA.MOSFET_NCH_DUAL(CHIPS)':
 C_PATH='@t6g_mb_lib.t6g(sch_1):page333_i100@pure_quanta.mosfet_nch_dual(chips)',
 P_PATH='@t6g_mb_lib.t6g(sch_1):page127_i100@pure_quanta.mosfet_nch_dual(chips)',
 PATH='I100',
 DRAWING='@T6G_MB_LIB.T6G(SCH_1):PAGE333',
 PART_TYPE='SMLF',
 MATERIAL='IC',
 PHYS_PAGE='127',
 XY='(1875,7800)',
 ROT='0',
 VER='2',
 LOCATION='Q71',
 CDS_LIB='pure_quanta',
 CDS_PART_NAME='MOSFET_NCH_DUAL-PJT138K,SMLF,IC,BAM138K0003',
 PART_NUMBER='BAM138K0003',
 VALUE='PJT138K',
 PRIM_FILE='./archive_libs/logical/mosfet_nch_dual/chips/chips.prt';

PART_NAME
 Q72 'MOSFET_NCH_DUAL-PJT138K,SMLF,IC,BAM138K0003':;

SECTION_NUMBER 1
 '@T6G_MB_LIB.T6G(SCH_1):PAGE333_I37@PURE_QUANTA.MOSFET_NCH_DUAL(CHIPS)':
 C_PATH='@t6g_mb_lib.t6g(sch_1):page333_i37@pure_quanta.mosfet_nch_dual(chips)',
 P_PATH='@t6g_mb_lib.t6g(sch_1):page127_i37@pure_quanta.mosfet_nch_dual(chips)',
 PATH='I37',
 DRAWING='@T6G_MB_LIB.T6G(SCH_1):PAGE333',
 PART_TYPE='SMLF',
 MATERIAL='IC',
 PHYS_PAGE='127',
 XY='(1050,6150)',
 ROT='0',
 VER='1',
 LOCATION='Q72',
 CDS_LIB='pure_quanta',
 CDS_PART_NAME='MOSFET_NCH_DUAL-PJT138K,SMLF,IC,BAM138K0003',
 PART_NUMBER='BAM138K0003',
 VALUE='PJT138K',
 PRIM_FILE='./archive_libs/logical/mosfet_nch_dual/chips/chips.prt';

SECTION_NUMBER 2
 '@T6G_MB_LIB.T6G(SCH_1):PAGE333_I119@PURE_QUANTA.MOSFET_NCH_DUAL(CHIPS)':
 C_PATH='@t6g_mb_lib.t6g(sch_1):page333_i119@pure_quanta.mosfet_nch_dual(chips)',
 P_PATH='@t6g_mb_lib.t6g(sch_1):page127_i119@pure_quanta.mosfet_nch_dual(chips)',
 PATH='I119',
 DRAWING='@T6G_MB_LIB.T6G(SCH_1):PAGE333',
 SEC_TYPE='',
 PART_TYPE='SMLF',
 MATERIAL='IC',
 PHYS_PAGE='127',
 XY='(1975,6425)',
 ROT='0',
 VER='2',
 LOCATION='Q72',
 SEC='2',
 CDS_LIB='pure_quanta',
 CDS_PART_NAME='MOSFET_NCH_DUAL-PJT138K,SMLF,IC,BAM138K0003',
 PART_NUMBER='BAM138K0003',
 VALUE='PJT138K',
 PRIM_FILE='./archive_libs/logical/mosfet_nch_dual/chips/chips.prt';

PART_NAME
 Q74 'MOSFET_NCH_DUAL-PJT138K,SMLF,IC,BAM138K0003':;

SECTION_NUMBER 1
 '@T6G_MB_LIB.T6G(SCH_1):PAGE333_I121@PURE_QUANTA.MOSFET_NCH_DUAL(CHIPS)':
 C_PATH='@t6g_mb_lib.t6g(sch_1):page333_i121@pure_quanta.mosfet_nch_dual(chips)',
 P_PATH='@t6g_mb_lib.t6g(sch_1):page127_i121@pure_quanta.mosfet_nch_dual(chips)',
 PATH='I121',
 DRAWING='@T6G_MB_LIB.T6G(SCH_1):PAGE333',
 SEC_TYPE='',
 PART_TYPE='SMLF',
 MATERIAL='IC',
 PHYS_PAGE='127',
 XY='(1075,4775)',
 ROT='0',
 VER='1',
 LOCATION='Q74',
 SEC='1',
 CDS_LIB='pure_quanta',
 CDS_PART_NAME='MOSFET_NCH_DUAL-PJT138K,SMLF,IC,BAM138K0003',
 PART_NUMBER='BAM138K0003',
 VALUE='PJT138K',
 PRIM_FILE='./archive_libs/logical/mosfet_nch_dual/chips/chips.prt';

SECTION_NUMBER 2
 '@T6G_MB_LIB.T6G(SCH_1):PAGE333_I122@PURE_QUANTA.MOSFET_NCH_DUAL(CHIPS)':
 C_PATH='@t6g_mb_lib.t6g(sch_1):page333_i122@pure_quanta.mosfet_nch_dual(chips)',
 P_PATH='@t6g_mb_lib.t6g(sch_1):page127_i122@pure_quanta.mosfet_nch_dual(chips)',
 PATH='I122',
 DRAWING='@T6G_MB_LIB.T6G(SCH_1):PAGE333',
 SEC_TYPE='',
 PART_TYPE='SMLF',
 MATERIAL='IC',
 PHYS_PAGE='127',
 XY='(2000,5050)',
 ROT='0',
 VER='2',
 LOCATION='Q74',
 SEC='2',
 CDS_LIB='pure_quanta',
 CDS_PART_NAME='MOSFET_NCH_DUAL-PJT138K,SMLF,IC,BAM138K0003',
 PART_NUMBER='BAM138K0003',
 VALUE='PJT138K',
 PRIM_FILE='./archive_libs/logical/mosfet_nch_dual/chips/chips.prt';

PART_NAME
 Q75 'MOSFET_NCH_DUAL-PJT138K,SMLF,IC,BAM138K0003':;

SECTION_NUMBER 1
 '@T6G_MB_LIB.T6G(SCH_1):PAGE333_I152@PURE_QUANTA.MOSFET_NCH_DUAL(CHIPS)':
 C_PATH='@t6g_mb_lib.t6g(sch_1):page333_i152@pure_quanta.mosfet_nch_dual(chips)',
 P_PATH='@t6g_mb_lib.t6g(sch_1):page127_i152@pure_quanta.mosfet_nch_dual(chips)',
 PATH='I152',
 DRAWING='@T6G_MB_LIB.T6G(SCH_1):PAGE333',
 PART_TYPE='SMLF',
 MATERIAL='IC',
 PHYS_PAGE='127',
 XY='(-3475,3075)',
 ROT='0',
 VER='1',
 LOCATION='Q75',
 CDS_LIB='pure_quanta',
 CDS_PART_NAME='MOSFET_NCH_DUAL-PJT138K,SMLF,IC,BAM138K0003',
 PART_NUMBER='BAM138K0003',
 VALUE='PJT138K',
 PRIM_FILE='./archive_libs/logical/mosfet_nch_dual/chips/chips.prt';

SECTION_NUMBER 2
 '@T6G_MB_LIB.T6G(SCH_1):PAGE333_I151@PURE_QUANTA.MOSFET_NCH_DUAL(CHIPS)':
 C_PATH='@t6g_mb_lib.t6g(sch_1):page333_i151@pure_quanta.mosfet_nch_dual(chips)',
 P_PATH='@t6g_mb_lib.t6g(sch_1):page127_i151@pure_quanta.mosfet_nch_dual(chips)',
 PATH='I151',
 DRAWING='@T6G_MB_LIB.T6G(SCH_1):PAGE333',
 PART_TYPE='SMLF',
 MATERIAL='IC',
 PHYS_PAGE='127',
 XY='(-2550,3350)',
 ROT='0',
 VER='2',
 LOCATION='Q75',
 CDS_LIB='pure_quanta',
 CDS_PART_NAME='MOSFET_NCH_DUAL-PJT138K,SMLF,IC,BAM138K0003',
 PART_NUMBER='BAM138K0003',
 VALUE='PJT138K',
 PRIM_FILE='./archive_libs/logical/mosfet_nch_dual/chips/chips.prt';

PART_NAME
 Q78 'MOSFET_NCH_DUAL-PJT138K,SMLF,IC,BAM138K0003':;

SECTION_NUMBER 1
 '@T6G_MB_LIB.T6G(SCH_1):PAGE254_I24@PURE_QUANTA.MOSFET_NCH_DUAL(CHIPS)':
 C_PATH='@t6g_mb_lib.t6g(sch_1):page254_i24@pure_quanta.mosfet_nch_dual(chips)',
 P_PATH='@t6g_mb_lib.t6g(sch_1):page254_i24@pure_quanta.mosfet_nch_dual(chips)',
 PATH='I24',
 DRAWING='@T6G_MB_LIB.T6G(SCH_1):PAGE254',
 PART_TYPE='SMLF',
 MATERIAL='IC',
 PHYS_PAGE='254',
 XY='(-7675,4275)',
 ROT='0',
 VER='1',
 LOCATION='Q78',
 CDS_LIB='pure_quanta',
 CDS_PART_NAME='MOSFET_NCH_DUAL-PJT138K,SMLF,IC,BAM138K0003',
 PART_NUMBER='BAM138K0003',
 VALUE='PJT138K',
 PRIM_FILE='./archive_libs/logical/mosfet_nch_dual/chips/chips.prt';

SECTION_NUMBER 2
 '@T6G_MB_LIB.T6G(SCH_1):PAGE254_I18@PURE_QUANTA.MOSFET_NCH_DUAL(CHIPS)':
 C_PATH='@t6g_mb_lib.t6g(sch_1):page254_i18@pure_quanta.mosfet_nch_dual(chips)',
 P_PATH='@t6g_mb_lib.t6g(sch_1):page254_i18@pure_quanta.mosfet_nch_dual(chips)',
 PATH='I18',
 DRAWING='@T6G_MB_LIB.T6G(SCH_1):PAGE254',
 SEC_TYPE='',
 PART_TYPE='SMLF',
 MATERIAL='IC',
 PHYS_PAGE='254',
 XY='(-7750,5650)',
 ROT='0',
 VER='2',
 LOCATION='Q78',
 SEC='2',
 CDS_LIB='pure_quanta',
 CDS_PART_NAME='MOSFET_NCH_DUAL-PJT138K,SMLF,IC,BAM138K0003',
 PART_NUMBER='BAM138K0003',
 VALUE='PJT138K',
 PRIM_FILE='./archive_libs/logical/mosfet_nch_dual/chips/chips.prt';

PART_NAME
 Q79 'MOSFET_NCH_DUAL-PJT138K,SMLF,IC,BAM138K0003':;

SECTION_NUMBER 1
 '@T6G_MB_LIB.T6G(SCH_1):PAGE374_I18@PURE_QUANTA.MOSFET_NCH_DUAL(CHIPS)':
 C_PATH='@t6g_mb_lib.t6g(sch_1):page374_i18@pure_quanta.mosfet_nch_dual(chips)',
 P_PATH='@t6g_mb_lib.t6g(sch_1):page255_i18@pure_quanta.mosfet_nch_dual(chips)',
 PATH='I18',
 DRAWING='@T6G_MB_LIB.T6G(SCH_1):PAGE374',
 PART_TYPE='SMLF',
 MATERIAL='IC',
 PHYS_PAGE='255',
 XY='(-7975,5450)',
 ROT='0',
 VER='1',
 LOCATION='Q79',
 CDS_LIB='pure_quanta',
 CDS_PART_NAME='MOSFET_NCH_DUAL-PJT138K,SMLF,IC,BAM138K0003',
 PART_NUMBER='BAM138K0003',
 VALUE='PJT138K',
 PRIM_FILE='./archive_libs/logical/mosfet_nch_dual/chips/chips.prt';

SECTION_NUMBER 2
 '@T6G_MB_LIB.T6G(SCH_1):PAGE374_I8@PURE_QUANTA.MOSFET_NCH_DUAL(CHIPS)':
 C_PATH='@t6g_mb_lib.t6g(sch_1):page374_i8@pure_quanta.mosfet_nch_dual(chips)',
 P_PATH='@t6g_mb_lib.t6g(sch_1):page255_i8@pure_quanta.mosfet_nch_dual(chips)',
 PATH='I8',
 DRAWING='@T6G_MB_LIB.T6G(SCH_1):PAGE374',
 SEC_TYPE='',
 PART_TYPE='SMLF',
 MATERIAL='IC',
 PHYS_PAGE='255',
 XY='(-7975,4125)',
 ROT='0',
 VER='2',
 LOCATION='Q79',
 SEC='2',
 CDS_LIB='pure_quanta',
 CDS_PART_NAME='MOSFET_NCH_DUAL-PJT138K,SMLF,IC,BAM138K0003',
 PART_NUMBER='BAM138K0003',
 VALUE='PJT138K',
 PRIM_FILE='./archive_libs/logical/mosfet_nch_dual/chips/chips.prt';

PART_NAME
 Q80 'MOSFET_NCH_DUAL-PJT138K,SMLF,IC,BAM138K0003':;

SECTION_NUMBER 1
 '@T6G_MB_LIB.T6G(SCH_1):PAGE374_I6@PURE_QUANTA.MOSFET_NCH_DUAL(CHIPS)':
 C_PATH='@t6g_mb_lib.t6g(sch_1):page374_i6@pure_quanta.mosfet_nch_dual(chips)',
 P_PATH='@t6g_mb_lib.t6g(sch_1):page255_i6@pure_quanta.mosfet_nch_dual(chips)',
 PATH='I6',
 DRAWING='@T6G_MB_LIB.T6G(SCH_1):PAGE374',
 PART_TYPE='SMLF',
 MATERIAL='IC',
 PHYS_PAGE='255',
 XY='(-7975,2900)',
 ROT='0',
 VER='1',
 LOCATION='Q80',
 CDS_LIB='pure_quanta',
 CDS_PART_NAME='MOSFET_NCH_DUAL-PJT138K,SMLF,IC,BAM138K0003',
 PART_NUMBER='BAM138K0003',
 VALUE='PJT138K',
 PRIM_FILE='./archive_libs/logical/mosfet_nch_dual/chips/chips.prt';

SECTION_NUMBER 2
 '@T6G_MB_LIB.T6G(SCH_1):PAGE374_I3@PURE_QUANTA.MOSFET_NCH_DUAL(CHIPS)':
 C_PATH='@t6g_mb_lib.t6g(sch_1):page374_i3@pure_quanta.mosfet_nch_dual(chips)',
 P_PATH='@t6g_mb_lib.t6g(sch_1):page255_i3@pure_quanta.mosfet_nch_dual(chips)',
 PATH='I3',
 DRAWING='@T6G_MB_LIB.T6G(SCH_1):PAGE374',
 SEC_TYPE='',
 PART_TYPE='SMLF',
 MATERIAL='IC',
 PHYS_PAGE='255',
 XY='(-7975,1575)',
 ROT='0',
 VER='2',
 LOCATION='Q80',
 SEC='2',
 CDS_LIB='pure_quanta',
 CDS_PART_NAME='MOSFET_NCH_DUAL-PJT138K,SMLF,IC,BAM138K0003',
 PART_NUMBER='BAM138K0003',
 VALUE='PJT138K',
 PRIM_FILE='./archive_libs/logical/mosfet_nch_dual/chips/chips.prt';

PART_NAME
 Q81 'MOSFET_NCH_DUAL-PJT138K,SMLF,IC,BAM138K0003':;

SECTION_NUMBER 1
 '@T6G_MB_LIB.T6G(SCH_1):PAGE374_I35@PURE_QUANTA.MOSFET_NCH_DUAL(CHIPS)':
 C_PATH='@t6g_mb_lib.t6g(sch_1):page374_i35@pure_quanta.mosfet_nch_dual(chips)',
 P_PATH='@t6g_mb_lib.t6g(sch_1):page255_i35@pure_quanta.mosfet_nch_dual(chips)',
 PATH='I35',
 DRAWING='@T6G_MB_LIB.T6G(SCH_1):PAGE374',
 PART_TYPE='SMLF',
 MATERIAL='IC',
 PHYS_PAGE='255',
 XY='(-3200,5450)',
 ROT='0',
 VER='1',
 LOCATION='Q81',
 CDS_LIB='pure_quanta',
 CDS_PART_NAME='MOSFET_NCH_DUAL-PJT138K,SMLF,IC,BAM138K0003',
 PART_NUMBER='BAM138K0003',
 VALUE='PJT138K',
 PRIM_FILE='./archive_libs/logical/mosfet_nch_dual/chips/chips.prt';

SECTION_NUMBER 2
 '@T6G_MB_LIB.T6G(SCH_1):PAGE374_I27@PURE_QUANTA.MOSFET_NCH_DUAL(CHIPS)':
 C_PATH='@t6g_mb_lib.t6g(sch_1):page374_i27@pure_quanta.mosfet_nch_dual(chips)',
 P_PATH='@t6g_mb_lib.t6g(sch_1):page255_i27@pure_quanta.mosfet_nch_dual(chips)',
 PATH='I27',
 DRAWING='@T6G_MB_LIB.T6G(SCH_1):PAGE374',
 SEC_TYPE='',
 PART_TYPE='SMLF',
 MATERIAL='IC',
 PHYS_PAGE='255',
 XY='(-3200,4125)',
 ROT='0',
 VER='2',
 LOCATION='Q81',
 SEC='2',
 CDS_LIB='pure_quanta',
 CDS_PART_NAME='MOSFET_NCH_DUAL-PJT138K,SMLF,IC,BAM138K0003',
 PART_NUMBER='BAM138K0003',
 VALUE='PJT138K',
 PRIM_FILE='./archive_libs/logical/mosfet_nch_dual/chips/chips.prt';

PART_NAME
 Q83 'MOSFET_NCH_DUAL-PJT138K,SMLF,IC,BAM138K0003':;

SECTION_NUMBER 1
 '@T6G_MB_LIB.T6G(SCH_1):PAGE374_I23@PURE_QUANTA.MOSFET_NCH_DUAL(CHIPS)':
 C_PATH='@t6g_mb_lib.t6g(sch_1):page374_i23@pure_quanta.mosfet_nch_dual(chips)',
 P_PATH='@t6g_mb_lib.t6g(sch_1):page255_i23@pure_quanta.mosfet_nch_dual(chips)',
 PATH='I23',
 DRAWING='@T6G_MB_LIB.T6G(SCH_1):PAGE374',
 PART_TYPE='SMLF',
 MATERIAL='IC',
 PHYS_PAGE='255',
 XY='(-3200,2875)',
 ROT='0',
 VER='1',
 LOCATION='Q83',
 CDS_LIB='pure_quanta',
 CDS_PART_NAME='MOSFET_NCH_DUAL-PJT138K,SMLF,IC,BAM138K0003',
 PART_NUMBER='BAM138K0003',
 VALUE='PJT138K',
 PRIM_FILE='./archive_libs/logical/mosfet_nch_dual/chips/chips.prt';

SECTION_NUMBER 2
 '@T6G_MB_LIB.T6G(SCH_1):PAGE374_I43@PURE_QUANTA.MOSFET_NCH_DUAL(CHIPS)':
 C_PATH='@t6g_mb_lib.t6g(sch_1):page374_i43@pure_quanta.mosfet_nch_dual(chips)',
 P_PATH='@t6g_mb_lib.t6g(sch_1):page255_i43@pure_quanta.mosfet_nch_dual(chips)',
 PATH='I43',
 DRAWING='@T6G_MB_LIB.T6G(SCH_1):PAGE374',
 PART_TYPE='SMLF',
 MATERIAL='IC',
 PHYS_PAGE='255',
 XY='(-3175,1900)',
 ROT='0',
 VER='2',
 LOCATION='Q83',
 CDS_LIB='pure_quanta',
 CDS_PART_NAME='MOSFET_NCH_DUAL-PJT138K,SMLF,IC,BAM138K0003',
 PART_NUMBER='BAM138K0003',
 VALUE='PJT138K',
 PRIM_FILE='./archive_libs/logical/mosfet_nch_dual/chips/chips.prt';

PART_NAME
 Q84 'MOSFET_NCH_DUAL-PJT138K,SMLF,IC,BAM138K0003':;

SECTION_NUMBER 1
 '@T6G_MB_LIB.T6G(SCH_1):PAGE375_I11@PURE_QUANTA.MOSFET_NCH_DUAL(CHIPS)':
 C_PATH='@t6g_mb_lib.t6g(sch_1):page375_i11@pure_quanta.mosfet_nch_dual(chips)',
 P_PATH='@t6g_mb_lib.t6g(sch_1):page256_i11@pure_quanta.mosfet_nch_dual(chips)',
 PATH='I11',
 DRAWING='@T6G_MB_LIB.T6G(SCH_1):PAGE375',
 PART_TYPE='SMLF',
 MATERIAL='IC',
 PHYS_PAGE='256',
 XY='(-7925,5725)',
 ROT='0',
 VER='1',
 LOCATION='Q84',
 CDS_LIB='pure_quanta',
 CDS_PART_NAME='MOSFET_NCH_DUAL-PJT138K,SMLF,IC,BAM138K0003',
 PART_NUMBER='BAM138K0003',
 VALUE='PJT138K',
 PRIM_FILE='./archive_libs/logical/mosfet_nch_dual/chips/chips.prt';

SECTION_NUMBER 2
 '@T6G_MB_LIB.T6G(SCH_1):PAGE375_I10@PURE_QUANTA.MOSFET_NCH_DUAL(CHIPS)':
 C_PATH='@t6g_mb_lib.t6g(sch_1):page375_i10@pure_quanta.mosfet_nch_dual(chips)',
 P_PATH='@t6g_mb_lib.t6g(sch_1):page256_i10@pure_quanta.mosfet_nch_dual(chips)',
 PATH='I10',
 DRAWING='@T6G_MB_LIB.T6G(SCH_1):PAGE375',
 SEC_TYPE='',
 PART_TYPE='SMLF',
 MATERIAL='IC',
 PHYS_PAGE='256',
 XY='(-7925,4400)',
 ROT='0',
 VER='2',
 LOCATION='Q84',
 SEC='2',
 CDS_LIB='pure_quanta',
 CDS_PART_NAME='MOSFET_NCH_DUAL-PJT138K,SMLF,IC,BAM138K0003',
 PART_NUMBER='BAM138K0003',
 VALUE='PJT138K',
 PRIM_FILE='./archive_libs/logical/mosfet_nch_dual/chips/chips.prt';

PART_NAME
 Q85 'MOSFET_NCH_DUAL-PJT138K,SMLF,IC,BAM138K0003':;

SECTION_NUMBER 1
 '@T6G_MB_LIB.T6G(SCH_1):PAGE375_I7@PURE_QUANTA.MOSFET_NCH_DUAL(CHIPS)':
 C_PATH='@t6g_mb_lib.t6g(sch_1):page375_i7@pure_quanta.mosfet_nch_dual(chips)',
 P_PATH='@t6g_mb_lib.t6g(sch_1):page256_i7@pure_quanta.mosfet_nch_dual(chips)',
 PATH='I7',
 DRAWING='@T6G_MB_LIB.T6G(SCH_1):PAGE375',
 PART_TYPE='SMLF',
 MATERIAL='IC',
 PHYS_PAGE='256',
 XY='(-7925,3175)',
 ROT='0',
 VER='1',
 LOCATION='Q85',
 CDS_LIB='pure_quanta',
 CDS_PART_NAME='MOSFET_NCH_DUAL-PJT138K,SMLF,IC,BAM138K0003',
 PART_NUMBER='BAM138K0003',
 VALUE='PJT138K',
 PRIM_FILE='./archive_libs/logical/mosfet_nch_dual/chips/chips.prt';

SECTION_NUMBER 2
 '@T6G_MB_LIB.T6G(SCH_1):PAGE375_I2@PURE_QUANTA.MOSFET_NCH_DUAL(CHIPS)':
 C_PATH='@t6g_mb_lib.t6g(sch_1):page375_i2@pure_quanta.mosfet_nch_dual(chips)',
 P_PATH='@t6g_mb_lib.t6g(sch_1):page256_i2@pure_quanta.mosfet_nch_dual(chips)',
 PATH='I2',
 DRAWING='@T6G_MB_LIB.T6G(SCH_1):PAGE375',
 SEC_TYPE='',
 PART_TYPE='SMLF',
 MATERIAL='IC',
 PHYS_PAGE='256',
 XY='(-7925,1850)',
 ROT='0',
 VER='2',
 LOCATION='Q85',
 SEC='2',
 CDS_LIB='pure_quanta',
 CDS_PART_NAME='MOSFET_NCH_DUAL-PJT138K,SMLF,IC,BAM138K0003',
 PART_NUMBER='BAM138K0003',
 VALUE='PJT138K',
 PRIM_FILE='./archive_libs/logical/mosfet_nch_dual/chips/chips.prt';

PART_NAME
 Q86 'MOSFET_NCH_DUAL-PJT138K,SMLF,IC,BAM138K0003':;

SECTION_NUMBER 1
 '@T6G_MB_LIB.T6G(SCH_1):PAGE375_I30@PURE_QUANTA.MOSFET_NCH_DUAL(CHIPS)':
 C_PATH='@t6g_mb_lib.t6g(sch_1):page375_i30@pure_quanta.mosfet_nch_dual(chips)',
 P_PATH='@t6g_mb_lib.t6g(sch_1):page256_i30@pure_quanta.mosfet_nch_dual(chips)',
 PATH='I30',
 DRAWING='@T6G_MB_LIB.T6G(SCH_1):PAGE375',
 PART_TYPE='SMLF',
 MATERIAL='IC',
 PHYS_PAGE='256',
 XY='(-3250,5750)',
 ROT='0',
 VER='1',
 LOCATION='Q86',
 CDS_LIB='pure_quanta',
 CDS_PART_NAME='MOSFET_NCH_DUAL-PJT138K,SMLF,IC,BAM138K0003',
 PART_NUMBER='BAM138K0003',
 VALUE='PJT138K',
 PRIM_FILE='./archive_libs/logical/mosfet_nch_dual/chips/chips.prt';

SECTION_NUMBER 2
 '@T6G_MB_LIB.T6G(SCH_1):PAGE375_I29@PURE_QUANTA.MOSFET_NCH_DUAL(CHIPS)':
 C_PATH='@t6g_mb_lib.t6g(sch_1):page375_i29@pure_quanta.mosfet_nch_dual(chips)',
 P_PATH='@t6g_mb_lib.t6g(sch_1):page256_i29@pure_quanta.mosfet_nch_dual(chips)',
 PATH='I29',
 DRAWING='@T6G_MB_LIB.T6G(SCH_1):PAGE375',
 SEC_TYPE='',
 PART_TYPE='SMLF',
 MATERIAL='IC',
 PHYS_PAGE='256',
 XY='(-3250,4425)',
 ROT='0',
 VER='2',
 LOCATION='Q86',
 SEC='2',
 CDS_LIB='pure_quanta',
 CDS_PART_NAME='MOSFET_NCH_DUAL-PJT138K,SMLF,IC,BAM138K0003',
 PART_NUMBER='BAM138K0003',
 VALUE='PJT138K',
 PRIM_FILE='./archive_libs/logical/mosfet_nch_dual/chips/chips.prt';

PART_NAME
 Q87 'MOSFET_NCH_DUAL-PJT138K,SMLF,IC,BAM138K0003':;

SECTION_NUMBER 1
 '@T6G_MB_LIB.T6G(SCH_1):PAGE254_I38@PURE_QUANTA.MOSFET_NCH_DUAL(CHIPS)':
 C_PATH='@t6g_mb_lib.t6g(sch_1):page254_i38@pure_quanta.mosfet_nch_dual(chips)',
 P_PATH='@t6g_mb_lib.t6g(sch_1):page254_i38@pure_quanta.mosfet_nch_dual(chips)',
 PATH='I38',
 DRAWING='@T6G_MB_LIB.T6G(SCH_1):PAGE254',
 PART_TYPE='SMLF',
 MATERIAL='IC',
 PHYS_PAGE='254',
 XY='(-7700,2850)',
 ROT='0',
 VER='1',
 LOCATION='Q87',
 CDS_LIB='pure_quanta',
 CDS_PART_NAME='MOSFET_NCH_DUAL-PJT138K,SMLF,IC,BAM138K0003',
 PART_NUMBER='BAM138K0003',
 VALUE='PJT138K',
 PRIM_FILE='./archive_libs/logical/mosfet_nch_dual/chips/chips.prt';

SECTION_NUMBER 2
 '@T6G_MB_LIB.T6G(SCH_1):PAGE254_I35@PURE_QUANTA.MOSFET_NCH_DUAL(CHIPS)':
 C_PATH='@t6g_mb_lib.t6g(sch_1):page254_i35@pure_quanta.mosfet_nch_dual(chips)',
 P_PATH='@t6g_mb_lib.t6g(sch_1):page254_i35@pure_quanta.mosfet_nch_dual(chips)',
 PATH='I35',
 DRAWING='@T6G_MB_LIB.T6G(SCH_1):PAGE254',
 SEC_TYPE='',
 PART_TYPE='SMLF',
 MATERIAL='IC',
 PHYS_PAGE='254',
 XY='(-7750,1200)',
 ROT='0',
 VER='2',
 LOCATION='Q87',
 SEC='2',
 CDS_LIB='pure_quanta',
 CDS_PART_NAME='MOSFET_NCH_DUAL-PJT138K,SMLF,IC,BAM138K0003',
 PART_NUMBER='BAM138K0003',
 VALUE='PJT138K',
 PRIM_FILE='./archive_libs/logical/mosfet_nch_dual/chips/chips.prt';

PART_NAME
 Q95 'MOSFET_NCH_DUAL-PJT138K,SMLF,IC,BAM138K0003':;

SECTION_NUMBER 1
 '@T6G_MB_LIB.T6G(SCH_1):PAGE345_I8@PURE_QUANTA.MOSFET_NCH_DUAL(CHIPS)':
 C_PATH='@t6g_mb_lib.t6g(sch_1):page345_i8@pure_quanta.mosfet_nch_dual(chips)',
 P_PATH='@t6g_mb_lib.t6g(sch_1):page144_i8@pure_quanta.mosfet_nch_dual(chips)',
 PATH='I8',
 DRAWING='@T6G_MB_LIB.T6G(SCH_1):PAGE345',
 SEC_TYPE='',
 PART_TYPE='SMLF',
 MATERIAL='IC',
 PHYS_PAGE='144',
 XY='(9750,-125)',
 ROT='0',
 VER='1',
 LOCATION='Q95',
 SEC='1',
 CDS_LIB='pure_quanta',
 CDS_PART_NAME='MOSFET_NCH_DUAL-PJT138K,SMLF,IC,BAM138K0003',
 PART_NUMBER='BAM138K0003',
 VALUE='PJT138K',
 PRIM_FILE='./archive_libs/logical/mosfet_nch_dual/chips/chips.prt';

SECTION_NUMBER 2
 '@T6G_MB_LIB.T6G(SCH_1):PAGE345_I89@PURE_QUANTA.MOSFET_NCH_DUAL(CHIPS)':
 C_PATH='@t6g_mb_lib.t6g(sch_1):page345_i89@pure_quanta.mosfet_nch_dual(chips)',
 P_PATH='@t6g_mb_lib.t6g(sch_1):page144_i89@pure_quanta.mosfet_nch_dual(chips)',
 PATH='I89',
 DRAWING='@T6G_MB_LIB.T6G(SCH_1):PAGE345',
 PART_TYPE='SMLF',
 MATERIAL='IC',
 PHYS_PAGE='144',
 XY='(10400,-800)',
 ROT='0',
 VER='2',
 LOCATION='Q95',
 CDS_LIB='pure_quanta',
 CDS_PART_NAME='MOSFET_NCH_DUAL-PJT138K,SMLF,IC,BAM138K0003',
 PART_NUMBER='BAM138K0003',
 VALUE='PJT138K',
 PRIM_FILE='./archive_libs/logical/mosfet_nch_dual/chips/chips.prt';

PART_NAME
 Q96 'MOSFET_NCH_DUAL-PJT138K,SMLF,IC,BAM138K0003':;

SECTION_NUMBER 1
 '@T6G_MB_LIB.T6G(SCH_1):PAGE333_I154@PURE_QUANTA.MOSFET_NCH_DUAL(CHIPS)':
 C_PATH='@t6g_mb_lib.t6g(sch_1):page333_i154@pure_quanta.mosfet_nch_dual(chips)',
 P_PATH='@t6g_mb_lib.t6g(sch_1):page127_i154@pure_quanta.mosfet_nch_dual(chips)',
 PATH='I154',
 DRAWING='@T6G_MB_LIB.T6G(SCH_1):PAGE333',
 PART_TYPE='SMLF',
 MATERIAL='IC',
 PHYS_PAGE='127',
 XY='(1025,3225)',
 ROT='0',
 VER='1',
 LOCATION='Q96',
 CDS_LIB='pure_quanta',
 CDS_PART_NAME='MOSFET_NCH_DUAL-PJT138K,SMLF,IC,BAM138K0003',
 PART_NUMBER='BAM138K0003',
 VALUE='PJT138K',
 PRIM_FILE='./archive_libs/logical/mosfet_nch_dual/chips/chips.prt';

SECTION_NUMBER 2
 '@T6G_MB_LIB.T6G(SCH_1):PAGE333_I159@PURE_QUANTA.MOSFET_NCH_DUAL(CHIPS)':
 C_PATH='@t6g_mb_lib.t6g(sch_1):page333_i159@pure_quanta.mosfet_nch_dual(chips)',
 P_PATH='@t6g_mb_lib.t6g(sch_1):page127_i159@pure_quanta.mosfet_nch_dual(chips)',
 PATH='I159',
 DRAWING='@T6G_MB_LIB.T6G(SCH_1):PAGE333',
 PART_TYPE='SMLF',
 MATERIAL='IC',
 PHYS_PAGE='127',
 XY='(1950,3500)',
 ROT='0',
 VER='2',
 LOCATION='Q96',
 CDS_LIB='pure_quanta',
 CDS_PART_NAME='MOSFET_NCH_DUAL-PJT138K,SMLF,IC,BAM138K0003',
 PART_NUMBER='BAM138K0003',
 VALUE='PJT138K',
 PRIM_FILE='./archive_libs/logical/mosfet_nch_dual/chips/chips.prt';

PART_NAME
 Q101 'MOSFET_NCH_DUAL-PJT138K,SMLF,IC,BAM138K0003':;

SECTION_NUMBER 1
 '@T6G_MB_LIB.T6G(SCH_1):PAGE299_I52@PURE_QUANTA.MOSFET_NCH_DUAL(CHIPS)':
 C_PATH='@t6g_mb_lib.t6g(sch_1):page299_i52@pure_quanta.mosfet_nch_dual(chips)',
 P_PATH='@t6g_mb_lib.t6g(sch_1):page126_i52@pure_quanta.mosfet_nch_dual(chips)',
 PATH='I52',
 DRAWING='@T6G_MB_LIB.T6G(SCH_1):PAGE299',
 PART_TYPE='SMLF',
 MATERIAL='IC',
 PHYS_PAGE='126',
 XY='(-1875,3775)',
 ROT='0',
 VER='1',
 LOCATION='Q101',
 CDS_LIB='pure_quanta',
 CDS_PART_NAME='MOSFET_NCH_DUAL-PJT138K,SMLF,IC,BAM138K0003',
 PART_NUMBER='BAM138K0003',
 VALUE='PJT138K',
 PRIM_FILE='./archive_libs/logical/mosfet_nch_dual/chips/chips.prt';

SECTION_NUMBER 2
 '@T6G_MB_LIB.T6G(SCH_1):PAGE299_I57@PURE_QUANTA.MOSFET_NCH_DUAL(CHIPS)':
 C_PATH='@t6g_mb_lib.t6g(sch_1):page299_i57@pure_quanta.mosfet_nch_dual(chips)',
 P_PATH='@t6g_mb_lib.t6g(sch_1):page126_i57@pure_quanta.mosfet_nch_dual(chips)',
 PATH='I57',
 DRAWING='@T6G_MB_LIB.T6G(SCH_1):PAGE299',
 PART_TYPE='SMLF',
 MATERIAL='IC',
 PHYS_PAGE='126',
 XY='(-725,4075)',
 ROT='0',
 VER='2',
 LOCATION='Q101',
 CDS_LIB='pure_quanta',
 CDS_PART_NAME='MOSFET_NCH_DUAL-PJT138K,SMLF,IC,BAM138K0003',
 PART_NUMBER='BAM138K0003',
 VALUE='PJT138K',
 PRIM_FILE='./archive_libs/logical/mosfet_nch_dual/chips/chips.prt';

PART_NAME
 Q102 'MOSFET_NCH_DUAL-PJT138K,SMLF,IC,BAM138K0003':;

SECTION_NUMBER 1
 '@T6G_MB_LIB.T6G(SCH_1):PAGE299_I40@PURE_QUANTA.MOSFET_NCH_DUAL(CHIPS)':
 C_PATH='@t6g_mb_lib.t6g(sch_1):page299_i40@pure_quanta.mosfet_nch_dual(chips)',
 P_PATH='@t6g_mb_lib.t6g(sch_1):page126_i40@pure_quanta.mosfet_nch_dual(chips)',
 PATH='I40',
 DRAWING='@T6G_MB_LIB.T6G(SCH_1):PAGE299',
 PART_TYPE='SMLF',
 MATERIAL='IC',
 PHYS_PAGE='126',
 XY='(-1800,2375)',
 ROT='0',
 VER='1',
 LOCATION='Q102',
 CDS_LIB='pure_quanta',
 CDS_PART_NAME='MOSFET_NCH_DUAL-PJT138K,SMLF,IC,BAM138K0003',
 PART_NUMBER='BAM138K0003',
 VALUE='PJT138K',
 PRIM_FILE='./archive_libs/logical/mosfet_nch_dual/chips/chips.prt';

SECTION_NUMBER 2
 '@T6G_MB_LIB.T6G(SCH_1):PAGE299_I48@PURE_QUANTA.MOSFET_NCH_DUAL(CHIPS)':
 C_PATH='@t6g_mb_lib.t6g(sch_1):page299_i48@pure_quanta.mosfet_nch_dual(chips)',
 P_PATH='@t6g_mb_lib.t6g(sch_1):page126_i48@pure_quanta.mosfet_nch_dual(chips)',
 PATH='I48',
 DRAWING='@T6G_MB_LIB.T6G(SCH_1):PAGE299',
 PART_TYPE='SMLF',
 MATERIAL='IC',
 PHYS_PAGE='126',
 XY='(-825,2675)',
 ROT='0',
 VER='2',
 LOCATION='Q102',
 CDS_LIB='pure_quanta',
 CDS_PART_NAME='MOSFET_NCH_DUAL-PJT138K,SMLF,IC,BAM138K0003',
 PART_NUMBER='BAM138K0003',
 VALUE='PJT138K',
 PRIM_FILE='./archive_libs/logical/mosfet_nch_dual/chips/chips.prt';

PART_NAME
 Q103 'MOSFET_NCH_DUAL-PJT138K,SMLF,IC,BAM138K0003':;

SECTION_NUMBER 1
 '@T6G_MB_LIB.T6G(SCH_1):PAGE299_I37@PURE_QUANTA.MOSFET_NCH_DUAL(CHIPS)':
 C_PATH='@t6g_mb_lib.t6g(sch_1):page299_i37@pure_quanta.mosfet_nch_dual(chips)',
 P_PATH='@t6g_mb_lib.t6g(sch_1):page126_i37@pure_quanta.mosfet_nch_dual(chips)',
 PATH='I37',
 DRAWING='@T6G_MB_LIB.T6G(SCH_1):PAGE299',
 PART_TYPE='SMLF',
 MATERIAL='IC',
 PHYS_PAGE='126',
 XY='(-1800,1025)',
 ROT='0',
 VER='1',
 LOCATION='Q103',
 CDS_LIB='pure_quanta',
 CDS_PART_NAME='MOSFET_NCH_DUAL-PJT138K,SMLF,IC,BAM138K0003',
 PART_NUMBER='BAM138K0003',
 VALUE='PJT138K',
 PRIM_FILE='./archive_libs/logical/mosfet_nch_dual/chips/chips.prt';

SECTION_NUMBER 2
 '@T6G_MB_LIB.T6G(SCH_1):PAGE299_I43@PURE_QUANTA.MOSFET_NCH_DUAL(CHIPS)':
 C_PATH='@t6g_mb_lib.t6g(sch_1):page299_i43@pure_quanta.mosfet_nch_dual(chips)',
 P_PATH='@t6g_mb_lib.t6g(sch_1):page126_i43@pure_quanta.mosfet_nch_dual(chips)',
 PATH='I43',
 DRAWING='@T6G_MB_LIB.T6G(SCH_1):PAGE299',
 PART_TYPE='SMLF',
 MATERIAL='IC',
 PHYS_PAGE='126',
 XY='(-850,1300)',
 ROT='0',
 VER='2',
 LOCATION='Q103',
 CDS_LIB='pure_quanta',
 CDS_PART_NAME='MOSFET_NCH_DUAL-PJT138K,SMLF,IC,BAM138K0003',
 PART_NUMBER='BAM138K0003',
 VALUE='PJT138K',
 PRIM_FILE='./archive_libs/logical/mosfet_nch_dual/chips/chips.prt';

PART_NAME
 Q104 'MOSFET_NCH_DUAL-PJT138K,SMLF,IC,BAM138K0003':;

SECTION_NUMBER 1
 '@T6G_MB_LIB.T6G(SCH_1):PAGE299_I21@PURE_QUANTA.MOSFET_NCH_DUAL(CHIPS)':
 C_PATH='@t6g_mb_lib.t6g(sch_1):page299_i21@pure_quanta.mosfet_nch_dual(chips)',
 P_PATH='@t6g_mb_lib.t6g(sch_1):page126_i21@pure_quanta.mosfet_nch_dual(chips)',
 PATH='I21',
 DRAWING='@T6G_MB_LIB.T6G(SCH_1):PAGE299',
 PART_TYPE='SMLF',
 MATERIAL='IC',
 PHYS_PAGE='126',
 XY='(-1775,-550)',
 ROT='0',
 VER='1',
 LOCATION='Q104',
 CDS_LIB='pure_quanta',
 CDS_PART_NAME='MOSFET_NCH_DUAL-PJT138K,SMLF,IC,BAM138K0003',
 PART_NUMBER='BAM138K0003',
 VALUE='PJT138K',
 PRIM_FILE='./archive_libs/logical/mosfet_nch_dual/chips/chips.prt';

SECTION_NUMBER 2
 '@T6G_MB_LIB.T6G(SCH_1):PAGE299_I26@PURE_QUANTA.MOSFET_NCH_DUAL(CHIPS)':
 C_PATH='@t6g_mb_lib.t6g(sch_1):page299_i26@pure_quanta.mosfet_nch_dual(chips)',
 P_PATH='@t6g_mb_lib.t6g(sch_1):page126_i26@pure_quanta.mosfet_nch_dual(chips)',
 PATH='I26',
 DRAWING='@T6G_MB_LIB.T6G(SCH_1):PAGE299',
 PART_TYPE='SMLF',
 MATERIAL='IC',
 PHYS_PAGE='126',
 XY='(-850,-275)',
 ROT='0',
 VER='2',
 LOCATION='Q104',
 CDS_LIB='pure_quanta',
 CDS_PART_NAME='MOSFET_NCH_DUAL-PJT138K,SMLF,IC,BAM138K0003',
 PART_NUMBER='BAM138K0003',
 VALUE='PJT138K',
 PRIM_FILE='./archive_libs/logical/mosfet_nch_dual/chips/chips.prt';

PART_NAME
 Q106 'MOSFET_NCH_DUAL-PJT138K,SMLF,IC,BAM138K0003':;

SECTION_NUMBER 1
 '@T6G_MB_LIB.T6G(SCH_1):PAGE299_I201@PURE_QUANTA.MOSFET_NCH_DUAL(CHIPS)':
 C_PATH='@t6g_mb_lib.t6g(sch_1):page299_i201@pure_quanta.mosfet_nch_dual(chips)',
 P_PATH='@t6g_mb_lib.t6g(sch_1):page126_i201@pure_quanta.mosfet_nch_dual(chips)',
 PATH='I201',
 DRAWING='@T6G_MB_LIB.T6G(SCH_1):PAGE299',
 PART_TYPE='SMLF',
 MATERIAL='IC',
 PHYS_PAGE='126',
 XY='(2700,3375)',
 ROT='0',
 VER='1',
 LOCATION='Q106',
 CDS_LIB='pure_quanta',
 CDS_PART_NAME='MOSFET_NCH_DUAL-PJT138K,SMLF,IC,BAM138K0003',
 PART_NUMBER='BAM138K0003',
 VALUE='PJT138K',
 PRIM_FILE='./archive_libs/logical/mosfet_nch_dual/chips/chips.prt';

SECTION_NUMBER 2
 '@T6G_MB_LIB.T6G(SCH_1):PAGE299_I200@PURE_QUANTA.MOSFET_NCH_DUAL(CHIPS)':
 C_PATH='@t6g_mb_lib.t6g(sch_1):page299_i200@pure_quanta.mosfet_nch_dual(chips)',
 P_PATH='@t6g_mb_lib.t6g(sch_1):page126_i200@pure_quanta.mosfet_nch_dual(chips)',
 PATH='I200',
 DRAWING='@T6G_MB_LIB.T6G(SCH_1):PAGE299',
 PART_TYPE='SMLF',
 MATERIAL='IC',
 PHYS_PAGE='126',
 XY='(3675,3675)',
 ROT='0',
 VER='2',
 LOCATION='Q106',
 CDS_LIB='pure_quanta',
 CDS_PART_NAME='MOSFET_NCH_DUAL-PJT138K,SMLF,IC,BAM138K0003',
 PART_NUMBER='BAM138K0003',
 VALUE='PJT138K',
 PRIM_FILE='./archive_libs/logical/mosfet_nch_dual/chips/chips.prt';

PART_NAME
 Q107 'MOSFET_NCH_DUAL-PJT138K,SMLF,IC,BAM138K0003':;

SECTION_NUMBER 1
 '@T6G_MB_LIB.T6G(SCH_1):PAGE299_I160@PURE_QUANTA.MOSFET_NCH_DUAL(CHIPS)':
 C_PATH='@t6g_mb_lib.t6g(sch_1):page299_i160@pure_quanta.mosfet_nch_dual(chips)',
 P_PATH='@t6g_mb_lib.t6g(sch_1):page126_i160@pure_quanta.mosfet_nch_dual(chips)',
 PATH='I160',
 DRAWING='@T6G_MB_LIB.T6G(SCH_1):PAGE299',
 PART_TYPE='SMLF',
 MATERIAL='IC',
 PHYS_PAGE='126',
 XY='(2900,1450)',
 ROT='0',
 VER='1',
 LOCATION='Q107',
 CDS_LIB='pure_quanta',
 CDS_PART_NAME='MOSFET_NCH_DUAL-PJT138K,SMLF,IC,BAM138K0003',
 PART_NUMBER='BAM138K0003',
 VALUE='PJT138K',
 PRIM_FILE='./archive_libs/logical/mosfet_nch_dual/chips/chips.prt';

SECTION_NUMBER 2
 '@T6G_MB_LIB.T6G(SCH_1):PAGE299_I157@PURE_QUANTA.MOSFET_NCH_DUAL(CHIPS)':
 C_PATH='@t6g_mb_lib.t6g(sch_1):page299_i157@pure_quanta.mosfet_nch_dual(chips)',
 P_PATH='@t6g_mb_lib.t6g(sch_1):page126_i157@pure_quanta.mosfet_nch_dual(chips)',
 PATH='I157',
 DRAWING='@T6G_MB_LIB.T6G(SCH_1):PAGE299',
 PART_TYPE='SMLF',
 MATERIAL='IC',
 PHYS_PAGE='126',
 XY='(3825,1725)',
 ROT='0',
 VER='2',
 LOCATION='Q107',
 CDS_LIB='pure_quanta',
 CDS_PART_NAME='MOSFET_NCH_DUAL-PJT138K,SMLF,IC,BAM138K0003',
 PART_NUMBER='BAM138K0003',
 VALUE='PJT138K',
 PRIM_FILE='./archive_libs/logical/mosfet_nch_dual/chips/chips.prt';

PART_NAME
 Q108 'MOSFET_NCH_DUAL-PJT138K,SMLF,IC,BAM138K0003':;

SECTION_NUMBER 1
 '@T6G_MB_LIB.T6G(SCH_1):PAGE299_I169@PURE_QUANTA.MOSFET_NCH_DUAL(CHIPS)':
 C_PATH='@t6g_mb_lib.t6g(sch_1):page299_i169@pure_quanta.mosfet_nch_dual(chips)',
 P_PATH='@t6g_mb_lib.t6g(sch_1):page126_i169@pure_quanta.mosfet_nch_dual(chips)',
 PATH='I169',
 DRAWING='@T6G_MB_LIB.T6G(SCH_1):PAGE299',
 PART_TYPE='SMLF',
 MATERIAL='IC',
 PHYS_PAGE='126',
 XY='(2925,-275)',
 ROT='0',
 VER='1',
 LOCATION='Q108',
 CDS_LIB='pure_quanta',
 CDS_PART_NAME='MOSFET_NCH_DUAL-PJT138K,SMLF,IC,BAM138K0003',
 PART_NUMBER='BAM138K0003',
 VALUE='PJT138K',
 PRIM_FILE='./archive_libs/logical/mosfet_nch_dual/chips/chips.prt';

SECTION_NUMBER 2
 '@T6G_MB_LIB.T6G(SCH_1):PAGE299_I168@PURE_QUANTA.MOSFET_NCH_DUAL(CHIPS)':
 C_PATH='@t6g_mb_lib.t6g(sch_1):page299_i168@pure_quanta.mosfet_nch_dual(chips)',
 P_PATH='@t6g_mb_lib.t6g(sch_1):page126_i168@pure_quanta.mosfet_nch_dual(chips)',
 PATH='I168',
 DRAWING='@T6G_MB_LIB.T6G(SCH_1):PAGE299',
 PART_TYPE='SMLF',
 MATERIAL='IC',
 PHYS_PAGE='126',
 XY='(3850,0)',
 ROT='0',
 VER='2',
 LOCATION='Q108',
 CDS_LIB='pure_quanta',
 CDS_PART_NAME='MOSFET_NCH_DUAL-PJT138K,SMLF,IC,BAM138K0003',
 PART_NUMBER='BAM138K0003',
 VALUE='PJT138K',
 PRIM_FILE='./archive_libs/logical/mosfet_nch_dual/chips/chips.prt';

PART_NAME
 Q118 'MOSFET_NCH_DUAL-PJT138K,SMLF,IC,BAM138K0003':
 ROOM='NIC_P12V_MAM_TIC_BOM1';

SECTION_NUMBER 1
 '@T6G_MB_LIB.T6G(SCH_1):PAGE343_I10@PURE_QUANTA.MOSFET_NCH_DUAL(CHIPS)':
 C_PATH='@t6g_mb_lib.t6g(sch_1):page343_i10@pure_quanta.mosfet_nch_dual(chips)',
 P_PATH='@t6g_mb_lib.t6g(sch_1):page140_i10@pure_quanta.mosfet_nch_dual(chips)',
 PATH='I10',
 DRAWING='@T6G_MB_LIB.T6G(SCH_1):PAGE343',
 PART_TYPE='SMLF',
 MATERIAL='IC',
 PHYS_PAGE='140',
 XY='(-2800,5875)',
 ROT='0',
 VER='1',
 LOCATION='Q118',
 CDS_LIB='pure_quanta',
 CDS_PART_NAME='MOSFET_NCH_DUAL-PJT138K,SMLF,IC,BAM138K0003',
 ROOM='NIC_P12V_MAM_TIC_BOM1',
 PART_NUMBER='BAM138K0003',
 VALUE='PJT138K',
 PRIM_FILE='./archive_libs/logical/mosfet_nch_dual/chips/chips.prt';

SECTION_NUMBER 2
 '@T6G_MB_LIB.T6G(SCH_1):PAGE343_I19@PURE_QUANTA.MOSFET_NCH_DUAL(CHIPS)':
 C_PATH='@t6g_mb_lib.t6g(sch_1):page343_i19@pure_quanta.mosfet_nch_dual(chips)',
 P_PATH='@t6g_mb_lib.t6g(sch_1):page140_i19@pure_quanta.mosfet_nch_dual(chips)',
 PATH='I19',
 DRAWING='@T6G_MB_LIB.T6G(SCH_1):PAGE343',
 PART_TYPE='SMLF',
 MATERIAL='IC',
 PHYS_PAGE='140',
 XY='(-1775,6200)',
 ROT='0',
 VER='2',
 LOCATION='Q118',
 CDS_LIB='pure_quanta',
 CDS_PART_NAME='MOSFET_NCH_DUAL-PJT138K,SMLF,IC,BAM138K0003',
 ROOM='NIC_P12V_MAM_TIC_BOM1',
 PART_NUMBER='BAM138K0003',
 VALUE='PJT138K',
 PRIM_FILE='./archive_libs/logical/mosfet_nch_dual/chips/chips.prt';

PART_NAME
 Q119 'MOSFET_NCH_DUAL-PJT138K,SMLF,IC,BAM138K0003':
 ROOM='NIC_P3V3_BOM1';

SECTION_NUMBER 1
 '@T6G_MB_LIB.T6G(SCH_1):PAGE343_I42@PURE_QUANTA.MOSFET_NCH_DUAL(CHIPS)':
 C_PATH='@t6g_mb_lib.t6g(sch_1):page343_i42@pure_quanta.mosfet_nch_dual(chips)',
 P_PATH='@t6g_mb_lib.t6g(sch_1):page140_i42@pure_quanta.mosfet_nch_dual(chips)',
 PATH='I42',
 DRAWING='@T6G_MB_LIB.T6G(SCH_1):PAGE343',
 PART_TYPE='SMLF',
 MATERIAL='IC',
 PHYS_PAGE='140',
 XY='(-2275,7875)',
 ROT='0',
 VER='1',
 LOCATION='Q119',
 CDS_LIB='pure_quanta',
 CDS_PART_NAME='MOSFET_NCH_DUAL-PJT138K,SMLF,IC,BAM138K0003',
 ROOM='NIC_P3V3_BOM1',
 PART_NUMBER='BAM138K0003',
 VALUE='PJT138K',
 PRIM_FILE='./archive_libs/logical/mosfet_nch_dual/chips/chips.prt';

SECTION_NUMBER 2
 '@T6G_MB_LIB.T6G(SCH_1):PAGE343_I45@PURE_QUANTA.MOSFET_NCH_DUAL(CHIPS)':
 C_PATH='@t6g_mb_lib.t6g(sch_1):page343_i45@pure_quanta.mosfet_nch_dual(chips)',
 P_PATH='@t6g_mb_lib.t6g(sch_1):page140_i45@pure_quanta.mosfet_nch_dual(chips)',
 PATH='I45',
 DRAWING='@T6G_MB_LIB.T6G(SCH_1):PAGE343',
 PART_TYPE='SMLF',
 MATERIAL='IC',
 PHYS_PAGE='140',
 XY='(-1575,8250)',
 ROT='0',
 VER='2',
 LOCATION='Q119',
 CDS_LIB='pure_quanta',
 CDS_PART_NAME='MOSFET_NCH_DUAL-PJT138K,SMLF,IC,BAM138K0003',
 ROOM='NIC_P3V3_BOM1',
 PART_NUMBER='BAM138K0003',
 VALUE='PJT138K',
 PRIM_FILE='./archive_libs/logical/mosfet_nch_dual/chips/chips.prt';

PART_NAME
 Q123 'MOSFET_NCH_DUAL-PJT138K,SMLF,IC,BAM138K0003':
 ROOM='NIC_P12V_MAM_TIC_BOM1';

SECTION_NUMBER 1
 '@T6G_MB_LIB.T6G(SCH_1):PAGE338_I11@PURE_QUANTA.MOSFET_NCH_DUAL(CHIPS)':
 C_PATH='@t6g_mb_lib.t6g(sch_1):page338_i11@pure_quanta.mosfet_nch_dual(chips)',
 P_PATH='@t6g_mb_lib.t6g(sch_1):page134_i11@pure_quanta.mosfet_nch_dual(chips)',
 PATH='I11',
 DRAWING='@T6G_MB_LIB.T6G(SCH_1):PAGE338',
 PART_TYPE='SMLF',
 MATERIAL='IC',
 PHYS_PAGE='134',
 XY='(3575,10275)',
 ROT='0',
 VER='1',
 LOCATION='Q123',
 CDS_LIB='pure_quanta',
 CDS_PART_NAME='MOSFET_NCH_DUAL-PJT138K,SMLF,IC,BAM138K0003',
 ROOM='NIC_P12V_MAM_TIC_BOM1',
 PART_NUMBER='BAM138K0003',
 VALUE='PJT138K',
 PRIM_FILE='./archive_libs/logical/mosfet_nch_dual/chips/chips.prt';

SECTION_NUMBER 2
 '@T6G_MB_LIB.T6G(SCH_1):PAGE338_I19@PURE_QUANTA.MOSFET_NCH_DUAL(CHIPS)':
 C_PATH='@t6g_mb_lib.t6g(sch_1):page338_i19@pure_quanta.mosfet_nch_dual(chips)',
 P_PATH='@t6g_mb_lib.t6g(sch_1):page134_i19@pure_quanta.mosfet_nch_dual(chips)',
 PATH='I19',
 DRAWING='@T6G_MB_LIB.T6G(SCH_1):PAGE338',
 PART_TYPE='SMLF',
 MATERIAL='IC',
 PHYS_PAGE='134',
 XY='(4425,10575)',
 ROT='0',
 VER='2',
 LOCATION='Q123',
 CDS_LIB='pure_quanta',
 CDS_PART_NAME='MOSFET_NCH_DUAL-PJT138K,SMLF,IC,BAM138K0003',
 ROOM='NIC_P12V_MAM_TIC_BOM1',
 PART_NUMBER='BAM138K0003',
 VALUE='PJT138K',
 PRIM_FILE='./archive_libs/logical/mosfet_nch_dual/chips/chips.prt';

PART_NAME
 Q124 'MOSFET_NCH_DUAL-PJT138K,SMLF,IC,BAM138K0003':
 ROOM='NIC_P3V3_BOM1';

SECTION_NUMBER 1
 '@T6G_MB_LIB.T6G(SCH_1):PAGE338_I23@PURE_QUANTA.MOSFET_NCH_DUAL(CHIPS)':
 C_PATH='@t6g_mb_lib.t6g(sch_1):page338_i23@pure_quanta.mosfet_nch_dual(chips)',
 P_PATH='@t6g_mb_lib.t6g(sch_1):page134_i23@pure_quanta.mosfet_nch_dual(chips)',
 PATH='I23',
 DRAWING='@T6G_MB_LIB.T6G(SCH_1):PAGE338',
 PART_TYPE='SMLF',
 MATERIAL='IC',
 PHYS_PAGE='134',
 XY='(4175,11875)',
 ROT='0',
 VER='1',
 LOCATION='Q124',
 CDS_LIB='pure_quanta',
 CDS_PART_NAME='MOSFET_NCH_DUAL-PJT138K,SMLF,IC,BAM138K0003',
 ROOM='NIC_P3V3_BOM1',
 PART_NUMBER='BAM138K0003',
 VALUE='PJT138K',
 PRIM_FILE='./archive_libs/logical/mosfet_nch_dual/chips/chips.prt';

SECTION_NUMBER 2
 '@T6G_MB_LIB.T6G(SCH_1):PAGE338_I112@PURE_QUANTA.MOSFET_NCH_DUAL(CHIPS)':
 C_PATH='@t6g_mb_lib.t6g(sch_1):page338_i112@pure_quanta.mosfet_nch_dual(chips)',
 P_PATH='@t6g_mb_lib.t6g(sch_1):page134_i112@pure_quanta.mosfet_nch_dual(chips)',
 PATH='I112',
 DRAWING='@T6G_MB_LIB.T6G(SCH_1):PAGE338',
 PART_TYPE='SMLF',
 MATERIAL='IC',
 PHYS_PAGE='134',
 XY='(4925,12250)',
 ROT='0',
 VER='2',
 LOCATION='Q124',
 CDS_LIB='pure_quanta',
 CDS_PART_NAME='MOSFET_NCH_DUAL-PJT138K,SMLF,IC,BAM138K0003',
 ROOM='NIC_P3V3_BOM1',
 PART_NUMBER='BAM138K0003',
 VALUE='PJT138K',
 PRIM_FILE='./archive_libs/logical/mosfet_nch_dual/chips/chips.prt';

PART_NAME
 Q125 'MOSFET_NCH_DUAL-PJT138K,SMLF,IC,BAM138K0003':
 ROOM='SCM_P12V_MAM_BOM1';

SECTION_NUMBER 1
 '@T6G_MB_LIB.T6G(SCH_1):PAGE350_I22@PURE_QUANTA.MOSFET_NCH_DUAL(CHIPS)':
 C_PATH='@t6g_mb_lib.t6g(sch_1):page350_i22@pure_quanta.mosfet_nch_dual(chips)',
 P_PATH='@t6g_mb_lib.t6g(sch_1):page152_i22@pure_quanta.mosfet_nch_dual(chips)',
 PATH='I22',
 DRAWING='@T6G_MB_LIB.T6G(SCH_1):PAGE350',
 PART_TYPE='SMLF',
 MATERIAL='IC',
 PHYS_PAGE='152',
 XY='(-1175,14325)',
 ROT='0',
 VER='1',
 LOCATION='Q125',
 CDS_LIB='pure_quanta',
 CDS_PART_NAME='MOSFET_NCH_DUAL-PJT138K,SMLF,IC,BAM138K0003',
 ROOM='SCM_P12V_MAM_BOM1',
 PART_NUMBER='BAM138K0003',
 VALUE='PJT138K',
 PRIM_FILE='./archive_libs/logical/mosfet_nch_dual/chips/chips.prt';

SECTION_NUMBER 2
 '@T6G_MB_LIB.T6G(SCH_1):PAGE350_I24@PURE_QUANTA.MOSFET_NCH_DUAL(CHIPS)':
 C_PATH='@t6g_mb_lib.t6g(sch_1):page350_i24@pure_quanta.mosfet_nch_dual(chips)',
 P_PATH='@t6g_mb_lib.t6g(sch_1):page152_i24@pure_quanta.mosfet_nch_dual(chips)',
 PATH='I24',
 DRAWING='@T6G_MB_LIB.T6G(SCH_1):PAGE350',
 PART_TYPE='SMLF',
 MATERIAL='IC',
 PHYS_PAGE='152',
 XY='(-500,14675)',
 ROT='0',
 VER='2',
 LOCATION='Q125',
 CDS_LIB='pure_quanta',
 CDS_PART_NAME='MOSFET_NCH_DUAL-PJT138K,SMLF,IC,BAM138K0003',
 ROOM='SCM_P12V_MAM_BOM1',
 PART_NUMBER='BAM138K0003',
 VALUE='PJT138K',
 PRIM_FILE='./archive_libs/logical/mosfet_nch_dual/chips/chips.prt';

PART_NAME
 Q126 'MOSFET_NCH_DUAL-PJT138K,SMLF,IC,BAM138K0003':
 ROOM='E1S_P3V3_BOM1';

SECTION_NUMBER 1
 '@T6G_MB_LIB.T6G(SCH_1):PAGE324_I6@PURE_QUANTA.MOSFET_NCH_DUAL(CHIPS)':
 C_PATH='@t6g_mb_lib.t6g(sch_1):page324_i6@pure_quanta.mosfet_nch_dual(chips)',
 P_PATH='@t6g_mb_lib.t6g(sch_1):page146_i6@pure_quanta.mosfet_nch_dual(chips)',
 PATH='I6',
 DRAWING='@T6G_MB_LIB.T6G(SCH_1):PAGE324',
 PART_TYPE='SMLF',
 MATERIAL='IC',
 PHYS_PAGE='146',
 XY='(-2775,-2600)',
 ROT='0',
 VER='1',
 LOCATION='Q126',
 CDS_LIB='pure_quanta',
 CDS_PART_NAME='MOSFET_NCH_DUAL-PJT138K,SMLF,IC,BAM138K0003',
 ROOM='E1S_P3V3_BOM1',
 PART_NUMBER='BAM138K0003',
 VALUE='PJT138K',
 PRIM_FILE='./archive_libs/logical/mosfet_nch_dual/chips/chips.prt';

SECTION_NUMBER 2
 '@T6G_MB_LIB.T6G(SCH_1):PAGE324_I7@PURE_QUANTA.MOSFET_NCH_DUAL(CHIPS)':
 C_PATH='@t6g_mb_lib.t6g(sch_1):page324_i7@pure_quanta.mosfet_nch_dual(chips)',
 P_PATH='@t6g_mb_lib.t6g(sch_1):page146_i7@pure_quanta.mosfet_nch_dual(chips)',
 PATH='I7',
 DRAWING='@T6G_MB_LIB.T6G(SCH_1):PAGE324',
 PART_TYPE='SMLF',
 MATERIAL='IC',
 PHYS_PAGE='146',
 XY='(-2100,-2275)',
 ROT='0',
 VER='2',
 LOCATION='Q126',
 CDS_LIB='pure_quanta',
 CDS_PART_NAME='MOSFET_NCH_DUAL-PJT138K,SMLF,IC,BAM138K0003',
 ROOM='E1S_P3V3_BOM1',
 PART_NUMBER='BAM138K0003',
 VALUE='PJT138K',
 PRIM_FILE='./archive_libs/logical/mosfet_nch_dual/chips/chips.prt';

PART_NAME
 Q127 'MOSFET_NCH_DUAL-PJT138K,SMLF,IC,BAM138K0003':
 ROOM='E1S_P12V_MAM_TIC_BOM1';

SECTION_NUMBER 1
 '@T6G_MB_LIB.T6G(SCH_1):PAGE324_I12@PURE_QUANTA.MOSFET_NCH_DUAL(CHIPS)':
 C_PATH='@t6g_mb_lib.t6g(sch_1):page324_i12@pure_quanta.mosfet_nch_dual(chips)',
 P_PATH='@t6g_mb_lib.t6g(sch_1):page146_i12@pure_quanta.mosfet_nch_dual(chips)',
 PATH='I12',
 DRAWING='@T6G_MB_LIB.T6G(SCH_1):PAGE324',
 PART_TYPE='SMLF',
 MATERIAL='IC',
 PHYS_PAGE='146',
 XY='(-2550,-100)',
 ROT='0',
 VER='1',
 LOCATION='Q127',
 CDS_LIB='pure_quanta',
 CDS_PART_NAME='MOSFET_NCH_DUAL-PJT138K,SMLF,IC,BAM138K0003',
 ROOM='E1S_P12V_MAM_TIC_BOM1',
 PART_NUMBER='BAM138K0003',
 VALUE='PJT138K',
 PRIM_FILE='./archive_libs/logical/mosfet_nch_dual/chips/chips.prt';

SECTION_NUMBER 2
 '@T6G_MB_LIB.T6G(SCH_1):PAGE324_I27@PURE_QUANTA.MOSFET_NCH_DUAL(CHIPS)':
 C_PATH='@t6g_mb_lib.t6g(sch_1):page324_i27@pure_quanta.mosfet_nch_dual(chips)',
 P_PATH='@t6g_mb_lib.t6g(sch_1):page146_i27@pure_quanta.mosfet_nch_dual(chips)',
 PATH='I27',
 DRAWING='@T6G_MB_LIB.T6G(SCH_1):PAGE324',
 PART_TYPE='SMLF',
 MATERIAL='IC',
 PHYS_PAGE='146',
 XY='(-1850,275)',
 ROT='0',
 VER='2',
 LOCATION='Q127',
 CDS_LIB='pure_quanta',
 CDS_PART_NAME='MOSFET_NCH_DUAL-PJT138K,SMLF,IC,BAM138K0003',
 ROOM='E1S_P12V_MAM_TIC_BOM1',
 PART_NUMBER='BAM138K0003',
 VALUE='PJT138K',
 PRIM_FILE='./archive_libs/logical/mosfet_nch_dual/chips/chips.prt';

PART_NAME
 Q128 'MOSFET_NCH_DUAL-PJT138K,SMLF,IC,BAM138K0003':;

SECTION_NUMBER 1
 '@T6G_MB_LIB.T6G(SCH_1):PAGE332_I37@PURE_QUANTA.MOSFET_NCH_DUAL(CHIPS)':
 C_PATH='@t6g_mb_lib.t6g(sch_1):page332_i37@pure_quanta.mosfet_nch_dual(chips)',
 P_PATH='@t6g_mb_lib.t6g(sch_1):page125_i37@pure_quanta.mosfet_nch_dual(chips)',
 PATH='I37',
 DRAWING='@T6G_MB_LIB.T6G(SCH_1):PAGE332',
 PART_TYPE='SMLF',
 MATERIAL='IC',
 PHYS_PAGE='125',
 XY='(-1025,3425)',
 ROT='0',
 VER='1',
 LOCATION='Q128',
 CDS_LIB='pure_quanta',
 CDS_PART_NAME='MOSFET_NCH_DUAL-PJT138K,SMLF,IC,BAM138K0003',
 PART_NUMBER='BAM138K0003',
 VALUE='PJT138K',
 PRIM_FILE='./archive_libs/logical/mosfet_nch_dual/chips/chips.prt';

SECTION_NUMBER 2
 '@T6G_MB_LIB.T6G(SCH_1):PAGE332_I42@PURE_QUANTA.MOSFET_NCH_DUAL(CHIPS)':
 C_PATH='@t6g_mb_lib.t6g(sch_1):page332_i42@pure_quanta.mosfet_nch_dual(chips)',
 P_PATH='@t6g_mb_lib.t6g(sch_1):page125_i42@pure_quanta.mosfet_nch_dual(chips)',
 PATH='I42',
 DRAWING='@T6G_MB_LIB.T6G(SCH_1):PAGE332',
 PART_TYPE='SMLF',
 MATERIAL='IC',
 PHYS_PAGE='125',
 XY='(125,3725)',
 ROT='0',
 VER='2',
 LOCATION='Q128',
 CDS_LIB='pure_quanta',
 CDS_PART_NAME='MOSFET_NCH_DUAL-PJT138K,SMLF,IC,BAM138K0003',
 PART_NUMBER='BAM138K0003',
 VALUE='PJT138K',
 PRIM_FILE='./archive_libs/logical/mosfet_nch_dual/chips/chips.prt';

PART_NAME
 Q129 'MOSFET_NCH_DUAL-PJT138K,SMLF,IC,BAM138K0003':;

SECTION_NUMBER 1
 '@T6G_MB_LIB.T6G(SCH_1):PAGE332_I86@PURE_QUANTA.MOSFET_NCH_DUAL(CHIPS)':
 C_PATH='@t6g_mb_lib.t6g(sch_1):page332_i86@pure_quanta.mosfet_nch_dual(chips)',
 P_PATH='@t6g_mb_lib.t6g(sch_1):page125_i86@pure_quanta.mosfet_nch_dual(chips)',
 PATH='I86',
 DRAWING='@T6G_MB_LIB.T6G(SCH_1):PAGE332',
 PART_TYPE='SMLF',
 MATERIAL='IC',
 PHYS_PAGE='125',
 XY='(3600,900)',
 ROT='0',
 VER='1',
 LOCATION='Q129',
 CDS_LIB='pure_quanta',
 CDS_PART_NAME='MOSFET_NCH_DUAL-PJT138K,SMLF,IC,BAM138K0003',
 PART_NUMBER='BAM138K0003',
 VALUE='PJT138K',
 PRIM_FILE='./archive_libs/logical/mosfet_nch_dual/chips/chips.prt';

SECTION_NUMBER 2
 '@T6G_MB_LIB.T6G(SCH_1):PAGE332_I113@PURE_QUANTA.MOSFET_NCH_DUAL(CHIPS)':
 C_PATH='@t6g_mb_lib.t6g(sch_1):page332_i113@pure_quanta.mosfet_nch_dual(chips)',
 P_PATH='@t6g_mb_lib.t6g(sch_1):page125_i113@pure_quanta.mosfet_nch_dual(chips)',
 PATH='I113',
 DRAWING='@T6G_MB_LIB.T6G(SCH_1):PAGE332',
 PART_TYPE='SMLF',
 MATERIAL='IC',
 PHYS_PAGE='125',
 XY='(4750,1200)',
 ROT='0',
 VER='2',
 LOCATION='Q129',
 CDS_LIB='pure_quanta',
 CDS_PART_NAME='MOSFET_NCH_DUAL-PJT138K,SMLF,IC,BAM138K0003',
 PART_NUMBER='BAM138K0003',
 VALUE='PJT138K',
 PRIM_FILE='./archive_libs/logical/mosfet_nch_dual/chips/chips.prt';

PART_NAME
 Q130 'MOSFET_NCH_DUAL-PJT138K,SMLF,IC,BAM138K0003':;

SECTION_NUMBER 1
 '@T6G_MB_LIB.T6G(SCH_1):PAGE332_I102@PURE_QUANTA.MOSFET_NCH_DUAL(CHIPS)':
 C_PATH='@t6g_mb_lib.t6g(sch_1):page332_i102@pure_quanta.mosfet_nch_dual(chips)',
 P_PATH='@t6g_mb_lib.t6g(sch_1):page125_i102@pure_quanta.mosfet_nch_dual(chips)',
 PATH='I102',
 DRAWING='@T6G_MB_LIB.T6G(SCH_1):PAGE332',
 PART_TYPE='SMLF',
 MATERIAL='IC',
 PHYS_PAGE='125',
 XY='(3600,3725)',
 ROT='0',
 VER='1',
 LOCATION='Q130',
 CDS_LIB='pure_quanta',
 CDS_PART_NAME='MOSFET_NCH_DUAL-PJT138K,SMLF,IC,BAM138K0003',
 PART_NUMBER='BAM138K0003',
 VALUE='PJT138K',
 PRIM_FILE='./archive_libs/logical/mosfet_nch_dual/chips/chips.prt';

SECTION_NUMBER 2
 '@T6G_MB_LIB.T6G(SCH_1):PAGE332_I123@PURE_QUANTA.MOSFET_NCH_DUAL(CHIPS)':
 C_PATH='@t6g_mb_lib.t6g(sch_1):page332_i123@pure_quanta.mosfet_nch_dual(chips)',
 P_PATH='@t6g_mb_lib.t6g(sch_1):page125_i123@pure_quanta.mosfet_nch_dual(chips)',
 PATH='I123',
 DRAWING='@T6G_MB_LIB.T6G(SCH_1):PAGE332',
 PART_TYPE='SMLF',
 MATERIAL='IC',
 PHYS_PAGE='125',
 XY='(4750,4025)',
 ROT='0',
 VER='2',
 LOCATION='Q130',
 CDS_LIB='pure_quanta',
 CDS_PART_NAME='MOSFET_NCH_DUAL-PJT138K,SMLF,IC,BAM138K0003',
 PART_NUMBER='BAM138K0003',
 VALUE='PJT138K',
 PRIM_FILE='./archive_libs/logical/mosfet_nch_dual/chips/chips.prt';

PART_NAME
 Q131 'MOSFET_NCH_DUAL-PJT138K,SMLF,IC,BAM138K0003':;

SECTION_NUMBER 1
 '@T6G_MB_LIB.T6G(SCH_1):PAGE332_I30@PURE_QUANTA.MOSFET_NCH_DUAL(CHIPS)':
 C_PATH='@t6g_mb_lib.t6g(sch_1):page332_i30@pure_quanta.mosfet_nch_dual(chips)',
 P_PATH='@t6g_mb_lib.t6g(sch_1):page125_i30@pure_quanta.mosfet_nch_dual(chips)',
 PATH='I30',
 DRAWING='@T6G_MB_LIB.T6G(SCH_1):PAGE332',
 PART_TYPE='SMLF',
 MATERIAL='IC',
 PHYS_PAGE='125',
 XY='(-1000,2050)',
 ROT='0',
 VER='1',
 LOCATION='Q131',
 CDS_LIB='pure_quanta',
 CDS_PART_NAME='MOSFET_NCH_DUAL-PJT138K,SMLF,IC,BAM138K0003',
 PART_NUMBER='BAM138K0003',
 VALUE='PJT138K',
 PRIM_FILE='./archive_libs/logical/mosfet_nch_dual/chips/chips.prt';

SECTION_NUMBER 2
 '@T6G_MB_LIB.T6G(SCH_1):PAGE332_I40@PURE_QUANTA.MOSFET_NCH_DUAL(CHIPS)':
 C_PATH='@t6g_mb_lib.t6g(sch_1):page332_i40@pure_quanta.mosfet_nch_dual(chips)',
 P_PATH='@t6g_mb_lib.t6g(sch_1):page125_i40@pure_quanta.mosfet_nch_dual(chips)',
 PATH='I40',
 DRAWING='@T6G_MB_LIB.T6G(SCH_1):PAGE332',
 PART_TYPE='SMLF',
 MATERIAL='IC',
 PHYS_PAGE='125',
 XY='(150,2350)',
 ROT='0',
 VER='2',
 LOCATION='Q131',
 CDS_LIB='pure_quanta',
 CDS_PART_NAME='MOSFET_NCH_DUAL-PJT138K,SMLF,IC,BAM138K0003',
 PART_NUMBER='BAM138K0003',
 VALUE='PJT138K',
 PRIM_FILE='./archive_libs/logical/mosfet_nch_dual/chips/chips.prt';

PART_NAME
 Q132 'MOSFET_NCH_DUAL-PJT138K,SMLF,IC,BAM138K0003':;

SECTION_NUMBER 1
 '@T6G_MB_LIB.T6G(SCH_1):PAGE332_I25@PURE_QUANTA.MOSFET_NCH_DUAL(CHIPS)':
 C_PATH='@t6g_mb_lib.t6g(sch_1):page332_i25@pure_quanta.mosfet_nch_dual(chips)',
 P_PATH='@t6g_mb_lib.t6g(sch_1):page125_i25@pure_quanta.mosfet_nch_dual(chips)',
 PATH='I25',
 DRAWING='@T6G_MB_LIB.T6G(SCH_1):PAGE332',
 PART_TYPE='SMLF',
 MATERIAL='IC',
 PHYS_PAGE='125',
 XY='(-1025,600)',
 ROT='0',
 VER='1',
 LOCATION='Q132',
 CDS_LIB='pure_quanta',
 CDS_PART_NAME='MOSFET_NCH_DUAL-PJT138K,SMLF,IC,BAM138K0003',
 PART_NUMBER='BAM138K0003',
 VALUE='PJT138K',
 PRIM_FILE='./archive_libs/logical/mosfet_nch_dual/chips/chips.prt';

SECTION_NUMBER 2
 '@T6G_MB_LIB.T6G(SCH_1):PAGE332_I32@PURE_QUANTA.MOSFET_NCH_DUAL(CHIPS)':
 C_PATH='@t6g_mb_lib.t6g(sch_1):page332_i32@pure_quanta.mosfet_nch_dual(chips)',
 P_PATH='@t6g_mb_lib.t6g(sch_1):page125_i32@pure_quanta.mosfet_nch_dual(chips)',
 PATH='I32',
 DRAWING='@T6G_MB_LIB.T6G(SCH_1):PAGE332',
 PART_TYPE='SMLF',
 MATERIAL='IC',
 PHYS_PAGE='125',
 XY='(125,900)',
 ROT='0',
 VER='2',
 LOCATION='Q132',
 CDS_LIB='pure_quanta',
 CDS_PART_NAME='MOSFET_NCH_DUAL-PJT138K,SMLF,IC,BAM138K0003',
 PART_NUMBER='BAM138K0003',
 VALUE='PJT138K',
 PRIM_FILE='./archive_libs/logical/mosfet_nch_dual/chips/chips.prt';

PART_NAME
 Q133 'MOSFET_NCH_DUAL-PJT138K,SMLF,IC,BAM138K0003':;

SECTION_NUMBER 1
 '@T6G_MB_LIB.T6G(SCH_1):PAGE332_I98@PURE_QUANTA.MOSFET_NCH_DUAL(CHIPS)':
 C_PATH='@t6g_mb_lib.t6g(sch_1):page332_i98@pure_quanta.mosfet_nch_dual(chips)',
 P_PATH='@t6g_mb_lib.t6g(sch_1):page125_i98@pure_quanta.mosfet_nch_dual(chips)',
 PATH='I98',
 DRAWING='@T6G_MB_LIB.T6G(SCH_1):PAGE332',
 PART_TYPE='SMLF',
 MATERIAL='IC',
 PHYS_PAGE='125',
 XY='(3625,2350)',
 ROT='0',
 VER='1',
 LOCATION='Q133',
 CDS_LIB='pure_quanta',
 CDS_PART_NAME='MOSFET_NCH_DUAL-PJT138K,SMLF,IC,BAM138K0003',
 PART_NUMBER='BAM138K0003',
 VALUE='PJT138K',
 PRIM_FILE='./archive_libs/logical/mosfet_nch_dual/chips/chips.prt';

SECTION_NUMBER 2
 '@T6G_MB_LIB.T6G(SCH_1):PAGE332_I120@PURE_QUANTA.MOSFET_NCH_DUAL(CHIPS)':
 C_PATH='@t6g_mb_lib.t6g(sch_1):page332_i120@pure_quanta.mosfet_nch_dual(chips)',
 P_PATH='@t6g_mb_lib.t6g(sch_1):page125_i120@pure_quanta.mosfet_nch_dual(chips)',
 PATH='I120',
 DRAWING='@T6G_MB_LIB.T6G(SCH_1):PAGE332',
 PART_TYPE='SMLF',
 MATERIAL='IC',
 PHYS_PAGE='125',
 XY='(4775,2650)',
 ROT='0',
 VER='2',
 LOCATION='Q133',
 CDS_LIB='pure_quanta',
 CDS_PART_NAME='MOSFET_NCH_DUAL-PJT138K,SMLF,IC,BAM138K0003',
 PART_NUMBER='BAM138K0003',
 VALUE='PJT138K',
 PRIM_FILE='./archive_libs/logical/mosfet_nch_dual/chips/chips.prt';

PART_NAME
 Q134 'MOSFET_NCH_DUAL-PJT138K,SMLF,IC,BAM138K0003':;

SECTION_NUMBER 1
 '@T6G_MB_LIB.T6G(SCH_1):PAGE332_I6@PURE_QUANTA.MOSFET_NCH_DUAL(CHIPS)':
 C_PATH='@t6g_mb_lib.t6g(sch_1):page332_i6@pure_quanta.mosfet_nch_dual(chips)',
 P_PATH='@t6g_mb_lib.t6g(sch_1):page125_i6@pure_quanta.mosfet_nch_dual(chips)',
 PATH='I6',
 DRAWING='@T6G_MB_LIB.T6G(SCH_1):PAGE332',
 PART_TYPE='SMLF',
 MATERIAL='IC',
 PHYS_PAGE='125',
 XY='(-950,-950)',
 ROT='0',
 VER='1',
 LOCATION='Q134',
 CDS_LIB='pure_quanta',
 CDS_PART_NAME='MOSFET_NCH_DUAL-PJT138K,SMLF,IC,BAM138K0003',
 PART_NUMBER='BAM138K0003',
 VALUE='PJT138K',
 PRIM_FILE='./archive_libs/logical/mosfet_nch_dual/chips/chips.prt';

SECTION_NUMBER 2
 '@T6G_MB_LIB.T6G(SCH_1):PAGE332_I10@PURE_QUANTA.MOSFET_NCH_DUAL(CHIPS)':
 C_PATH='@t6g_mb_lib.t6g(sch_1):page332_i10@pure_quanta.mosfet_nch_dual(chips)',
 P_PATH='@t6g_mb_lib.t6g(sch_1):page125_i10@pure_quanta.mosfet_nch_dual(chips)',
 PATH='I10',
 DRAWING='@T6G_MB_LIB.T6G(SCH_1):PAGE332',
 PART_TYPE='SMLF',
 MATERIAL='IC',
 PHYS_PAGE='125',
 XY='(200,-650)',
 ROT='0',
 VER='2',
 LOCATION='Q134',
 CDS_LIB='pure_quanta',
 CDS_PART_NAME='MOSFET_NCH_DUAL-PJT138K,SMLF,IC,BAM138K0003',
 PART_NUMBER='BAM138K0003',
 VALUE='PJT138K',
 PRIM_FILE='./archive_libs/logical/mosfet_nch_dual/chips/chips.prt';

PART_NAME
 Q135 'MOSFET_NCH_DUAL-PJT138K,SMLF,IC,BAM138K0003':;

SECTION_NUMBER 1
 '@T6G_MB_LIB.T6G(SCH_1):PAGE331_I25@PURE_QUANTA.MOSFET_NCH_DUAL(CHIPS)':
 C_PATH='@t6g_mb_lib.t6g(sch_1):page331_i25@pure_quanta.mosfet_nch_dual(chips)',
 P_PATH='@t6g_mb_lib.t6g(sch_1):page124_i25@pure_quanta.mosfet_nch_dual(chips)',
 PATH='I25',
 DRAWING='@T6G_MB_LIB.T6G(SCH_1):PAGE331',
 PART_TYPE='SMLF',
 MATERIAL='IC',
 PHYS_PAGE='124',
 XY='(-875,4975)',
 ROT='0',
 VER='1',
 LOCATION='Q135',
 CDS_LIB='pure_quanta',
 CDS_PART_NAME='MOSFET_NCH_DUAL-PJT138K,SMLF,IC,BAM138K0003',
 PART_NUMBER='BAM138K0003',
 VALUE='PJT138K',
 PRIM_FILE='./archive_libs/logical/mosfet_nch_dual/chips/chips.prt';

SECTION_NUMBER 2
 '@T6G_MB_LIB.T6G(SCH_1):PAGE331_I29@PURE_QUANTA.MOSFET_NCH_DUAL(CHIPS)':
 C_PATH='@t6g_mb_lib.t6g(sch_1):page331_i29@pure_quanta.mosfet_nch_dual(chips)',
 P_PATH='@t6g_mb_lib.t6g(sch_1):page124_i29@pure_quanta.mosfet_nch_dual(chips)',
 PATH='I29',
 DRAWING='@T6G_MB_LIB.T6G(SCH_1):PAGE331',
 PART_TYPE='SMLF',
 MATERIAL='IC',
 PHYS_PAGE='124',
 XY='(275,5275)',
 ROT='0',
 VER='2',
 LOCATION='Q135',
 CDS_LIB='pure_quanta',
 CDS_PART_NAME='MOSFET_NCH_DUAL-PJT138K,SMLF,IC,BAM138K0003',
 PART_NUMBER='BAM138K0003',
 VALUE='PJT138K',
 PRIM_FILE='./archive_libs/logical/mosfet_nch_dual/chips/chips.prt';

PART_NAME
 Q136 'MOSFET_NCH_DUAL-PJT138K,SMLF,IC,BAM138K0003':;

SECTION_NUMBER 1
 '@T6G_MB_LIB.T6G(SCH_1):PAGE331_I17@PURE_QUANTA.MOSFET_NCH_DUAL(CHIPS)':
 C_PATH='@t6g_mb_lib.t6g(sch_1):page331_i17@pure_quanta.mosfet_nch_dual(chips)',
 P_PATH='@t6g_mb_lib.t6g(sch_1):page124_i17@pure_quanta.mosfet_nch_dual(chips)',
 PATH='I17',
 DRAWING='@T6G_MB_LIB.T6G(SCH_1):PAGE331',
 PART_TYPE='SMLF',
 MATERIAL='IC',
 PHYS_PAGE='124',
 XY='(-875,2150)',
 ROT='0',
 VER='1',
 LOCATION='Q136',
 CDS_LIB='pure_quanta',
 CDS_PART_NAME='MOSFET_NCH_DUAL-PJT138K,SMLF,IC,BAM138K0003',
 PART_NUMBER='BAM138K0003',
 VALUE='PJT138K',
 PRIM_FILE='./archive_libs/logical/mosfet_nch_dual/chips/chips.prt';

SECTION_NUMBER 2
 '@T6G_MB_LIB.T6G(SCH_1):PAGE331_I22@PURE_QUANTA.MOSFET_NCH_DUAL(CHIPS)':
 C_PATH='@t6g_mb_lib.t6g(sch_1):page331_i22@pure_quanta.mosfet_nch_dual(chips)',
 P_PATH='@t6g_mb_lib.t6g(sch_1):page124_i22@pure_quanta.mosfet_nch_dual(chips)',
 PATH='I22',
 DRAWING='@T6G_MB_LIB.T6G(SCH_1):PAGE331',
 PART_TYPE='SMLF',
 MATERIAL='IC',
 PHYS_PAGE='124',
 XY='(275,2450)',
 ROT='0',
 VER='2',
 LOCATION='Q136',
 CDS_LIB='pure_quanta',
 CDS_PART_NAME='MOSFET_NCH_DUAL-PJT138K,SMLF,IC,BAM138K0003',
 PART_NUMBER='BAM138K0003',
 VALUE='PJT138K',
 PRIM_FILE='./archive_libs/logical/mosfet_nch_dual/chips/chips.prt';

PART_NAME
 Q137 'MOSFET_NCH_DUAL-PJT138K,SMLF,IC,BAM138K0003':;

SECTION_NUMBER 1
 '@T6G_MB_LIB.T6G(SCH_1):PAGE331_I21@PURE_QUANTA.MOSFET_NCH_DUAL(CHIPS)':
 C_PATH='@t6g_mb_lib.t6g(sch_1):page331_i21@pure_quanta.mosfet_nch_dual(chips)',
 P_PATH='@t6g_mb_lib.t6g(sch_1):page124_i21@pure_quanta.mosfet_nch_dual(chips)',
 PATH='I21',
 DRAWING='@T6G_MB_LIB.T6G(SCH_1):PAGE331',
 PART_TYPE='SMLF',
 MATERIAL='IC',
 PHYS_PAGE='124',
 XY='(-850,3600)',
 ROT='0',
 VER='1',
 LOCATION='Q137',
 CDS_LIB='pure_quanta',
 CDS_PART_NAME='MOSFET_NCH_DUAL-PJT138K,SMLF,IC,BAM138K0003',
 PART_NUMBER='BAM138K0003',
 VALUE='PJT138K',
 PRIM_FILE='./archive_libs/logical/mosfet_nch_dual/chips/chips.prt';

SECTION_NUMBER 2
 '@T6G_MB_LIB.T6G(SCH_1):PAGE331_I28@PURE_QUANTA.MOSFET_NCH_DUAL(CHIPS)':
 C_PATH='@t6g_mb_lib.t6g(sch_1):page331_i28@pure_quanta.mosfet_nch_dual(chips)',
 P_PATH='@t6g_mb_lib.t6g(sch_1):page124_i28@pure_quanta.mosfet_nch_dual(chips)',
 PATH='I28',
 DRAWING='@T6G_MB_LIB.T6G(SCH_1):PAGE331',
 PART_TYPE='SMLF',
 MATERIAL='IC',
 PHYS_PAGE='124',
 XY='(300,3900)',
 ROT='0',
 VER='2',
 LOCATION='Q137',
 CDS_LIB='pure_quanta',
 CDS_PART_NAME='MOSFET_NCH_DUAL-PJT138K,SMLF,IC,BAM138K0003',
 PART_NUMBER='BAM138K0003',
 VALUE='PJT138K',
 PRIM_FILE='./archive_libs/logical/mosfet_nch_dual/chips/chips.prt';

PART_NAME
 Q144 'MOSFET_NCH_DUAL-PJT138K,SMLF,IC,BAM138K0003':;

SECTION_NUMBER 1
 '@T6G_MB_LIB.T6G(SCH_1):PAGE368_I3@PURE_QUANTA.MOSFET_NCH_DUAL(CHIPS)':
 C_PATH='@t6g_mb_lib.t6g(sch_1):page368_i3@pure_quanta.mosfet_nch_dual(chips)',
 P_PATH='@t6g_mb_lib.t6g(sch_1):page253_i3@pure_quanta.mosfet_nch_dual(chips)',
 PATH='I3',
 DRAWING='@T6G_MB_LIB.T6G(SCH_1):PAGE368',
 PART_TYPE='SMLF',
 MATERIAL='IC',
 PHYS_PAGE='253',
 XY='(-5975,3900)',
 ROT='0',
 VER='1',
 LOCATION='Q144',
 CDS_LIB='pure_quanta',
 CDS_PART_NAME='MOSFET_NCH_DUAL-PJT138K,SMLF,IC,BAM138K0003',
 PART_NUMBER='BAM138K0003',
 VALUE='PJT138K',
 PRIM_FILE='./archive_libs/logical/mosfet_nch_dual/chips/chips.prt';

SECTION_NUMBER 2
 '@T6G_MB_LIB.T6G(SCH_1):PAGE368_I10@PURE_QUANTA.MOSFET_NCH_DUAL(CHIPS)':
 C_PATH='@t6g_mb_lib.t6g(sch_1):page368_i10@pure_quanta.mosfet_nch_dual(chips)',
 P_PATH='@t6g_mb_lib.t6g(sch_1):page253_i10@pure_quanta.mosfet_nch_dual(chips)',
 PATH='I10',
 DRAWING='@T6G_MB_LIB.T6G(SCH_1):PAGE368',
 PART_TYPE='SMLF',
 MATERIAL='IC',
 PHYS_PAGE='253',
 XY='(-4825,4200)',
 ROT='0',
 VER='2',
 LOCATION='Q144',
 CDS_LIB='pure_quanta',
 CDS_PART_NAME='MOSFET_NCH_DUAL-PJT138K,SMLF,IC,BAM138K0003',
 PART_NUMBER='BAM138K0003',
 VALUE='PJT138K',
 PRIM_FILE='./archive_libs/logical/mosfet_nch_dual/chips/chips.prt';

PART_NAME
 Q145 'MOSFET_NCH_DUAL-PJT138K,SMLF,IC,BAM138K0003':;

SECTION_NUMBER 1
 '@T6G_MB_LIB.T6G(SCH_1):PAGE364_I53@PURE_QUANTA.MOSFET_NCH_DUAL(CHIPS)':
 C_PATH='@t6g_mb_lib.t6g(sch_1):page364_i53@pure_quanta.mosfet_nch_dual(chips)',
 P_PATH='@t6g_mb_lib.t6g(sch_1):page241_i53@pure_quanta.mosfet_nch_dual(chips)',
 PATH='I53',
 DRAWING='@T6G_MB_LIB.T6G(SCH_1):PAGE364',
 PART_TYPE='SMLF',
 MATERIAL='IC',
 PHYS_PAGE='241',
 XY='(0,-2025)',
 ROT='0',
 VER='1',
 LOCATION='Q145',
 CDS_LIB='pure_quanta',
 CDS_PART_NAME='MOSFET_NCH_DUAL-PJT138K,SMLF,IC,BAM138K0003',
 PART_NUMBER='BAM138K0003',
 VALUE='PJT138K',
 PRIM_FILE='./archive_libs/logical/mosfet_nch_dual/chips/chips.prt';

SECTION_NUMBER 2
 '@T6G_MB_LIB.T6G(SCH_1):PAGE364_I58@PURE_QUANTA.MOSFET_NCH_DUAL(CHIPS)':
 C_PATH='@t6g_mb_lib.t6g(sch_1):page364_i58@pure_quanta.mosfet_nch_dual(chips)',
 P_PATH='@t6g_mb_lib.t6g(sch_1):page241_i58@pure_quanta.mosfet_nch_dual(chips)',
 PATH='I58',
 DRAWING='@T6G_MB_LIB.T6G(SCH_1):PAGE364',
 PART_TYPE='SMLF',
 MATERIAL='IC',
 PHYS_PAGE='241',
 XY='(1150,-1725)',
 ROT='0',
 VER='2',
 LOCATION='Q145',
 CDS_LIB='pure_quanta',
 CDS_PART_NAME='MOSFET_NCH_DUAL-PJT138K,SMLF,IC,BAM138K0003',
 PART_NUMBER='BAM138K0003',
 VALUE='PJT138K',
 PRIM_FILE='./archive_libs/logical/mosfet_nch_dual/chips/chips.prt';

PART_NAME
 Q146 'MOSFET_NCH_DUAL-PJT138K,SMLF,IC,BAM138K0003':;

SECTION_NUMBER 1
 '@T6G_MB_LIB.T6G(SCH_1):PAGE332_I57@PURE_QUANTA.MOSFET_NCH_DUAL(CHIPS)':
 C_PATH='@t6g_mb_lib.t6g(sch_1):page332_i57@pure_quanta.mosfet_nch_dual(chips)',
 P_PATH='@t6g_mb_lib.t6g(sch_1):page125_i57@pure_quanta.mosfet_nch_dual(chips)',
 PATH='I57',
 DRAWING='@T6G_MB_LIB.T6G(SCH_1):PAGE332',
 PART_TYPE='SMLF',
 MATERIAL='IC',
 PHYS_PAGE='125',
 XY='(3600,-575)',
 ROT='0',
 VER='1',
 LOCATION='Q146',
 CDS_LIB='pure_quanta',
 CDS_PART_NAME='MOSFET_NCH_DUAL-PJT138K,SMLF,IC,BAM138K0003',
 PART_NUMBER='BAM138K0003',
 VALUE='PJT138K',
 PRIM_FILE='./archive_libs/logical/mosfet_nch_dual/chips/chips.prt';

SECTION_NUMBER 2
 '@T6G_MB_LIB.T6G(SCH_1):PAGE332_I134@PURE_QUANTA.MOSFET_NCH_DUAL(CHIPS)':
 C_PATH='@t6g_mb_lib.t6g(sch_1):page332_i134@pure_quanta.mosfet_nch_dual(chips)',
 P_PATH='@t6g_mb_lib.t6g(sch_1):page125_i134@pure_quanta.mosfet_nch_dual(chips)',
 PATH='I134',
 DRAWING='@T6G_MB_LIB.T6G(SCH_1):PAGE332',
 PART_TYPE='SMLF',
 MATERIAL='IC',
 PHYS_PAGE='125',
 XY='(4750,-275)',
 ROT='0',
 VER='2',
 LOCATION='Q146',
 CDS_LIB='pure_quanta',
 CDS_PART_NAME='MOSFET_NCH_DUAL-PJT138K,SMLF,IC,BAM138K0003',
 PART_NUMBER='BAM138K0003',
 VALUE='PJT138K',
 PRIM_FILE='./archive_libs/logical/mosfet_nch_dual/chips/chips.prt';

PART_NAME
 Q148 'MOSFET_NCH_DUAL-PJT138K,SMLF,IC,BAM138K0003':;

SECTION_NUMBER 1
 '@T6G_MB_LIB.T6G(SCH_1):PAGE331_I61@PURE_QUANTA.MOSFET_NCH_DUAL(CHIPS)':
 C_PATH='@t6g_mb_lib.t6g(sch_1):page331_i61@pure_quanta.mosfet_nch_dual(chips)',
 P_PATH='@t6g_mb_lib.t6g(sch_1):page124_i61@pure_quanta.mosfet_nch_dual(chips)',
 PATH='I61',
 DRAWING='@T6G_MB_LIB.T6G(SCH_1):PAGE331',
 PART_TYPE='SMLF',
 MATERIAL='IC',
 PHYS_PAGE='124',
 XY='(-875,525)',
 ROT='0',
 VER='1',
 LOCATION='Q148',
 CDS_LIB='pure_quanta',
 CDS_PART_NAME='MOSFET_NCH_DUAL-PJT138K,SMLF,IC,BAM138K0003',
 PART_NUMBER='BAM138K0003',
 VALUE='PJT138K',
 PRIM_FILE='./archive_libs/logical/mosfet_nch_dual/chips/chips.prt';

SECTION_NUMBER 2
 '@T6G_MB_LIB.T6G(SCH_1):PAGE331_I55@PURE_QUANTA.MOSFET_NCH_DUAL(CHIPS)':
 C_PATH='@t6g_mb_lib.t6g(sch_1):page331_i55@pure_quanta.mosfet_nch_dual(chips)',
 P_PATH='@t6g_mb_lib.t6g(sch_1):page124_i55@pure_quanta.mosfet_nch_dual(chips)',
 PATH='I55',
 DRAWING='@T6G_MB_LIB.T6G(SCH_1):PAGE331',
 PART_TYPE='SMLF',
 MATERIAL='IC',
 PHYS_PAGE='124',
 XY='(275,825)',
 ROT='0',
 VER='2',
 LOCATION='Q148',
 CDS_LIB='pure_quanta',
 CDS_PART_NAME='MOSFET_NCH_DUAL-PJT138K,SMLF,IC,BAM138K0003',
 PART_NUMBER='BAM138K0003',
 VALUE='PJT138K',
 PRIM_FILE='./archive_libs/logical/mosfet_nch_dual/chips/chips.prt';

PART_NAME
 Q6000 'MOSFET_NCH_DUAL-PJT138K,SMLF,IC,BAM138K0003':;

SECTION_NUMBER 1
 '@T6G_MB_LIB.T6G(SCH_1):PAGE254_I47@PURE_QUANTA.MOSFET_NCH_DUAL(CHIPS)':
 C_PATH='@t6g_mb_lib.t6g(sch_1):page254_i47@pure_quanta.mosfet_nch_dual(chips)',
 P_PATH='@t6g_mb_lib.t6g(sch_1):page254_i47@pure_quanta.mosfet_nch_dual(chips)',
 PATH='I47',
 DRAWING='@T6G_MB_LIB.T6G(SCH_1):PAGE254',
 PART_TYPE='SMLF',
 MATERIAL='IC',
 PHYS_PAGE='254',
 XY='(-2875,3675)',
 ROT='0',
 VER='1',
 LOCATION='Q6000',
 CDS_LIB='pure_quanta',
 CDS_PART_NAME='MOSFET_NCH_DUAL-PJT138K,SMLF,IC,BAM138K0003',
 PART_NUMBER='BAM138K0003',
 VALUE='PJT138K',
 PRIM_FILE='./archive_libs/logical/mosfet_nch_dual/chips/chips.prt';

PART_NAME
 Q6001 'METR3904G-METR3904-G,SMLF,IC,BA039040020':
 ROOM='HSC BOM2';

SECTION_NUMBER 1
 '@T6G_MB_LIB.T6G(SCH_1):PAGE371_I1@PURE_QUANTA.METR3904G(CHIPS)':
 C_PATH='@t6g_mb_lib.t6g(sch_1):page371_i1@pure_quanta.metr3904g(chips)',
 P_PATH='@t6g_mb_lib.t6g(sch_1):page267_i1@pure_quanta.metr3904g(chips)',
 PATH='I1',
 DRAWING='@T6G_MB_LIB.T6G(SCH_1):PAGE371',
 PART_TYPE='SMLF',
 MATERIAL='IC',
 PHYS_PAGE='267',
 XY='(-6100,1950)',
 ROT='2',
 VER='1',
 LOCATION='Q6001',
 CDS_LIB='pure_quanta',
 CDS_PART_NAME='METR3904G-METR3904-G,SMLF,IC,BA039040020',
 ROOM='HSC BOM2',
 PART_NUMBER='BA039040020',
 VALUE='METR3904-G',
 PRIM_FILE='./archive_libs/logical/metr3904g/chips/chips.prt';

PART_NAME
 Q7000 'MOSFET_PCH_GDS_ESD_PROTECTED-DMP2035U-7,SMLF,EMPTYA':;

SECTION_NUMBER 1
 '@T6G_MB_LIB.T6G(SCH_1):PAGE146_I10@PURE_QUANTA.MOSFET_PCH_GDS_ESD_PROTECTED(CHIPS)':
 C_PATH='@t6g_mb_lib.t6g(sch_1):page146_i10@pure_quanta.mosfet_pch_gds_esd_prote~
cted(chips)',
 P_PATH='@t6g_mb_lib.t6g(sch_1):page169_i10@pure_quanta.mosfet_pch_gds_esd_prote~
cted(chips)',
 PATH='I10',
 DRAWING='@T6G_MB_LIB.T6G(SCH_1):PAGE146',
 SEC_TYPE='',
 PART_TYPE='SMLF',
 MATERIAL='EMPTY',
 PHYS_PAGE='169',
 XY='(-5750,4350)',
 ROT='5',
 VER='1',
 LOCATION='Q7000',
 SEC='1',
 CDS_LIB='pure_quanta',
 CDS_PART_NAME='MOSFET_PCH_GDS_ESD_PROTECTED-DMP2035U-7,SMLF,EMPTYA',
 PART_NUMBER='BAM20350002',
 VALUE='DMP2035U-7',
 PRIM_FILE='./archive_libs/logical/mosfet_pch_gds_esd_protected/chips/chips.prt';

PART_NAME
 Q7001 'MOSFET_NCH_1D3S-PSMNR58-30YLH,SMLF,EMPTY,BAMNR5800A':;

SECTION_NUMBER 1
 '@T6G_MB_LIB.T6G(SCH_1):PAGE146_I16@PURE_QUANTA.MOSFET_NCH_1D3S(CHIPS)':
 C_PATH='@t6g_mb_lib.t6g(sch_1):page146_i16@pure_quanta.mosfet_nch_1d3s(chips)',
 P_PATH='@t6g_mb_lib.t6g(sch_1):page169_i16@pure_quanta.mosfet_nch_1d3s(chips)',
 PATH='I16',
 DRAWING='@T6G_MB_LIB.T6G(SCH_1):PAGE146',
 PART_TYPE='SMLF',
 MATERIAL='EMPTY',
 PHYS_PAGE='169',
 XY='(-4150,4375)',
 ROT='6',
 VER='1',
 LOCATION='Q7001',
 CDS_LIB='pure_quanta',
 CDS_PART_NAME='MOSFET_NCH_1D3S-PSMNR58-30YLH,SMLF,EMPTY,BAMNR5800A',
 PART_NUMBER='BAMNR580000',
 VALUE='PSMNR58-30YLH',
 PRIM_FILE='./archive_libs/logical/mosfet_nch_1d3s/chips/chips.prt';

PART_NAME
 Q7002 'MOSFET_PCH_GDS_ESD_PROTECTED-DMP2035U-7,SMLF,EMPTYA':;

SECTION_NUMBER 1
 '@T6G_MB_LIB.T6G(SCH_1):PAGE146_I23@PURE_QUANTA.MOSFET_PCH_GDS_ESD_PROTECTED(CHIPS)':
 C_PATH='@t6g_mb_lib.t6g(sch_1):page146_i23@pure_quanta.mosfet_pch_gds_esd_prote~
cted(chips)',
 P_PATH='@t6g_mb_lib.t6g(sch_1):page169_i23@pure_quanta.mosfet_pch_gds_esd_prote~
cted(chips)',
 PATH='I23',
 DRAWING='@T6G_MB_LIB.T6G(SCH_1):PAGE146',
 PART_TYPE='SMLF',
 MATERIAL='EMPTY',
 PHYS_PAGE='169',
 XY='(-5625,1475)',
 ROT='5',
 VER='1',
 LOCATION='Q7002',
 CDS_LIB='pure_quanta',
 CDS_PART_NAME='MOSFET_PCH_GDS_ESD_PROTECTED-DMP2035U-7,SMLF,EMPTYA',
 PART_NUMBER='BAM20350002',
 VALUE='DMP2035U-7',
 PRIM_FILE='./archive_libs/logical/mosfet_pch_gds_esd_protected/chips/chips.prt';

PART_NAME
 Q7003 'MOSFET_NCH_1D3S-PSMNR58-30YLH,SMLF,EMPTY,BAMNR5800A':;

SECTION_NUMBER 1
 '@T6G_MB_LIB.T6G(SCH_1):PAGE146_I22@PURE_QUANTA.MOSFET_NCH_1D3S(CHIPS)':
 C_PATH='@t6g_mb_lib.t6g(sch_1):page146_i22@pure_quanta.mosfet_nch_1d3s(chips)',
 P_PATH='@t6g_mb_lib.t6g(sch_1):page169_i22@pure_quanta.mosfet_nch_1d3s(chips)',
 PATH='I22',
 DRAWING='@T6G_MB_LIB.T6G(SCH_1):PAGE146',
 PART_TYPE='SMLF',
 MATERIAL='EMPTY',
 PHYS_PAGE='169',
 XY='(-4025,1500)',
 ROT='6',
 VER='1',
 LOCATION='Q7003',
 CDS_LIB='pure_quanta',
 CDS_PART_NAME='MOSFET_NCH_1D3S-PSMNR58-30YLH,SMLF,EMPTY,BAMNR5800A',
 PART_NUMBER='BAMNR580000',
 VALUE='PSMNR58-30YLH',
 PRIM_FILE='./archive_libs/logical/mosfet_nch_1d3s/chips/chips.prt';

PART_NAME
 Q8000 'MOSFET_NCH_DUAL-PJT138K,SMLF,IC,BAM138K0003':;

SECTION_NUMBER 1
 '@T6G_MB_LIB.T6G(SCH_1):PAGE330_I29@PURE_QUANTA.MOSFET_NCH_DUAL(CHIPS)':
 C_PATH='@t6g_mb_lib.t6g(sch_1):page330_i29@pure_quanta.mosfet_nch_dual(chips)',
 P_PATH='@t6g_mb_lib.t6g(sch_1):page123_i29@pure_quanta.mosfet_nch_dual(chips)',
 PATH='I29',
 DRAWING='@T6G_MB_LIB.T6G(SCH_1):PAGE330',
 SEC_TYPE='',
 PART_TYPE='SMLF',
 MATERIAL='IC',
 PHYS_PAGE='123',
 XY='(-5725,7825)',
 ROT='0',
 VER='1',
 LOCATION='Q8000',
 SEC='1',
 CDS_LIB='pure_quanta',
 CDS_PART_NAME='MOSFET_NCH_DUAL-PJT138K,SMLF,IC,BAM138K0003',
 PART_NUMBER='BAM138K0003',
 VALUE='PJT138K',
 PRIM_FILE='./archive_libs/logical/mosfet_nch_dual/chips/chips.prt';

SECTION_NUMBER 2
 '@T6G_MB_LIB.T6G(SCH_1):PAGE330_I30@PURE_QUANTA.MOSFET_NCH_DUAL(CHIPS)':
 C_PATH='@t6g_mb_lib.t6g(sch_1):page330_i30@pure_quanta.mosfet_nch_dual(chips)',
 P_PATH='@t6g_mb_lib.t6g(sch_1):page123_i30@pure_quanta.mosfet_nch_dual(chips)',
 PATH='I30',
 DRAWING='@T6G_MB_LIB.T6G(SCH_1):PAGE330',
 SEC_TYPE='',
 PART_TYPE='SMLF',
 MATERIAL='IC',
 PHYS_PAGE='123',
 XY='(-4900,8175)',
 ROT='0',
 VER='2',
 LOCATION='Q8000',
 SEC='2',
 CDS_LIB='pure_quanta',
 CDS_PART_NAME='MOSFET_NCH_DUAL-PJT138K,SMLF,IC,BAM138K0003',
 PART_NUMBER='BAM138K0003',
 VALUE='PJT138K',
 PRIM_FILE='./archive_libs/logical/mosfet_nch_dual/chips/chips.prt';

PART_NAME
 Q8001 'MOSFET_NCH_DUAL-PJT138K,SMLF,IC,BAM138K0003':;

SECTION_NUMBER 1
 '@T6G_MB_LIB.T6G(SCH_1):PAGE375_I57@PURE_QUANTA.MOSFET_NCH_DUAL(CHIPS)':
 C_PATH='@t6g_mb_lib.t6g(sch_1):page375_i57@pure_quanta.mosfet_nch_dual(chips)',
 P_PATH='@t6g_mb_lib.t6g(sch_1):page256_i57@pure_quanta.mosfet_nch_dual(chips)',
 PATH='I57',
 DRAWING='@T6G_MB_LIB.T6G(SCH_1):PAGE375',
 SEC_TYPE='',
 PART_TYPE='SMLF',
 MATERIAL='IC',
 PHYS_PAGE='256',
 XY='(-3075,750)',
 ROT='0',
 VER='1',
 LOCATION='Q8001',
 SEC='1',
 CDS_LIB='pure_quanta',
 CDS_PART_NAME='MOSFET_NCH_DUAL-PJT138K,SMLF,IC,BAM138K0003',
 PART_NUMBER='BAM138K0003',
 VALUE='PJT138K',
 PRIM_FILE='./archive_libs/logical/mosfet_nch_dual/chips/chips.prt';

SECTION_NUMBER 2
 '@T6G_MB_LIB.T6G(SCH_1):PAGE375_I58@PURE_QUANTA.MOSFET_NCH_DUAL(CHIPS)':
 C_PATH='@t6g_mb_lib.t6g(sch_1):page375_i58@pure_quanta.mosfet_nch_dual(chips)',
 P_PATH='@t6g_mb_lib.t6g(sch_1):page256_i58@pure_quanta.mosfet_nch_dual(chips)',
 PATH='I58',
 DRAWING='@T6G_MB_LIB.T6G(SCH_1):PAGE375',
 SEC_TYPE='',
 PART_TYPE='SMLF',
 MATERIAL='IC',
 PHYS_PAGE='256',
 XY='(-2100,1175)',
 ROT='0',
 VER='2',
 LOCATION='Q8001',
 SEC='2',
 CDS_LIB='pure_quanta',
 CDS_PART_NAME='MOSFET_NCH_DUAL-PJT138K,SMLF,IC,BAM138K0003',
 PART_NUMBER='BAM138K0003',
 VALUE='PJT138K',
 PRIM_FILE='./archive_libs/logical/mosfet_nch_dual/chips/chips.prt';

PART_NAME
 Q9000 'MOSFET_NCH_DUAL-PJT138K,SMLF,IC,BAM138K0003':;

SECTION_NUMBER 1
 '@T6G_MB_LIB.T6G(SCH_1):PAGE330_I21@PURE_QUANTA.MOSFET_NCH_DUAL(CHIPS)':
 C_PATH='@t6g_mb_lib.t6g(sch_1):page330_i21@pure_quanta.mosfet_nch_dual(chips)',
 P_PATH='@t6g_mb_lib.t6g(sch_1):page123_i21@pure_quanta.mosfet_nch_dual(chips)',
 PATH='I21',
 DRAWING='@T6G_MB_LIB.T6G(SCH_1):PAGE330',
 SEC_TYPE='',
 PART_TYPE='SMLF',
 MATERIAL='IC',
 PHYS_PAGE='123',
 XY='(-5750,6050)',
 ROT='0',
 VER='1',
 LOCATION='Q9000',
 SEC='1',
 CDS_LIB='pure_quanta',
 CDS_PART_NAME='MOSFET_NCH_DUAL-PJT138K,SMLF,IC,BAM138K0003',
 PART_NUMBER='BAM138K0003',
 VALUE='PJT138K',
 PRIM_FILE='./archive_libs/logical/mosfet_nch_dual/chips/chips.prt';

SECTION_NUMBER 2
 '@T6G_MB_LIB.T6G(SCH_1):PAGE330_I31@PURE_QUANTA.MOSFET_NCH_DUAL(CHIPS)':
 C_PATH='@t6g_mb_lib.t6g(sch_1):page330_i31@pure_quanta.mosfet_nch_dual(chips)',
 P_PATH='@t6g_mb_lib.t6g(sch_1):page123_i31@pure_quanta.mosfet_nch_dual(chips)',
 PATH='I31',
 DRAWING='@T6G_MB_LIB.T6G(SCH_1):PAGE330',
 SEC_TYPE='',
 PART_TYPE='SMLF',
 MATERIAL='IC',
 PHYS_PAGE='123',
 XY='(-4750,6400)',
 ROT='0',
 VER='2',
 LOCATION='Q9000',
 SEC='2',
 CDS_LIB='pure_quanta',
 CDS_PART_NAME='MOSFET_NCH_DUAL-PJT138K,SMLF,IC,BAM138K0003',
 PART_NUMBER='BAM138K0003',
 VALUE='PJT138K',
 PRIM_FILE='./archive_libs/logical/mosfet_nch_dual/chips/chips.prt';

PART_NAME
 Q9001 'MOSFET_NCH_DUAL-PJT138K,SMLF,IC,BAM138K0003':;

SECTION_NUMBER 1
 '@T6G_MB_LIB.T6G(SCH_1):PAGE330_I3@PURE_QUANTA.MOSFET_NCH_DUAL(CHIPS)':
 C_PATH='@t6g_mb_lib.t6g(sch_1):page330_i3@pure_quanta.mosfet_nch_dual(chips)',
 P_PATH='@t6g_mb_lib.t6g(sch_1):page123_i3@pure_quanta.mosfet_nch_dual(chips)',
 PATH='I3',
 DRAWING='@T6G_MB_LIB.T6G(SCH_1):PAGE330',
 PART_TYPE='SMLF',
 MATERIAL='IC',
 PHYS_PAGE='123',
 XY='(-5700,4250)',
 ROT='0',
 VER='1',
 LOCATION='Q9001',
 CDS_LIB='pure_quanta',
 CDS_PART_NAME='MOSFET_NCH_DUAL-PJT138K,SMLF,IC,BAM138K0003',
 PART_NUMBER='BAM138K0003',
 VALUE='PJT138K',
 PRIM_FILE='./archive_libs/logical/mosfet_nch_dual/chips/chips.prt';

SECTION_NUMBER 2
 '@T6G_MB_LIB.T6G(SCH_1):PAGE330_I22@PURE_QUANTA.MOSFET_NCH_DUAL(CHIPS)':
 C_PATH='@t6g_mb_lib.t6g(sch_1):page330_i22@pure_quanta.mosfet_nch_dual(chips)',
 P_PATH='@t6g_mb_lib.t6g(sch_1):page123_i22@pure_quanta.mosfet_nch_dual(chips)',
 PATH='I22',
 DRAWING='@T6G_MB_LIB.T6G(SCH_1):PAGE330',
 PART_TYPE='SMLF',
 MATERIAL='IC',
 PHYS_PAGE='123',
 XY='(-4700,4600)',
 ROT='0',
 VER='2',
 LOCATION='Q9001',
 CDS_LIB='pure_quanta',
 CDS_PART_NAME='MOSFET_NCH_DUAL-PJT138K,SMLF,IC,BAM138K0003',
 PART_NUMBER='BAM138K0003',
 VALUE='PJT138K',
 PRIM_FILE='./archive_libs/logical/mosfet_nch_dual/chips/chips.prt';

PART_NAME
 Q9002 'MOSFET_NCH_DUAL-PJT138K,SMLF,IC,BAM138K0003':;

SECTION_NUMBER 1
 '@T6G_MB_LIB.T6G(SCH_1):PAGE330_I52@PURE_QUANTA.MOSFET_NCH_DUAL(CHIPS)':
 C_PATH='@t6g_mb_lib.t6g(sch_1):page330_i52@pure_quanta.mosfet_nch_dual(chips)',
 P_PATH='@t6g_mb_lib.t6g(sch_1):page123_i52@pure_quanta.mosfet_nch_dual(chips)',
 PATH='I52',
 DRAWING='@T6G_MB_LIB.T6G(SCH_1):PAGE330',
 PART_TYPE='SMLF',
 MATERIAL='IC',
 PHYS_PAGE='123',
 XY='(-975,7825)',
 ROT='0',
 VER='1',
 LOCATION='Q9002',
 CDS_LIB='pure_quanta',
 CDS_PART_NAME='MOSFET_NCH_DUAL-PJT138K,SMLF,IC,BAM138K0003',
 PART_NUMBER='BAM138K0003',
 VALUE='PJT138K',
 PRIM_FILE='./archive_libs/logical/mosfet_nch_dual/chips/chips.prt';

SECTION_NUMBER 2
 '@T6G_MB_LIB.T6G(SCH_1):PAGE330_I75@PURE_QUANTA.MOSFET_NCH_DUAL(CHIPS)':
 C_PATH='@t6g_mb_lib.t6g(sch_1):page330_i75@pure_quanta.mosfet_nch_dual(chips)',
 P_PATH='@t6g_mb_lib.t6g(sch_1):page123_i75@pure_quanta.mosfet_nch_dual(chips)',
 PATH='I75',
 DRAWING='@T6G_MB_LIB.T6G(SCH_1):PAGE330',
 PART_TYPE='SMLF',
 MATERIAL='IC',
 PHYS_PAGE='123',
 XY='(25,8175)',
 ROT='0',
 VER='2',
 LOCATION='Q9002',
 CDS_LIB='pure_quanta',
 CDS_PART_NAME='MOSFET_NCH_DUAL-PJT138K,SMLF,IC,BAM138K0003',
 PART_NUMBER='BAM138K0003',
 VALUE='PJT138K',
 PRIM_FILE='./archive_libs/logical/mosfet_nch_dual/chips/chips.prt';

PART_NAME
 Q9003 'MOSFET_NCH_DUAL-PJT138K,SMLF,IC,BAM138K0003':;

SECTION_NUMBER 1
 '@T6G_MB_LIB.T6G(SCH_1):PAGE84_I111@PURE_QUANTA.MOSFET_NCH_DUAL(CHIPS)':
 C_PATH='@t6g_mb_lib.t6g(sch_1):page84_i111@pure_quanta.mosfet_nch_dual(chips)',
 P_PATH='@t6g_mb_lib.t6g(sch_1):page85_i111@pure_quanta.mosfet_nch_dual(chips)',
 PATH='I111',
 DRAWING='@T6G_MB_LIB.T6G(SCH_1):PAGE84',
 PART_TYPE='SMLF',
 MATERIAL='IC',
 PHYS_PAGE='85',
 XY='(-7525,3900)',
 ROT='0',
 VER='1',
 LOCATION='Q9003',
 CDS_LIB='pure_quanta',
 CDS_PART_NAME='MOSFET_NCH_DUAL-PJT138K,SMLF,IC,BAM138K0003',
 PART_NUMBER='BAM138K0003',
 VALUE='PJT138K',
 PRIM_FILE='./archive_libs/logical/mosfet_nch_dual/chips/chips.prt';

SECTION_NUMBER 2
 '@T6G_MB_LIB.T6G(SCH_1):PAGE84_I121@PURE_QUANTA.MOSFET_NCH_DUAL(CHIPS)':
 C_PATH='@t6g_mb_lib.t6g(sch_1):page84_i121@pure_quanta.mosfet_nch_dual(chips)',
 P_PATH='@t6g_mb_lib.t6g(sch_1):page85_i121@pure_quanta.mosfet_nch_dual(chips)',
 PATH='I121',
 DRAWING='@T6G_MB_LIB.T6G(SCH_1):PAGE84',
 PART_TYPE='SMLF',
 MATERIAL='IC',
 PHYS_PAGE='85',
 XY='(-6375,4200)',
 ROT='0',
 VER='2',
 LOCATION='Q9003',
 CDS_LIB='pure_quanta',
 CDS_PART_NAME='MOSFET_NCH_DUAL-PJT138K,SMLF,IC,BAM138K0003',
 PART_NUMBER='BAM138K0003',
 VALUE='PJT138K',
 PRIM_FILE='./archive_libs/logical/mosfet_nch_dual/chips/chips.prt';

PART_NAME
 R1 'Q_RES_0402LF-49.9,1%,1/16W,CHIP,CS04992FB07':;

SECTION_NUMBER 1
 '@T6G_MB_LIB.T6G(SCH_1):PAGE88_I421@PURE_QUANTA.Q_RES(CHIPS)':
 C_PATH='@t6g_mb_lib.t6g(sch_1):page88_i421@pure_quanta.q_res(chips)',
 P_PATH='@t6g_mb_lib.t6g(sch_1):page89_i421@pure_quanta.q_res(chips)',
 PATH='I421',
 DRAWING='@T6G_MB_LIB.T6G(SCH_1):PAGE88',
 WATTAGE='1/16W',
 TOLERANCE='1%',
 MATERIAL='CHIP',
 PHYS_PAGE='89',
 XY='(-7825,2775)',
 ROT='0',
 VER='1',
 PACK_TYPE='0402LF',
 LOCATION='R1',
 CDS_LIB='pure_quanta',
 CDS_PART_NAME='Q_RES_0402LF-49.9,1%,1/16W,CHIP,CS04992FB07',
 PART_NUMBER='CS04992FB07',
 VALUE='49.9',
 PRIM_FILE='./archive_libs/logical/q_res/chips/chips.prt';

PART_NAME
 R2 'Q_RES_0402LF-33.2,1%,1/16W,CHIP,CS03322FB03':;

SECTION_NUMBER 1
 '@T6G_MB_LIB.T6G(SCH_1):PAGE84_I94@PURE_QUANTA.Q_RES(CHIPS)':
 C_PATH='@t6g_mb_lib.t6g(sch_1):page84_i94@pure_quanta.q_res(chips)',
 P_PATH='@t6g_mb_lib.t6g(sch_1):page85_i94@pure_quanta.q_res(chips)',
 PATH='I94',
 DRAWING='@T6G_MB_LIB.T6G(SCH_1):PAGE84',
 BOM_COST='MEM',
 WATTAGE='1/16W',
 TOLERANCE='1%',
 MATERIAL='CHIP',
 PHYS_PAGE='85',
 XY='(-7550,2100)',
 ROT='0',
 VER='1',
 PACK_TYPE='0402LF',
 LOCATION='R2',
 CDS_LIB='pure_quanta',
 CDS_PART_NAME='Q_RES_0402LF-33.2,1%,1/16W,CHIP,CS03322FB03',
 PART_NUMBER='CS03322FB03',
 VALUE='33.2',
 PRIM_FILE='./archive_libs/logical/q_res/chips/chips.prt';

PART_NAME
 R3 'Q_RES_0402LF-2K,1%,1/16W,CHIP,CS22002FB07':;

SECTION_NUMBER 1
 '@T6G_MB_LIB.T6G(SCH_1):PAGE82_I154@PURE_QUANTA.Q_RES(CHIPS)':
 C_PATH='@t6g_mb_lib.t6g(sch_1):page82_i154@pure_quanta.q_res(chips)',
 P_PATH='@t6g_mb_lib.t6g(sch_1):page83_i154@pure_quanta.q_res(chips)',
 PATH='I154',
 DRAWING='@T6G_MB_LIB.T6G(SCH_1):PAGE82',
 WATTAGE='1/16W',
 TOLERANCE='1%',
 MATERIAL='CHIP',
 PHYS_PAGE='83',
 XY='(-5350,4925)',
 ROT='0',
 VER='1',
 PACK_TYPE='0402LF',
 LOCATION='R3',
 CDS_LIB='pure_quanta',
 CDS_PART_NAME='Q_RES_0402LF-2K,1%,1/16W,CHIP,CS22002FB07',
 PART_NUMBER='CS22002FB07',
 VALUE='2K',
 PRIM_FILE='./archive_libs/logical/q_res/chips/chips.prt';

PART_NAME
 R4 'Q_RES_0402LF-4.7K,5%,1/16W,EMPTY,CS24702JB10':;

SECTION_NUMBER 1
 '@T6G_MB_LIB.T6G(SCH_1):PAGE361_I114@PURE_QUANTA.Q_RES(CHIPS)':
 C_PATH='@t6g_mb_lib.t6g(sch_1):page361_i114@pure_quanta.q_res(chips)',
 P_PATH='@t6g_mb_lib.t6g(sch_1):page238_i114@pure_quanta.q_res(chips)',
 PATH='I114',
 DRAWING='@T6G_MB_LIB.T6G(SCH_1):PAGE361',
 WATTAGE='1/16W',
 TOLERANCE='5%',
 MATERIAL='EMPTY',
 PHYS_PAGE='238',
 XY='(-2000,1350)',
 ROT='2',
 VER='2',
 PACK_TYPE='0402LF',
 LOCATION='R4',
 CDS_LIB='pure_quanta',
 CDS_PART_NAME='Q_RES_0402LF-4.7K,5%,1/16W,EMPTY,CS24702JB10',
 PART_NUMBER='CS24702JB10',
 VALUE='4.7K',
 PRIM_FILE='./archive_libs/logical/q_res/chips/chips.prt';

PART_NAME
 R5 'Q_RES_0402LF-54.9K,1%,1/16W,CHIP,CS35492FB03':;

SECTION_NUMBER 1
 '@T6G_MB_LIB.T6G(SCH_1):PAGE89_I331@PURE_QUANTA.Q_RES(CHIPS)':
 C_PATH='@t6g_mb_lib.t6g(sch_1):page89_i331@pure_quanta.q_res(chips)',
 P_PATH='@t6g_mb_lib.t6g(sch_1):page90_i331@pure_quanta.q_res(chips)',
 PATH='I331',
 DRAWING='@T6G_MB_LIB.T6G(SCH_1):PAGE89',
 SEC_TYPE='0402LF',
 BOM_COST='MEM',
 WATTAGE='1/16W',
 TOLERANCE='1%',
 MATERIAL='CHIP',
 PHYS_PAGE='90',
 XY='(-6650,1425)',
 ROT='0',
 VER='2',
 PACK_TYPE='0402LF',
 LOCATION='R5',
 SEC='1',
 CDS_LIB='pure_quanta',
 CDS_PART_NAME='Q_RES_0402LF-54.9K,1%,1/16W,CHIP,CS35492FB03',
 PART_NUMBER='CS35492FB03',
 VALUE='54.9K',
 PRIM_FILE='./archive_libs/logical/q_res/chips/chips.prt';

PART_NAME
 R6 'Q_RES_0402LF-54.9K,1%,1/16W,CHIP,CS35492FB03':;

SECTION_NUMBER 1
 '@T6G_MB_LIB.T6G(SCH_1):PAGE101_I127@PURE_QUANTA.Q_RES(CHIPS)':
 C_PATH='@t6g_mb_lib.t6g(sch_1):page101_i127@pure_quanta.q_res(chips)',
 P_PATH='@t6g_mb_lib.t6g(sch_1):page102_i127@pure_quanta.q_res(chips)',
 PATH='I127',
 DRAWING='@T6G_MB_LIB.T6G(SCH_1):PAGE101',
 SEC_TYPE='0402LF',
 BOM_COST='MEM',
 WATTAGE='1/16W',
 TOLERANCE='1%',
 MATERIAL='CHIP',
 PHYS_PAGE='102',
 XY='(-6575,1475)',
 ROT='0',
 VER='2',
 PACK_TYPE='0402LF',
 LOCATION='R6',
 SEC='1',
 CDS_LIB='pure_quanta',
 CDS_PART_NAME='Q_RES_0402LF-54.9K,1%,1/16W,CHIP,CS35492FB03',
 PART_NUMBER='CS35492FB03',
 VALUE='54.9K',
 PRIM_FILE='./archive_libs/logical/q_res/chips/chips.prt';

PART_NAME
 R7 'Q_RES_0402LF-10K,1%,1/16W,CHIP,CS31002FB08':
 ROOM='';

SECTION_NUMBER 1
 '@T6G_MB_LIB.T6G(SCH_1):PAGE85_I499@PURE_QUANTA.Q_RES(CHIPS)':
 C_PATH='@t6g_mb_lib.t6g(sch_1):page85_i499@pure_quanta.q_res(chips)',
 P_PATH='@t6g_mb_lib.t6g(sch_1):page86_i499@pure_quanta.q_res(chips)',
 PATH='I499',
 DRAWING='@T6G_MB_LIB.T6G(SCH_1):PAGE85',
 SEC_TYPE='0402LF',
 BOM_COST='MEM',
 WATTAGE='1/16W',
 TOLERANCE='1%',
 MATERIAL='CHIP',
 PHYS_PAGE='86',
 XY='(-6500,1325)',
 ROT='0',
 VER='2',
 PACK_TYPE='0402LF',
 LOCATION='R7',
 SEC='1',
 CDS_LIB='pure_quanta',
 CDS_PART_NAME='Q_RES_0402LF-10K,1%,1/16W,CHIP,CS31002FB08',
 ROOM='',
 PART_NUMBER='CS31002FB08',
 VALUE='10K',
 PRIM_FILE='./archive_libs/logical/q_res/chips/chips.prt';

PART_NAME
 R8 'Q_RES_0402LF-100K,1%,1/16W,CHIP,CS41002FB09':;

SECTION_NUMBER 1
 '@T6G_MB_LIB.T6G(SCH_1):PAGE144_I47@PURE_QUANTA.Q_RES(CHIPS)':
 C_PATH='@t6g_mb_lib.t6g(sch_1):page144_i47@pure_quanta.q_res(chips)',
 P_PATH='@t6g_mb_lib.t6g(sch_1):page167_i47@pure_quanta.q_res(chips)',
 PATH='I47',
 DRAWING='@T6G_MB_LIB.T6G(SCH_1):PAGE144',
 WATTAGE='1/16W',
 TOLERANCE='1%',
 MATERIAL='CHIP',
 PHYS_PAGE='167',
 XY='(-4300,3900)',
 ROT='1',
 VER='1',
 PACK_TYPE='0402LF',
 LOCATION='R8',
 CDS_LIB='pure_quanta',
 CDS_PART_NAME='Q_RES_0402LF-100K,1%,1/16W,CHIP,CS41002FB09',
 PART_NUMBER='CS41002FB09',
 VALUE='100K',
 PRIM_FILE='./archive_libs/logical/q_res/chips/chips.prt';

PART_NAME
 R9 'Q_RES_0402LF-0,5%,1/16W,CHIP,CS00002JB13':;

SECTION_NUMBER 1
 '@T6G_MB_LIB.T6G(SCH_1):PAGE84_I37@PURE_QUANTA.Q_RES(CHIPS)':
 C_PATH='@t6g_mb_lib.t6g(sch_1):page84_i37@pure_quanta.q_res(chips)',
 P_PATH='@t6g_mb_lib.t6g(sch_1):page85_i37@pure_quanta.q_res(chips)',
 PATH='I37',
 DRAWING='@T6G_MB_LIB.T6G(SCH_1):PAGE84',
 BOM_COST='MEM',
 WATTAGE='1/16W',
 TOLERANCE='5%',
 MATERIAL='CHIP',
 PHYS_PAGE='85',
 XY='(-2575,1825)',
 ROT='2',
 VER='1',
 PACK_TYPE='0402LF',
 LOCATION='R9',
 CDS_LIB='pure_quanta',
 CDS_PART_NAME='Q_RES_0402LF-0,5%,1/16W,CHIP,CS00002JB13',
 PART_NUMBER='CS00002JB13',
 VALUE='0',
 PRIM_FILE='./archive_libs/logical/q_res/chips/chips.prt';

PART_NAME
 R10 'Q_RES_0402LF-10K,1%,1/16W,CHIP,CS31002FB08':;

SECTION_NUMBER 1
 '@T6G_MB_LIB.T6G(SCH_1):PAGE82_I93@PURE_QUANTA.Q_RES(CHIPS)':
 C_PATH='@t6g_mb_lib.t6g(sch_1):page82_i93@pure_quanta.q_res(chips)',
 P_PATH='@t6g_mb_lib.t6g(sch_1):page83_i93@pure_quanta.q_res(chips)',
 PATH='I93',
 DRAWING='@T6G_MB_LIB.T6G(SCH_1):PAGE82',
 BOM_COST='MEM',
 WATTAGE='1/16W',
 TOLERANCE='1%',
 MATERIAL='CHIP',
 PHYS_PAGE='83',
 XY='(-3700,3250)',
 ROT='0',
 VER='2',
 PACK_TYPE='0402LF',
 LOCATION='R10',
 CDS_LIB='pure_quanta',
 CDS_PART_NAME='Q_RES_0402LF-10K,1%,1/16W,CHIP,CS31002FB08',
 PART_NUMBER='CS31002FB08',
 VALUE='10K',
 PRIM_FILE='./archive_libs/logical/q_res/chips/chips.prt';

PART_NAME
 R11 'Q_RES_0402LF-10K,1%,1/16W,CHIP,CS31002FB08':;

SECTION_NUMBER 1
 '@T6G_MB_LIB.T6G(SCH_1):PAGE82_I94@PURE_QUANTA.Q_RES(CHIPS)':
 C_PATH='@t6g_mb_lib.t6g(sch_1):page82_i94@pure_quanta.q_res(chips)',
 P_PATH='@t6g_mb_lib.t6g(sch_1):page83_i94@pure_quanta.q_res(chips)',
 PATH='I94',
 DRAWING='@T6G_MB_LIB.T6G(SCH_1):PAGE82',
 BOM_COST='MEM',
 WATTAGE='1/16W',
 TOLERANCE='1%',
 MATERIAL='CHIP',
 PHYS_PAGE='83',
 XY='(-3500,3250)',
 ROT='0',
 VER='2',
 PACK_TYPE='0402LF',
 LOCATION='R11',
 CDS_LIB='pure_quanta',
 CDS_PART_NAME='Q_RES_0402LF-10K,1%,1/16W,CHIP,CS31002FB08',
 PART_NUMBER='CS31002FB08',
 VALUE='10K',
 PRIM_FILE='./archive_libs/logical/q_res/chips/chips.prt';

PART_NAME
 R12 'Q_RES_0402LF-10K,1%,1/16W,CHIP,CS31002FB08':;

SECTION_NUMBER 1
 '@T6G_MB_LIB.T6G(SCH_1):PAGE82_I95@PURE_QUANTA.Q_RES(CHIPS)':
 C_PATH='@t6g_mb_lib.t6g(sch_1):page82_i95@pure_quanta.q_res(chips)',
 P_PATH='@t6g_mb_lib.t6g(sch_1):page83_i95@pure_quanta.q_res(chips)',
 PATH='I95',
 DRAWING='@T6G_MB_LIB.T6G(SCH_1):PAGE82',
 BOM_COST='MEM',
 WATTAGE='1/16W',
 TOLERANCE='1%',
 MATERIAL='CHIP',
 PHYS_PAGE='83',
 XY='(-3300,3250)',
 ROT='0',
 VER='2',
 PACK_TYPE='0402LF',
 LOCATION='R12',
 CDS_LIB='pure_quanta',
 CDS_PART_NAME='Q_RES_0402LF-10K,1%,1/16W,CHIP,CS31002FB08',
 PART_NUMBER='CS31002FB08',
 VALUE='10K',
 PRIM_FILE='./archive_libs/logical/q_res/chips/chips.prt';

PART_NAME
 R13 'Q_RES_0402LF-0,5%,1/16W,CHIP,CS00002JB13':;

SECTION_NUMBER 1
 '@T6G_MB_LIB.T6G(SCH_1):PAGE84_I38@PURE_QUANTA.Q_RES(CHIPS)':
 C_PATH='@t6g_mb_lib.t6g(sch_1):page84_i38@pure_quanta.q_res(chips)',
 P_PATH='@t6g_mb_lib.t6g(sch_1):page85_i38@pure_quanta.q_res(chips)',
 PATH='I38',
 DRAWING='@T6G_MB_LIB.T6G(SCH_1):PAGE84',
 BOM_COST='MEM',
 WATTAGE='1/16W',
 TOLERANCE='5%',
 MATERIAL='CHIP',
 PHYS_PAGE='85',
 XY='(-2575,1775)',
 ROT='2',
 VER='1',
 PACK_TYPE='0402LF',
 LOCATION='R13',
 CDS_LIB='pure_quanta',
 CDS_PART_NAME='Q_RES_0402LF-0,5%,1/16W,CHIP,CS00002JB13',
 PART_NUMBER='CS00002JB13',
 VALUE='0',
 PRIM_FILE='./archive_libs/logical/q_res/chips/chips.prt';

PART_NAME
 R14 'Q_RES_0402LF-0,5%,1/16W,CHIP,CS00002JB13':;

SECTION_NUMBER 1
 '@T6G_MB_LIB.T6G(SCH_1):PAGE84_I36@PURE_QUANTA.Q_RES(CHIPS)':
 C_PATH='@t6g_mb_lib.t6g(sch_1):page84_i36@pure_quanta.q_res(chips)',
 P_PATH='@t6g_mb_lib.t6g(sch_1):page85_i36@pure_quanta.q_res(chips)',
 PATH='I36',
 DRAWING='@T6G_MB_LIB.T6G(SCH_1):PAGE84',
 BOM_COST='MEM',
 WATTAGE='1/16W',
 TOLERANCE='5%',
 MATERIAL='CHIP',
 PHYS_PAGE='85',
 XY='(-2575,1625)',
 ROT='2',
 VER='1',
 PACK_TYPE='0402LF',
 LOCATION='R14',
 CDS_LIB='pure_quanta',
 CDS_PART_NAME='Q_RES_0402LF-0,5%,1/16W,CHIP,CS00002JB13',
 PART_NUMBER='CS00002JB13',
 VALUE='0',
 PRIM_FILE='./archive_libs/logical/q_res/chips/chips.prt';

PART_NAME
 R15 'Q_RES_0402LF-0,5%,1/16W,CHIP,CS00002JB13':;

SECTION_NUMBER 1
 '@T6G_MB_LIB.T6G(SCH_1):PAGE84_I35@PURE_QUANTA.Q_RES(CHIPS)':
 C_PATH='@t6g_mb_lib.t6g(sch_1):page84_i35@pure_quanta.q_res(chips)',
 P_PATH='@t6g_mb_lib.t6g(sch_1):page85_i35@pure_quanta.q_res(chips)',
 PATH='I35',
 DRAWING='@T6G_MB_LIB.T6G(SCH_1):PAGE84',
 BOM_COST='MEM',
 WATTAGE='1/16W',
 TOLERANCE='5%',
 MATERIAL='CHIP',
 PHYS_PAGE='85',
 XY='(-2575,1525)',
 ROT='2',
 VER='1',
 PACK_TYPE='0402LF',
 LOCATION='R15',
 CDS_LIB='pure_quanta',
 CDS_PART_NAME='Q_RES_0402LF-0,5%,1/16W,CHIP,CS00002JB13',
 PART_NUMBER='CS00002JB13',
 VALUE='0',
 PRIM_FILE='./archive_libs/logical/q_res/chips/chips.prt';

PART_NAME
 R16 'Q_RES_0402LF-10K,1%,1/16W,CHIP,CS31002FB08':;

SECTION_NUMBER 1
 '@T6G_MB_LIB.T6G(SCH_1):PAGE82_I124@PURE_QUANTA.Q_RES(CHIPS)':
 C_PATH='@t6g_mb_lib.t6g(sch_1):page82_i124@pure_quanta.q_res(chips)',
 P_PATH='@t6g_mb_lib.t6g(sch_1):page83_i124@pure_quanta.q_res(chips)',
 PATH='I124',
 DRAWING='@T6G_MB_LIB.T6G(SCH_1):PAGE82',
 BOM_COST='MEM',
 WATTAGE='1/16W',
 TOLERANCE='1%',
 MATERIAL='CHIP',
 PHYS_PAGE='83',
 XY='(-3500,5800)',
 ROT='0',
 VER='2',
 PACK_TYPE='0402LF',
 LOCATION='R16',
 CDS_LIB='pure_quanta',
 CDS_PART_NAME='Q_RES_0402LF-10K,1%,1/16W,CHIP,CS31002FB08',
 PART_NUMBER='CS31002FB08',
 VALUE='10K',
 PRIM_FILE='./archive_libs/logical/q_res/chips/chips.prt';

PART_NAME
 R17 'Q_RES_0402LF-10K,1%,1/16W,CHIP,CS31002FB08':;

SECTION_NUMBER 1
 '@T6G_MB_LIB.T6G(SCH_1):PAGE82_I125@PURE_QUANTA.Q_RES(CHIPS)':
 C_PATH='@t6g_mb_lib.t6g(sch_1):page82_i125@pure_quanta.q_res(chips)',
 P_PATH='@t6g_mb_lib.t6g(sch_1):page83_i125@pure_quanta.q_res(chips)',
 PATH='I125',
 DRAWING='@T6G_MB_LIB.T6G(SCH_1):PAGE82',
 BOM_COST='MEM',
 WATTAGE='1/16W',
 TOLERANCE='1%',
 MATERIAL='CHIP',
 PHYS_PAGE='83',
 XY='(-3300,5800)',
 ROT='0',
 VER='2',
 PACK_TYPE='0402LF',
 LOCATION='R17',
 CDS_LIB='pure_quanta',
 CDS_PART_NAME='Q_RES_0402LF-10K,1%,1/16W,CHIP,CS31002FB08',
 PART_NUMBER='CS31002FB08',
 VALUE='10K',
 PRIM_FILE='./archive_libs/logical/q_res/chips/chips.prt';

PART_NAME
 R18 'Q_RES_0402LF-10K,1%,1/16W,CHIP,CS31002FB08':;

SECTION_NUMBER 1
 '@T6G_MB_LIB.T6G(SCH_1):PAGE82_I126@PURE_QUANTA.Q_RES(CHIPS)':
 C_PATH='@t6g_mb_lib.t6g(sch_1):page82_i126@pure_quanta.q_res(chips)',
 P_PATH='@t6g_mb_lib.t6g(sch_1):page83_i126@pure_quanta.q_res(chips)',
 PATH='I126',
 DRAWING='@T6G_MB_LIB.T6G(SCH_1):PAGE82',
 BOM_COST='MEM',
 WATTAGE='1/16W',
 TOLERANCE='1%',
 MATERIAL='CHIP',
 PHYS_PAGE='83',
 XY='(-3100,5800)',
 ROT='0',
 VER='2',
 PACK_TYPE='0402LF',
 LOCATION='R18',
 CDS_LIB='pure_quanta',
 CDS_PART_NAME='Q_RES_0402LF-10K,1%,1/16W,CHIP,CS31002FB08',
 PART_NUMBER='CS31002FB08',
 VALUE='10K',
 PRIM_FILE='./archive_libs/logical/q_res/chips/chips.prt';

PART_NAME
 R19 'Q_RES_0402LF-10K,1%,1/16W,CHIP,CS31002FB08':;

SECTION_NUMBER 1
 '@T6G_MB_LIB.T6G(SCH_1):PAGE82_I128@PURE_QUANTA.Q_RES(CHIPS)':
 C_PATH='@t6g_mb_lib.t6g(sch_1):page82_i128@pure_quanta.q_res(chips)',
 P_PATH='@t6g_mb_lib.t6g(sch_1):page83_i128@pure_quanta.q_res(chips)',
 PATH='I128',
 DRAWING='@T6G_MB_LIB.T6G(SCH_1):PAGE82',
 BOM_COST='MEM',
 WATTAGE='1/16W',
 TOLERANCE='1%',
 MATERIAL='CHIP',
 PHYS_PAGE='83',
 XY='(-2875,5800)',
 ROT='0',
 VER='2',
 PACK_TYPE='0402LF',
 LOCATION='R19',
 CDS_LIB='pure_quanta',
 CDS_PART_NAME='Q_RES_0402LF-10K,1%,1/16W,CHIP,CS31002FB08',
 PART_NUMBER='CS31002FB08',
 VALUE='10K',
 PRIM_FILE='./archive_libs/logical/q_res/chips/chips.prt';

PART_NAME
 R20 'Q_RES_0402LF-10K,1%,1/16W,CHIP,CS31002FB08':;

SECTION_NUMBER 1
 '@T6G_MB_LIB.T6G(SCH_1):PAGE76_I115@PURE_QUANTA.Q_RES(CHIPS)':
 C_PATH='@t6g_mb_lib.t6g(sch_1):page76_i115@pure_quanta.q_res(chips)',
 P_PATH='@t6g_mb_lib.t6g(sch_1):page77_i115@pure_quanta.q_res(chips)',
 PATH='I115',
 DRAWING='@T6G_MB_LIB.T6G(SCH_1):PAGE76',
 WATTAGE='1/16W',
 TOLERANCE='1%',
 MATERIAL='CHIP',
 PHYS_PAGE='77',
 XY='(-2225,5625)',
 ROT='2',
 VER='2',
 PACK_TYPE='0402LF',
 LOCATION='R20',
 CDS_LIB='pure_quanta',
 CDS_PART_NAME='Q_RES_0402LF-10K,1%,1/16W,CHIP,CS31002FB08',
 PART_NUMBER='CS31002FB08',
 VALUE='10K',
 PRIM_FILE='./archive_libs/logical/q_res/chips/chips.prt';

PART_NAME
 R21 'Q_RES_0402LF-1K,1%,1/16W,EMPTY,CS21002FB06':;

SECTION_NUMBER 1
 '@T6G_MB_LIB.T6G(SCH_1):PAGE76_I116@PURE_QUANTA.Q_RES(CHIPS)':
 C_PATH='@t6g_mb_lib.t6g(sch_1):page76_i116@pure_quanta.q_res(chips)',
 P_PATH='@t6g_mb_lib.t6g(sch_1):page77_i116@pure_quanta.q_res(chips)',
 PATH='I116',
 DRAWING='@T6G_MB_LIB.T6G(SCH_1):PAGE76',
 WATTAGE='1/16W',
 TOLERANCE='1%',
 MATERIAL='EMPTY',
 PHYS_PAGE='77',
 XY='(-1875,5625)',
 ROT='2',
 VER='2',
 PACK_TYPE='0402LF',
 LOCATION='R21',
 CDS_LIB='pure_quanta',
 CDS_PART_NAME='Q_RES_0402LF-1K,1%,1/16W,EMPTY,CS21002FB06',
 PART_NUMBER='CS21002FB06',
 VALUE='1K',
 PRIM_FILE='./archive_libs/logical/q_res/chips/chips.prt';

PART_NAME
 R22 'Q_RES_0402LF-100,1%,1/16W,CHIP,CS11002FB07':;

SECTION_NUMBER 1
 '@T6G_MB_LIB.T6G(SCH_1):PAGE144_I54@PURE_QUANTA.Q_RES(CHIPS)':
 C_PATH='@t6g_mb_lib.t6g(sch_1):page144_i54@pure_quanta.q_res(chips)',
 P_PATH='@t6g_mb_lib.t6g(sch_1):page167_i54@pure_quanta.q_res(chips)',
 PATH='I54',
 DRAWING='@T6G_MB_LIB.T6G(SCH_1):PAGE144',
 WATTAGE='1/16W',
 TOLERANCE='1%',
 MATERIAL='CHIP',
 PHYS_PAGE='167',
 XY='(-4850,5725)',
 ROT='0',
 VER='2',
 PACK_TYPE='0402LF',
 LOCATION='R22',
 CDS_LIB='pure_quanta',
 CDS_PART_NAME='Q_RES_0402LF-100,1%,1/16W,CHIP,CS11002FB07',
 PART_NUMBER='CS11002FB07',
 VALUE='100',
 PRIM_FILE='./archive_libs/logical/q_res/chips/chips.prt';

PART_NAME
 R23 'Q_RES_0402LF-33,5%,1/16W,CHIP,CS03302JB10':;

SECTION_NUMBER 1
 '@T6G_MB_LIB.T6G(SCH_1):PAGE79_I23@PURE_QUANTA.Q_RES(CHIPS)':
 C_PATH='@t6g_mb_lib.t6g(sch_1):page79_i23@pure_quanta.q_res(chips)',
 P_PATH='@t6g_mb_lib.t6g(sch_1):page80_i23@pure_quanta.q_res(chips)',
 PATH='I23',
 DRAWING='@T6G_MB_LIB.T6G(SCH_1):PAGE79',
 BOM_COST='MEM',
 WATTAGE='1/16W',
 TOLERANCE='5%',
 MATERIAL='CHIP',
 PHYS_PAGE='80',
 XY='(-6850,3400)',
 ROT='2',
 VER='1',
 PACK_TYPE='0402LF',
 LOCATION='R23',
 CDS_LIB='pure_quanta',
 CDS_PART_NAME='Q_RES_0402LF-33,5%,1/16W,CHIP,CS03302JB10',
 PART_NUMBER='CS03302JB10',
 VALUE='33',
 PRIM_FILE='./archive_libs/logical/q_res/chips/chips.prt';

PART_NAME
 R24 'Q_RES_0402LF-4.7K,5%,1/16W,EMPTY,CS24702JB10':;

SECTION_NUMBER 1
 '@T6G_MB_LIB.T6G(SCH_1):PAGE361_I113@PURE_QUANTA.Q_RES(CHIPS)':
 C_PATH='@t6g_mb_lib.t6g(sch_1):page361_i113@pure_quanta.q_res(chips)',
 P_PATH='@t6g_mb_lib.t6g(sch_1):page238_i113@pure_quanta.q_res(chips)',
 PATH='I113',
 DRAWING='@T6G_MB_LIB.T6G(SCH_1):PAGE361',
 WATTAGE='1/16W',
 TOLERANCE='5%',
 MATERIAL='EMPTY',
 PHYS_PAGE='238',
 XY='(-1900,1350)',
 ROT='0',
 VER='2',
 PACK_TYPE='0402LF',
 LOCATION='R24',
 CDS_LIB='pure_quanta',
 CDS_PART_NAME='Q_RES_0402LF-4.7K,5%,1/16W,EMPTY,CS24702JB10',
 PART_NUMBER='CS24702JB10',
 VALUE='4.7K',
 PRIM_FILE='./archive_libs/logical/q_res/chips/chips.prt';

PART_NAME
 R25 'Q_RES_0402LF-10K,1%,1/16W,CHIP,CS31002FB08':;

SECTION_NUMBER 1
 '@T6G_MB_LIB.T6G(SCH_1):PAGE82_I97@PURE_QUANTA.Q_RES(CHIPS)':
 C_PATH='@t6g_mb_lib.t6g(sch_1):page82_i97@pure_quanta.q_res(chips)',
 P_PATH='@t6g_mb_lib.t6g(sch_1):page83_i97@pure_quanta.q_res(chips)',
 PATH='I97',
 DRAWING='@T6G_MB_LIB.T6G(SCH_1):PAGE82',
 BOM_COST='MEM',
 WATTAGE='1/16W',
 TOLERANCE='1%',
 MATERIAL='CHIP',
 PHYS_PAGE='83',
 XY='(-3075,3250)',
 ROT='0',
 VER='2',
 PACK_TYPE='0402LF',
 LOCATION='R25',
 CDS_LIB='pure_quanta',
 CDS_PART_NAME='Q_RES_0402LF-10K,1%,1/16W,CHIP,CS31002FB08',
 PART_NUMBER='CS31002FB08',
 VALUE='10K',
 PRIM_FILE='./archive_libs/logical/q_res/chips/chips.prt';

PART_NAME
 R26 'Q_RES_0402LF-4.7K,5%,1/16W,EMPTY,CS24702JB10':;

SECTION_NUMBER 1
 '@T6G_MB_LIB.T6G(SCH_1):PAGE361_I95@PURE_QUANTA.Q_RES(CHIPS)':
 C_PATH='@t6g_mb_lib.t6g(sch_1):page361_i95@pure_quanta.q_res(chips)',
 P_PATH='@t6g_mb_lib.t6g(sch_1):page238_i95@pure_quanta.q_res(chips)',
 PATH='I95',
 DRAWING='@T6G_MB_LIB.T6G(SCH_1):PAGE361',
 WATTAGE='1/16W',
 TOLERANCE='5%',
 MATERIAL='EMPTY',
 PHYS_PAGE='238',
 XY='(-2025,3650)',
 ROT='2',
 VER='2',
 PACK_TYPE='0402LF',
 LOCATION='R26',
 CDS_LIB='pure_quanta',
 CDS_PART_NAME='Q_RES_0402LF-4.7K,5%,1/16W,EMPTY,CS24702JB10',
 PART_NUMBER='CS24702JB10',
 VALUE='4.7K',
 PRIM_FILE='./archive_libs/logical/q_res/chips/chips.prt';

PART_NAME
 R27 'Q_RES_0402LF-0,5%,1/16W,CHIP,CS00002JB13':;

SECTION_NUMBER 1
 '@T6G_MB_LIB.T6G(SCH_1):PAGE28_I206@PURE_QUANTA.Q_RES(CHIPS)':
 C_PATH='@t6g_mb_lib.t6g(sch_1):page28_i206@pure_quanta.q_res(chips)',
 P_PATH='@t6g_mb_lib.t6g(sch_1):page28_i206@pure_quanta.q_res(chips)',
 PATH='I206',
 DRAWING='@T6G_MB_LIB.T6G(SCH_1):PAGE28',
 WATTAGE='1/16W',
 TOLERANCE='5%',
 MATERIAL='CHIP',
 PHYS_PAGE='28',
 XY='(-6850,11125)',
 ROT='2',
 VER='1',
 PACK_TYPE='0402LF',
 LOCATION='R27',
 CDS_LIB='pure_quanta',
 CDS_PART_NAME='Q_RES_0402LF-0,5%,1/16W,CHIP,CS00002JB13',
 PART_NUMBER='CS00002JB13',
 VALUE='0',
 PRIM_FILE='./archive_libs/logical/q_res/chips/chips.prt';

PART_NAME
 R28 'Q_RES_0402LF-0,5%,1/16W,CHIP,CS00002JB13':;

SECTION_NUMBER 1
 '@T6G_MB_LIB.T6G(SCH_1):PAGE28_I207@PURE_QUANTA.Q_RES(CHIPS)':
 C_PATH='@t6g_mb_lib.t6g(sch_1):page28_i207@pure_quanta.q_res(chips)',
 P_PATH='@t6g_mb_lib.t6g(sch_1):page28_i207@pure_quanta.q_res(chips)',
 PATH='I207',
 DRAWING='@T6G_MB_LIB.T6G(SCH_1):PAGE28',
 WATTAGE='1/16W',
 TOLERANCE='5%',
 MATERIAL='CHIP',
 PHYS_PAGE='28',
 XY='(-6850,11075)',
 ROT='2',
 VER='1',
 PACK_TYPE='0402LF',
 LOCATION='R28',
 CDS_LIB='pure_quanta',
 CDS_PART_NAME='Q_RES_0402LF-0,5%,1/16W,CHIP,CS00002JB13',
 PART_NUMBER='CS00002JB13',
 VALUE='0',
 PRIM_FILE='./archive_libs/logical/q_res/chips/chips.prt';

PART_NAME
 R29 'Q_RES_0402LF-0,5%,1/16W,CHIP,CS00002JB13':;

SECTION_NUMBER 1
 '@T6G_MB_LIB.T6G(SCH_1):PAGE28_I208@PURE_QUANTA.Q_RES(CHIPS)':
 C_PATH='@t6g_mb_lib.t6g(sch_1):page28_i208@pure_quanta.q_res(chips)',
 P_PATH='@t6g_mb_lib.t6g(sch_1):page28_i208@pure_quanta.q_res(chips)',
 PATH='I208',
 DRAWING='@T6G_MB_LIB.T6G(SCH_1):PAGE28',
 WATTAGE='1/16W',
 TOLERANCE='5%',
 MATERIAL='CHIP',
 PHYS_PAGE='28',
 XY='(-6850,11025)',
 ROT='2',
 VER='1',
 PACK_TYPE='0402LF',
 LOCATION='R29',
 CDS_LIB='pure_quanta',
 CDS_PART_NAME='Q_RES_0402LF-0,5%,1/16W,CHIP,CS00002JB13',
 PART_NUMBER='CS00002JB13',
 VALUE='0',
 PRIM_FILE='./archive_libs/logical/q_res/chips/chips.prt';

PART_NAME
 R30 'Q_RES_0402LF-0,5%,1/16W,CHIP,CS00002JB13':;

SECTION_NUMBER 1
 '@T6G_MB_LIB.T6G(SCH_1):PAGE28_I209@PURE_QUANTA.Q_RES(CHIPS)':
 C_PATH='@t6g_mb_lib.t6g(sch_1):page28_i209@pure_quanta.q_res(chips)',
 P_PATH='@t6g_mb_lib.t6g(sch_1):page28_i209@pure_quanta.q_res(chips)',
 PATH='I209',
 DRAWING='@T6G_MB_LIB.T6G(SCH_1):PAGE28',
 WATTAGE='1/16W',
 TOLERANCE='5%',
 MATERIAL='CHIP',
 PHYS_PAGE='28',
 XY='(-6850,10975)',
 ROT='2',
 VER='1',
 PACK_TYPE='0402LF',
 LOCATION='R30',
 CDS_LIB='pure_quanta',
 CDS_PART_NAME='Q_RES_0402LF-0,5%,1/16W,CHIP,CS00002JB13',
 PART_NUMBER='CS00002JB13',
 VALUE='0',
 PRIM_FILE='./archive_libs/logical/q_res/chips/chips.prt';

PART_NAME
 R31 'Q_RES_0402LF-4.7K,1%,1/16W,EMPTY,CS24702FB06':;

SECTION_NUMBER 1
 '@T6G_MB_LIB.T6G(SCH_1):PAGE335_I3@PURE_QUANTA.Q_RES(CHIPS)':
 C_PATH='@t6g_mb_lib.t6g(sch_1):page335_i3@pure_quanta.q_res(chips)',
 P_PATH='@t6g_mb_lib.t6g(sch_1):page131_i3@pure_quanta.q_res(chips)',
 PATH='I3',
 DRAWING='@T6G_MB_LIB.T6G(SCH_1):PAGE335',
 WATTAGE='1/16W',
 TOLERANCE='1%',
 MATERIAL='EMPTY',
 PHYS_PAGE='131',
 XY='(-4300,2250)',
 ROT='0',
 VER='2',
 PACK_TYPE='0402LF',
 LOCATION='R31',
 CDS_LIB='pure_quanta',
 CDS_PART_NAME='Q_RES_0402LF-4.7K,1%,1/16W,EMPTY,CS24702FB06',
 PART_NUMBER='CS24702FB06',
 VALUE='4.7K',
 PRIM_FILE='./archive_libs/logical/q_res/chips/chips.prt';

PART_NAME
 R32 'Q_RES_0402LF-4.7K,1%,1/16W,CHIP,CS24702FB06':;

SECTION_NUMBER 1
 '@T6G_MB_LIB.T6G(SCH_1):PAGE335_I2@PURE_QUANTA.Q_RES(CHIPS)':
 C_PATH='@t6g_mb_lib.t6g(sch_1):page335_i2@pure_quanta.q_res(chips)',
 P_PATH='@t6g_mb_lib.t6g(sch_1):page131_i2@pure_quanta.q_res(chips)',
 PATH='I2',
 DRAWING='@T6G_MB_LIB.T6G(SCH_1):PAGE335',
 WATTAGE='1/16W',
 TOLERANCE='1%',
 MATERIAL='CHIP',
 PHYS_PAGE='131',
 XY='(-4300,1725)',
 ROT='0',
 VER='2',
 PACK_TYPE='0402LF',
 LOCATION='R32',
 CDS_LIB='pure_quanta',
 CDS_PART_NAME='Q_RES_0402LF-4.7K,1%,1/16W,CHIP,CS24702FB06',
 PART_NUMBER='CS24702FB06',
 VALUE='4.7K',
 PRIM_FILE='./archive_libs/logical/q_res/chips/chips.prt';

PART_NAME
 R33 'Q_RES_0402LF-4.7K,1%,1/16W,EMPTY,CS24702FB06':;

SECTION_NUMBER 1
 '@T6G_MB_LIB.T6G(SCH_1):PAGE335_I17@PURE_QUANTA.Q_RES(CHIPS)':
 C_PATH='@t6g_mb_lib.t6g(sch_1):page335_i17@pure_quanta.q_res(chips)',
 P_PATH='@t6g_mb_lib.t6g(sch_1):page131_i17@pure_quanta.q_res(chips)',
 PATH='I17',
 DRAWING='@T6G_MB_LIB.T6G(SCH_1):PAGE335',
 WATTAGE='1/16W',
 TOLERANCE='1%',
 MATERIAL='EMPTY',
 PHYS_PAGE='131',
 XY='(-3825,2250)',
 ROT='0',
 VER='2',
 PACK_TYPE='0402LF',
 LOCATION='R33',
 CDS_LIB='pure_quanta',
 CDS_PART_NAME='Q_RES_0402LF-4.7K,1%,1/16W,EMPTY,CS24702FB06',
 PART_NUMBER='CS24702FB06',
 VALUE='4.7K',
 PRIM_FILE='./archive_libs/logical/q_res/chips/chips.prt';

PART_NAME
 R34 'Q_RES_0402LF-4.7K,1%,1/16W,CHIP,CS24702FB06':;

SECTION_NUMBER 1
 '@T6G_MB_LIB.T6G(SCH_1):PAGE335_I12@PURE_QUANTA.Q_RES(CHIPS)':
 C_PATH='@t6g_mb_lib.t6g(sch_1):page335_i12@pure_quanta.q_res(chips)',
 P_PATH='@t6g_mb_lib.t6g(sch_1):page131_i12@pure_quanta.q_res(chips)',
 PATH='I12',
 DRAWING='@T6G_MB_LIB.T6G(SCH_1):PAGE335',
 WATTAGE='1/16W',
 TOLERANCE='1%',
 MATERIAL='CHIP',
 PHYS_PAGE='131',
 XY='(-3825,1725)',
 ROT='0',
 VER='2',
 PACK_TYPE='0402LF',
 LOCATION='R34',
 CDS_LIB='pure_quanta',
 CDS_PART_NAME='Q_RES_0402LF-4.7K,1%,1/16W,CHIP,CS24702FB06',
 PART_NUMBER='CS24702FB06',
 VALUE='4.7K',
 PRIM_FILE='./archive_libs/logical/q_res/chips/chips.prt';

PART_NAME
 R35 'Q_RES_0402LF-10K,1%,1/16W,CHIP,CS31002FB08':
 ROOM='';

SECTION_NUMBER 1
 '@T6G_MB_LIB.T6G(SCH_1):PAGE91_I129@PURE_QUANTA.Q_RES(CHIPS)':
 C_PATH='@t6g_mb_lib.t6g(sch_1):page91_i129@pure_quanta.q_res(chips)',
 P_PATH='@t6g_mb_lib.t6g(sch_1):page92_i129@pure_quanta.q_res(chips)',
 PATH='I129',
 DRAWING='@T6G_MB_LIB.T6G(SCH_1):PAGE91',
 SEC_TYPE='0402LF',
 BOM_COST='MEM',
 WATTAGE='1/16W',
 TOLERANCE='1%',
 MATERIAL='CHIP',
 PHYS_PAGE='92',
 XY='(-6025,1200)',
 ROT='0',
 VER='2',
 PACK_TYPE='0402LF',
 LOCATION='R35',
 SEC='1',
 CDS_LIB='pure_quanta',
 CDS_PART_NAME='Q_RES_0402LF-10K,1%,1/16W,CHIP,CS31002FB08',
 ROOM='',
 PART_NUMBER='CS31002FB08',
 VALUE='10K',
 PRIM_FILE='./archive_libs/logical/q_res/chips/chips.prt';

PART_NAME
 R36 'Q_RES_0402LF-10K,1%,1/16W,CHIP,CS31002FB08':;

SECTION_NUMBER 1
 '@T6G_MB_LIB.T6G(SCH_1):PAGE97_I129@PURE_QUANTA.Q_RES(CHIPS)':
 C_PATH='@t6g_mb_lib.t6g(sch_1):page97_i129@pure_quanta.q_res(chips)',
 P_PATH='@t6g_mb_lib.t6g(sch_1):page98_i129@pure_quanta.q_res(chips)',
 PATH='I129',
 DRAWING='@T6G_MB_LIB.T6G(SCH_1):PAGE97',
 SEC_TYPE='0402LF',
 BOM_COST='MEM',
 WATTAGE='1/16W',
 TOLERANCE='1%',
 MATERIAL='CHIP',
 PHYS_PAGE='98',
 XY='(-6125,1300)',
 ROT='0',
 VER='2',
 PACK_TYPE='0402LF',
 LOCATION='R36',
 SEC='1',
 CDS_LIB='pure_quanta',
 CDS_PART_NAME='Q_RES_0402LF-10K,1%,1/16W,CHIP,CS31002FB08',
 PART_NUMBER='CS31002FB08',
 VALUE='10K',
 PRIM_FILE='./archive_libs/logical/q_res/chips/chips.prt';

PART_NAME
 R37 'Q_RES_0402LF-10K,1%,1/16W,CHIP,CS31002FB08':;

SECTION_NUMBER 1
 '@T6G_MB_LIB.T6G(SCH_1):PAGE103_I129@PURE_QUANTA.Q_RES(CHIPS)':
 C_PATH='@t6g_mb_lib.t6g(sch_1):page103_i129@pure_quanta.q_res(chips)',
 P_PATH='@t6g_mb_lib.t6g(sch_1):page104_i129@pure_quanta.q_res(chips)',
 PATH='I129',
 DRAWING='@T6G_MB_LIB.T6G(SCH_1):PAGE103',
 SEC_TYPE='0402LF',
 BOM_COST='MEM',
 WATTAGE='1/16W',
 TOLERANCE='1%',
 MATERIAL='CHIP',
 PHYS_PAGE='104',
 XY='(-6200,1125)',
 ROT='0',
 VER='2',
 PACK_TYPE='0402LF',
 LOCATION='R37',
 SEC='1',
 CDS_LIB='pure_quanta',
 CDS_PART_NAME='Q_RES_0402LF-10K,1%,1/16W,CHIP,CS31002FB08',
 PART_NUMBER='CS31002FB08',
 VALUE='10K',
 PRIM_FILE='./archive_libs/logical/q_res/chips/chips.prt';

PART_NAME
 R38 'Q_RES_0402LF-0,5%,1/16W,CHIP,CS00002JB13':;

SECTION_NUMBER 1
 '@T6G_MB_LIB.T6G(SCH_1):PAGE335_I59@PURE_QUANTA.Q_RES(CHIPS)':
 C_PATH='@t6g_mb_lib.t6g(sch_1):page335_i59@pure_quanta.q_res(chips)',
 P_PATH='@t6g_mb_lib.t6g(sch_1):page131_i59@pure_quanta.q_res(chips)',
 PATH='I59',
 DRAWING='@T6G_MB_LIB.T6G(SCH_1):PAGE335',
 WATTAGE='1/16W',
 TOLERANCE='5%',
 MATERIAL='CHIP',
 PHYS_PAGE='131',
 XY='(-2875,7050)',
 ROT='0',
 VER='1',
 PACK_TYPE='0402LF',
 LOCATION='R38',
 CDS_LIB='pure_quanta',
 CDS_PART_NAME='Q_RES_0402LF-0,5%,1/16W,CHIP,CS00002JB13',
 PART_NUMBER='CS00002JB13',
 VALUE='0',
 PRIM_FILE='./archive_libs/logical/q_res/chips/chips.prt';

PART_NAME
 R39 'Q_RES_0402LF-0,5%,1/16W,CHIP,CS00002JB13':;

SECTION_NUMBER 1
 '@T6G_MB_LIB.T6G(SCH_1):PAGE335_I57@PURE_QUANTA.Q_RES(CHIPS)':
 C_PATH='@t6g_mb_lib.t6g(sch_1):page335_i57@pure_quanta.q_res(chips)',
 P_PATH='@t6g_mb_lib.t6g(sch_1):page131_i57@pure_quanta.q_res(chips)',
 PATH='I57',
 DRAWING='@T6G_MB_LIB.T6G(SCH_1):PAGE335',
 WATTAGE='1/16W',
 TOLERANCE='5%',
 MATERIAL='CHIP',
 PHYS_PAGE='131',
 XY='(-2875,6000)',
 ROT='0',
 VER='1',
 PACK_TYPE='0402LF',
 LOCATION='R39',
 CDS_LIB='pure_quanta',
 CDS_PART_NAME='Q_RES_0402LF-0,5%,1/16W,CHIP,CS00002JB13',
 PART_NUMBER='CS00002JB13',
 VALUE='0',
 PRIM_FILE='./archive_libs/logical/q_res/chips/chips.prt';

PART_NAME
 R40 'Q_RES_0402LF-0,5%,1/16W,CHIP,CS00002JB13':;

SECTION_NUMBER 1
 '@T6G_MB_LIB.T6G(SCH_1):PAGE335_I56@PURE_QUANTA.Q_RES(CHIPS)':
 C_PATH='@t6g_mb_lib.t6g(sch_1):page335_i56@pure_quanta.q_res(chips)',
 P_PATH='@t6g_mb_lib.t6g(sch_1):page131_i56@pure_quanta.q_res(chips)',
 PATH='I56',
 DRAWING='@T6G_MB_LIB.T6G(SCH_1):PAGE335',
 WATTAGE='1/16W',
 TOLERANCE='5%',
 MATERIAL='CHIP',
 PHYS_PAGE='131',
 XY='(-2875,5950)',
 ROT='0',
 VER='1',
 PACK_TYPE='0402LF',
 LOCATION='R40',
 CDS_LIB='pure_quanta',
 CDS_PART_NAME='Q_RES_0402LF-0,5%,1/16W,CHIP,CS00002JB13',
 PART_NUMBER='CS00002JB13',
 VALUE='0',
 PRIM_FILE='./archive_libs/logical/q_res/chips/chips.prt';

PART_NAME
 R41 'Q_RES_0402LF-0,5%,1/16W,CHIP,CS00002JB13':;

SECTION_NUMBER 1
 '@T6G_MB_LIB.T6G(SCH_1):PAGE335_I55@PURE_QUANTA.Q_RES(CHIPS)':
 C_PATH='@t6g_mb_lib.t6g(sch_1):page335_i55@pure_quanta.q_res(chips)',
 P_PATH='@t6g_mb_lib.t6g(sch_1):page131_i55@pure_quanta.q_res(chips)',
 PATH='I55',
 DRAWING='@T6G_MB_LIB.T6G(SCH_1):PAGE335',
 WATTAGE='1/16W',
 TOLERANCE='5%',
 MATERIAL='CHIP',
 PHYS_PAGE='131',
 XY='(-2875,5900)',
 ROT='0',
 VER='1',
 PACK_TYPE='0402LF',
 LOCATION='R41',
 CDS_LIB='pure_quanta',
 CDS_PART_NAME='Q_RES_0402LF-0,5%,1/16W,CHIP,CS00002JB13',
 PART_NUMBER='CS00002JB13',
 VALUE='0',
 PRIM_FILE='./archive_libs/logical/q_res/chips/chips.prt';

PART_NAME
 R42 'Q_RES_0402LF-0,5%,1/16W,CHIP,CS00002JB13':;

SECTION_NUMBER 1
 '@T6G_MB_LIB.T6G(SCH_1):PAGE335_I166@PURE_QUANTA.Q_RES(CHIPS)':
 C_PATH='@t6g_mb_lib.t6g(sch_1):page335_i166@pure_quanta.q_res(chips)',
 P_PATH='@t6g_mb_lib.t6g(sch_1):page131_i166@pure_quanta.q_res(chips)',
 PATH='I166',
 DRAWING='@T6G_MB_LIB.T6G(SCH_1):PAGE335',
 WATTAGE='1/16W',
 TOLERANCE='5%',
 MATERIAL='CHIP',
 PHYS_PAGE='131',
 XY='(1525,2750)',
 ROT='0',
 VER='1',
 PACK_TYPE='0402LF',
 LOCATION='R42',
 CDS_LIB='pure_quanta',
 CDS_PART_NAME='Q_RES_0402LF-0,5%,1/16W,CHIP,CS00002JB13',
 PART_NUMBER='CS00002JB13',
 VALUE='0',
 PRIM_FILE='./archive_libs/logical/q_res/chips/chips.prt';

PART_NAME
 R43 'Q_RES_0402LF-4.7K,5%,1/16W,EMPTY,CS24702JB10':;

SECTION_NUMBER 1
 '@T6G_MB_LIB.T6G(SCH_1):PAGE361_I93@PURE_QUANTA.Q_RES(CHIPS)':
 C_PATH='@t6g_mb_lib.t6g(sch_1):page361_i93@pure_quanta.q_res(chips)',
 P_PATH='@t6g_mb_lib.t6g(sch_1):page238_i93@pure_quanta.q_res(chips)',
 PATH='I93',
 DRAWING='@T6G_MB_LIB.T6G(SCH_1):PAGE361',
 WATTAGE='1/16W',
 TOLERANCE='5%',
 MATERIAL='EMPTY',
 PHYS_PAGE='238',
 XY='(-1925,3650)',
 ROT='0',
 VER='2',
 PACK_TYPE='0402LF',
 LOCATION='R43',
 CDS_LIB='pure_quanta',
 CDS_PART_NAME='Q_RES_0402LF-4.7K,5%,1/16W,EMPTY,CS24702JB10',
 PART_NUMBER='CS24702JB10',
 VALUE='4.7K',
 PRIM_FILE='./archive_libs/logical/q_res/chips/chips.prt';

PART_NAME
 R44 'Q_RES_0402LF-1K,1%,1/16W,CHIP,CS21002FB06':;

SECTION_NUMBER 1
 '@T6G_MB_LIB.T6G(SCH_1):PAGE361_I115@PURE_QUANTA.Q_RES(CHIPS)':
 C_PATH='@t6g_mb_lib.t6g(sch_1):page361_i115@pure_quanta.q_res(chips)',
 P_PATH='@t6g_mb_lib.t6g(sch_1):page238_i115@pure_quanta.q_res(chips)',
 PATH='I115',
 DRAWING='@T6G_MB_LIB.T6G(SCH_1):PAGE361',
 WATTAGE='1/16W',
 TOLERANCE='1%',
 MATERIAL='CHIP',
 PHYS_PAGE='238',
 XY='(-1075,750)',
 ROT='0',
 VER='2',
 PACK_TYPE='0402LF',
 LOCATION='R44',
 CDS_LIB='pure_quanta',
 CDS_PART_NAME='Q_RES_0402LF-1K,1%,1/16W,CHIP,CS21002FB06',
 PART_NUMBER='CS21002FB06',
 VALUE='1K',
 PRIM_FILE='./archive_libs/logical/q_res/chips/chips.prt';

PART_NAME
 R45 'Q_RES_0402LF-10K,1%,1/16W,CHIP,CS31002FB08':;

SECTION_NUMBER 1
 '@T6G_MB_LIB.T6G(SCH_1):PAGE337_I12@PURE_QUANTA.Q_RES(CHIPS)':
 C_PATH='@t6g_mb_lib.t6g(sch_1):page337_i12@pure_quanta.q_res(chips)',
 P_PATH='@t6g_mb_lib.t6g(sch_1):page133_i12@pure_quanta.q_res(chips)',
 PATH='I12',
 DRAWING='@T6G_MB_LIB.T6G(SCH_1):PAGE337',
 WATTAGE='1/16W',
 TOLERANCE='1%',
 MATERIAL='CHIP',
 PHYS_PAGE='133',
 XY='(-9400,4625)',
 ROT='0',
 VER='2',
 PACK_TYPE='0402LF',
 LOCATION='R45',
 CDS_LIB='pure_quanta',
 CDS_PART_NAME='Q_RES_0402LF-10K,1%,1/16W,CHIP,CS31002FB08',
 PART_NUMBER='CS31002FB08',
 VALUE='10K',
 PRIM_FILE='./archive_libs/logical/q_res/chips/chips.prt';

PART_NAME
 R46 'Q_RES_0402LF-0,5%,1/16W,CHIP,CS00002JB13':;

SECTION_NUMBER 1
 '@T6G_MB_LIB.T6G(SCH_1):PAGE335_I108@PURE_QUANTA.Q_RES(CHIPS)':
 C_PATH='@t6g_mb_lib.t6g(sch_1):page335_i108@pure_quanta.q_res(chips)',
 P_PATH='@t6g_mb_lib.t6g(sch_1):page131_i108@pure_quanta.q_res(chips)',
 PATH='I108',
 DRAWING='@T6G_MB_LIB.T6G(SCH_1):PAGE335',
 WATTAGE='1/16W',
 TOLERANCE='5%',
 MATERIAL='CHIP',
 PHYS_PAGE='131',
 XY='(1525,2700)',
 ROT='0',
 VER='1',
 PACK_TYPE='0402LF',
 LOCATION='R46',
 CDS_LIB='pure_quanta',
 CDS_PART_NAME='Q_RES_0402LF-0,5%,1/16W,CHIP,CS00002JB13',
 PART_NUMBER='CS00002JB13',
 VALUE='0',
 PRIM_FILE='./archive_libs/logical/q_res/chips/chips.prt';

PART_NAME
 R47 'Q_RES_0402LF-200,1%,1/16W,CHIP,CS12002FB06':;

SECTION_NUMBER 1
 '@T6G_MB_LIB.T6G(SCH_1):PAGE335_I171@PURE_QUANTA.Q_RES(CHIPS)':
 C_PATH='@t6g_mb_lib.t6g(sch_1):page335_i171@pure_quanta.q_res(chips)',
 P_PATH='@t6g_mb_lib.t6g(sch_1):page131_i171@pure_quanta.q_res(chips)',
 PATH='I171',
 DRAWING='@T6G_MB_LIB.T6G(SCH_1):PAGE335',
 SEC_TYPE='0402LF',
 WATTAGE='1/16W',
 TOLERANCE='1%',
 MATERIAL='CHIP',
 PHYS_PAGE='131',
 XY='(1775,6000)',
 ROT='0',
 VER='1',
 PACK_TYPE='0402LF',
 LOCATION='R47',
 SEC='1',
 CDS_LIB='pure_quanta',
 CDS_PART_NAME='Q_RES_0402LF-200,1%,1/16W,CHIP,CS12002FB06',
 PART_NUMBER='CS12002FB06',
 VALUE='200',
 PRIM_FILE='./archive_libs/logical/q_res/chips/chips.prt';

PART_NAME
 R48 'Q_RES_0402LF-200,1%,1/16W,CHIP,CS12002FB06':;

SECTION_NUMBER 1
 '@T6G_MB_LIB.T6G(SCH_1):PAGE335_I170@PURE_QUANTA.Q_RES(CHIPS)':
 C_PATH='@t6g_mb_lib.t6g(sch_1):page335_i170@pure_quanta.q_res(chips)',
 P_PATH='@t6g_mb_lib.t6g(sch_1):page131_i170@pure_quanta.q_res(chips)',
 PATH='I170',
 DRAWING='@T6G_MB_LIB.T6G(SCH_1):PAGE335',
 SEC_TYPE='0402LF',
 WATTAGE='1/16W',
 TOLERANCE='1%',
 MATERIAL='CHIP',
 PHYS_PAGE='131',
 XY='(1775,5950)',
 ROT='0',
 VER='1',
 PACK_TYPE='0402LF',
 LOCATION='R48',
 SEC='1',
 CDS_LIB='pure_quanta',
 CDS_PART_NAME='Q_RES_0402LF-200,1%,1/16W,CHIP,CS12002FB06',
 PART_NUMBER='CS12002FB06',
 VALUE='200',
 PRIM_FILE='./archive_libs/logical/q_res/chips/chips.prt';

PART_NAME
 R49 'Q_RES_0402LF-33,5%,1/16W,CHIP,CS03302JB10':;

SECTION_NUMBER 1
 '@T6G_MB_LIB.T6G(SCH_1):PAGE79_I46@PURE_QUANTA.Q_RES(CHIPS)':
 C_PATH='@t6g_mb_lib.t6g(sch_1):page79_i46@pure_quanta.q_res(chips)',
 P_PATH='@t6g_mb_lib.t6g(sch_1):page80_i46@pure_quanta.q_res(chips)',
 PATH='I46',
 DRAWING='@T6G_MB_LIB.T6G(SCH_1):PAGE79',
 BOM_COST='MEM',
 WATTAGE='1/16W',
 TOLERANCE='5%',
 MATERIAL='CHIP',
 PHYS_PAGE='80',
 XY='(-6850,4600)',
 ROT='2',
 VER='1',
 PACK_TYPE='0402LF',
 LOCATION='R49',
 CDS_LIB='pure_quanta',
 CDS_PART_NAME='Q_RES_0402LF-33,5%,1/16W,CHIP,CS03302JB10',
 PART_NUMBER='CS03302JB10',
 VALUE='33',
 PRIM_FILE='./archive_libs/logical/q_res/chips/chips.prt';

PART_NAME
 R50 'Q_RES_0402LF-33,5%,1/16W,CHIP,CS03302JB10':;

SECTION_NUMBER 1
 '@T6G_MB_LIB.T6G(SCH_1):PAGE79_I49@PURE_QUANTA.Q_RES(CHIPS)':
 C_PATH='@t6g_mb_lib.t6g(sch_1):page79_i49@pure_quanta.q_res(chips)',
 P_PATH='@t6g_mb_lib.t6g(sch_1):page80_i49@pure_quanta.q_res(chips)',
 PATH='I49',
 DRAWING='@T6G_MB_LIB.T6G(SCH_1):PAGE79',
 BOM_COST='MEM',
 WATTAGE='1/16W',
 TOLERANCE='5%',
 MATERIAL='CHIP',
 PHYS_PAGE='80',
 XY='(-6850,4750)',
 ROT='2',
 VER='1',
 PACK_TYPE='0402LF',
 LOCATION='R50',
 CDS_LIB='pure_quanta',
 CDS_PART_NAME='Q_RES_0402LF-33,5%,1/16W,CHIP,CS03302JB10',
 PART_NUMBER='CS03302JB10',
 VALUE='33',
 PRIM_FILE='./archive_libs/logical/q_res/chips/chips.prt';

PART_NAME
 R51 'Q_RES_0402LF-0,5%,1/16W,CHIP,CS00002JB13':;

SECTION_NUMBER 1
 '@T6G_MB_LIB.T6G(SCH_1):PAGE79_I83@PURE_QUANTA.Q_RES(CHIPS)':
 C_PATH='@t6g_mb_lib.t6g(sch_1):page79_i83@pure_quanta.q_res(chips)',
 P_PATH='@t6g_mb_lib.t6g(sch_1):page80_i83@pure_quanta.q_res(chips)',
 PATH='I83',
 DRAWING='@T6G_MB_LIB.T6G(SCH_1):PAGE79',
 BOM_COST='MEM',
 WATTAGE='1/16W',
 TOLERANCE='5%',
 MATERIAL='CHIP',
 PHYS_PAGE='80',
 XY='(-2775,4950)',
 ROT='2',
 VER='1',
 PACK_TYPE='0402LF',
 LOCATION='R51',
 CDS_LIB='pure_quanta',
 CDS_PART_NAME='Q_RES_0402LF-0,5%,1/16W,CHIP,CS00002JB13',
 PART_NUMBER='CS00002JB13',
 VALUE='0',
 PRIM_FILE='./archive_libs/logical/q_res/chips/chips.prt';

PART_NAME
 R52 'Q_RES_0402LF-10K,1%,1/16W,EMPTY,CS31002FB08':;

SECTION_NUMBER 1
 '@T6G_MB_LIB.T6G(SCH_1):PAGE361_I103@PURE_QUANTA.Q_RES(CHIPS)':
 C_PATH='@t6g_mb_lib.t6g(sch_1):page361_i103@pure_quanta.q_res(chips)',
 P_PATH='@t6g_mb_lib.t6g(sch_1):page238_i103@pure_quanta.q_res(chips)',
 PATH='I103',
 DRAWING='@T6G_MB_LIB.T6G(SCH_1):PAGE361',
 WATTAGE='1/16W',
 TOLERANCE='1%',
 MATERIAL='EMPTY',
 PHYS_PAGE='238',
 XY='(1525,1375)',
 ROT='0',
 VER='2',
 PACK_TYPE='0402LF',
 LOCATION='R52',
 CDS_LIB='pure_quanta',
 CDS_PART_NAME='Q_RES_0402LF-10K,1%,1/16W,EMPTY,CS31002FB08',
 PART_NUMBER='CS31002FB08',
 VALUE='10K',
 PRIM_FILE='./archive_libs/logical/q_res/chips/chips.prt';

PART_NAME
 R53 'Q_RES_0402LF-4.7K,1%,1/16W,CHIP,CS24702FB06':;

SECTION_NUMBER 1
 '@T6G_MB_LIB.T6G(SCH_1):PAGE337_I42@PURE_QUANTA.Q_RES(CHIPS)':
 C_PATH='@t6g_mb_lib.t6g(sch_1):page337_i42@pure_quanta.q_res(chips)',
 P_PATH='@t6g_mb_lib.t6g(sch_1):page133_i42@pure_quanta.q_res(chips)',
 PATH='I42',
 DRAWING='@T6G_MB_LIB.T6G(SCH_1):PAGE337',
 WATTAGE='1/16W',
 TOLERANCE='1%',
 MATERIAL='CHIP',
 PHYS_PAGE='133',
 XY='(-5875,6100)',
 ROT='0',
 VER='2',
 PACK_TYPE='0402LF',
 LOCATION='R53',
 CDS_LIB='pure_quanta',
 CDS_PART_NAME='Q_RES_0402LF-4.7K,1%,1/16W,CHIP,CS24702FB06',
 PART_NUMBER='CS24702FB06',
 VALUE='4.7K',
 PRIM_FILE='./archive_libs/logical/q_res/chips/chips.prt';

PART_NAME
 R54 'Q_RES_0402LF-1K,1%,1/16W,CHIP,CS21002FB06':;

SECTION_NUMBER 1
 '@T6G_MB_LIB.T6G(SCH_1):PAGE361_I107@PURE_QUANTA.Q_RES(CHIPS)':
 C_PATH='@t6g_mb_lib.t6g(sch_1):page361_i107@pure_quanta.q_res(chips)',
 P_PATH='@t6g_mb_lib.t6g(sch_1):page238_i107@pure_quanta.q_res(chips)',
 PATH='I107',
 DRAWING='@T6G_MB_LIB.T6G(SCH_1):PAGE361',
 WATTAGE='1/16W',
 TOLERANCE='1%',
 MATERIAL='CHIP',
 PHYS_PAGE='238',
 XY='(1525,825)',
 ROT='0',
 VER='2',
 PACK_TYPE='0402LF',
 LOCATION='R54',
 CDS_LIB='pure_quanta',
 CDS_PART_NAME='Q_RES_0402LF-1K,1%,1/16W,CHIP,CS21002FB06',
 PART_NUMBER='CS21002FB06',
 VALUE='1K',
 PRIM_FILE='./archive_libs/logical/q_res/chips/chips.prt';

PART_NAME
 R55 'Q_RES_0402LF-33.2,1%,1/16W,CHIP,CS03322FB03':;

SECTION_NUMBER 1
 '@T6G_MB_LIB.T6G(SCH_1):PAGE252_I73@PURE_QUANTA.Q_RES(CHIPS)':
 C_PATH='@t6g_mb_lib.t6g(sch_1):page252_i73@pure_quanta.q_res(chips)',
 P_PATH='@t6g_mb_lib.t6g(sch_1):page250_i73@pure_quanta.q_res(chips)',
 PATH='I73',
 DRAWING='@T6G_MB_LIB.T6G(SCH_1):PAGE252',
 WATTAGE='1/16W',
 TOLERANCE='1%',
 MATERIAL='CHIP',
 PHYS_PAGE='250',
 XY='(-2525,4825)',
 ROT='2',
 VER='1',
 PACK_TYPE='0402LF',
 LOCATION='R55',
 CDS_LIB='pure_quanta',
 CDS_PART_NAME='Q_RES_0402LF-33.2,1%,1/16W,CHIP,CS03322FB03',
 PART_NUMBER='CS03322FB03',
 VALUE='33.2',
 PRIM_FILE='./archive_libs/logical/q_res/chips/chips.prt';

PART_NAME
 R56 'Q_RES_0402LF-0,5%,1/16W,CHIP,CS00002JB13':;

SECTION_NUMBER 1
 '@T6G_MB_LIB.T6G(SCH_1):PAGE79_I82@PURE_QUANTA.Q_RES(CHIPS)':
 C_PATH='@t6g_mb_lib.t6g(sch_1):page79_i82@pure_quanta.q_res(chips)',
 P_PATH='@t6g_mb_lib.t6g(sch_1):page80_i82@pure_quanta.q_res(chips)',
 PATH='I82',
 DRAWING='@T6G_MB_LIB.T6G(SCH_1):PAGE79',
 BOM_COST='MEM',
 WATTAGE='1/16W',
 TOLERANCE='5%',
 MATERIAL='CHIP',
 PHYS_PAGE='80',
 XY='(-2775,4900)',
 ROT='2',
 VER='1',
 PACK_TYPE='0402LF',
 LOCATION='R56',
 CDS_LIB='pure_quanta',
 CDS_PART_NAME='Q_RES_0402LF-0,5%,1/16W,CHIP,CS00002JB13',
 PART_NUMBER='CS00002JB13',
 VALUE='0',
 PRIM_FILE='./archive_libs/logical/q_res/chips/chips.prt';

PART_NAME
 R57 'Q_RES_0402LF-0,5%,1/16W,CHIP,CS00002JB13':;

SECTION_NUMBER 1
 '@T6G_MB_LIB.T6G(SCH_1):PAGE80_I113@PURE_QUANTA.Q_RES(CHIPS)':
 C_PATH='@t6g_mb_lib.t6g(sch_1):page80_i113@pure_quanta.q_res(chips)',
 P_PATH='@t6g_mb_lib.t6g(sch_1):page81_i113@pure_quanta.q_res(chips)',
 PATH='I113',
 DRAWING='@T6G_MB_LIB.T6G(SCH_1):PAGE80',
 BOM_COST='MEM',
 WATTAGE='1/16W',
 TOLERANCE='5%',
 MATERIAL='CHIP',
 PHYS_PAGE='81',
 XY='(-6425,5125)',
 ROT='0',
 VER='1',
 PACK_TYPE='0402LF',
 LOCATION='R57',
 CDS_LIB='pure_quanta',
 CDS_PART_NAME='Q_RES_0402LF-0,5%,1/16W,CHIP,CS00002JB13',
 PART_NUMBER='CS00002JB13',
 VALUE='0',
 PRIM_FILE='./archive_libs/logical/q_res/chips/chips.prt';

PART_NAME
 R58 'Q_RES_0402LF-33,5%,1/16W,CHIP,CS03302JB10':;

SECTION_NUMBER 1
 '@T6G_MB_LIB.T6G(SCH_1):PAGE79_I44@PURE_QUANTA.Q_RES(CHIPS)':
 C_PATH='@t6g_mb_lib.t6g(sch_1):page79_i44@pure_quanta.q_res(chips)',
 P_PATH='@t6g_mb_lib.t6g(sch_1):page80_i44@pure_quanta.q_res(chips)',
 PATH='I44',
 DRAWING='@T6G_MB_LIB.T6G(SCH_1):PAGE79',
 BOM_COST='MEM',
 WATTAGE='1/16W',
 TOLERANCE='5%',
 MATERIAL='CHIP',
 PHYS_PAGE='80',
 XY='(-6850,4450)',
 ROT='2',
 VER='1',
 PACK_TYPE='0402LF',
 LOCATION='R58',
 CDS_LIB='pure_quanta',
 CDS_PART_NAME='Q_RES_0402LF-33,5%,1/16W,CHIP,CS03302JB10',
 PART_NUMBER='CS03302JB10',
 VALUE='33',
 PRIM_FILE='./archive_libs/logical/q_res/chips/chips.prt';

PART_NAME
 R59 'Q_RES_0402LF-22,1%,1/16W,CHIP,CS02202FB02':;

SECTION_NUMBER 1
 '@T6G_MB_LIB.T6G(SCH_1):PAGE336_I99@PURE_QUANTA.Q_RES(CHIPS)':
 C_PATH='@t6g_mb_lib.t6g(sch_1):page336_i99@pure_quanta.q_res(chips)',
 P_PATH='@t6g_mb_lib.t6g(sch_1):page132_i99@pure_quanta.q_res(chips)',
 PATH='I99',
 DRAWING='@T6G_MB_LIB.T6G(SCH_1):PAGE336',
 WATTAGE='1/16W',
 TOLERANCE='1%',
 MATERIAL='CHIP',
 PHYS_PAGE='132',
 XY='(1450,6750)',
 ROT='0',
 VER='1',
 PACK_TYPE='0402LF',
 LOCATION='R59',
 CDS_LIB='pure_quanta',
 CDS_PART_NAME='Q_RES_0402LF-22,1%,1/16W,CHIP,CS02202FB02',
 PART_NUMBER='CS02202FB02',
 VALUE='22',
 PRIM_FILE='./archive_libs/logical/q_res/chips/chips.prt';

PART_NAME
 R60 'Q_RES_0402LF-10K,1%,1/16W,EMPTY,CS31002FB08':;

SECTION_NUMBER 1
 '@T6G_MB_LIB.T6G(SCH_1):PAGE361_I101@PURE_QUANTA.Q_RES(CHIPS)':
 C_PATH='@t6g_mb_lib.t6g(sch_1):page361_i101@pure_quanta.q_res(chips)',
 P_PATH='@t6g_mb_lib.t6g(sch_1):page238_i101@pure_quanta.q_res(chips)',
 PATH='I101',
 DRAWING='@T6G_MB_LIB.T6G(SCH_1):PAGE361',
 WATTAGE='1/16W',
 TOLERANCE='1%',
 MATERIAL='EMPTY',
 PHYS_PAGE='238',
 XY='(1800,1375)',
 ROT='0',
 VER='2',
 PACK_TYPE='0402LF',
 LOCATION='R60',
 CDS_LIB='pure_quanta',
 CDS_PART_NAME='Q_RES_0402LF-10K,1%,1/16W,EMPTY,CS31002FB08',
 PART_NUMBER='CS31002FB08',
 VALUE='10K',
 PRIM_FILE='./archive_libs/logical/q_res/chips/chips.prt';

PART_NAME
 R61 'Q_RES_0402LF-49.9,1%,1/16W,CHIP,CS04992FB07':;

SECTION_NUMBER 1
 '@T6G_MB_LIB.T6G(SCH_1):PAGE175_I83@PURE_QUANTA.Q_RES(CHIPS)':
 C_PATH='@t6g_mb_lib.t6g(sch_1):page175_i83@pure_quanta.q_res(chips)',
 P_PATH='@t6g_mb_lib.t6g(sch_1):page200_i83@pure_quanta.q_res(chips)',
 PATH='I83',
 DRAWING='@T6G_MB_LIB.T6G(SCH_1):PAGE175',
 WATTAGE='1/16W',
 TOLERANCE='1%',
 MATERIAL='CHIP',
 PHYS_PAGE='200',
 XY='(-6475,5550)',
 ROT='0',
 VER='1',
 PACK_TYPE='0402LF',
 LOCATION='R61',
 CDS_LIB='pure_quanta',
 CDS_PART_NAME='Q_RES_0402LF-49.9,1%,1/16W,CHIP,CS04992FB07',
 PART_NUMBER='CS04992FB07',
 VALUE='49.9',
 PRIM_FILE='./archive_libs/logical/q_res/chips/chips.prt';

PART_NAME
 R62 'Q_RES_0402LF-1K,1%,1/16W,CHIP,CS21002FB06':;

SECTION_NUMBER 1
 '@T6G_MB_LIB.T6G(SCH_1):PAGE361_I104@PURE_QUANTA.Q_RES(CHIPS)':
 C_PATH='@t6g_mb_lib.t6g(sch_1):page361_i104@pure_quanta.q_res(chips)',
 P_PATH='@t6g_mb_lib.t6g(sch_1):page238_i104@pure_quanta.q_res(chips)',
 PATH='I104',
 DRAWING='@T6G_MB_LIB.T6G(SCH_1):PAGE361',
 WATTAGE='1/16W',
 TOLERANCE='1%',
 MATERIAL='CHIP',
 PHYS_PAGE='238',
 XY='(1800,825)',
 ROT='0',
 VER='2',
 PACK_TYPE='0402LF',
 LOCATION='R62',
 CDS_LIB='pure_quanta',
 CDS_PART_NAME='Q_RES_0402LF-1K,1%,1/16W,CHIP,CS21002FB06',
 PART_NUMBER='CS21002FB06',
 VALUE='1K',
 PRIM_FILE='./archive_libs/logical/q_res/chips/chips.prt';

PART_NAME
 R63 'Q_RES_0402LF-33,5%,1/16W,CHIP,CS03302JB10':;

SECTION_NUMBER 1
 '@T6G_MB_LIB.T6G(SCH_1):PAGE79_I79@PURE_QUANTA.Q_RES(CHIPS)':
 C_PATH='@t6g_mb_lib.t6g(sch_1):page79_i79@pure_quanta.q_res(chips)',
 P_PATH='@t6g_mb_lib.t6g(sch_1):page80_i79@pure_quanta.q_res(chips)',
 PATH='I79',
 DRAWING='@T6G_MB_LIB.T6G(SCH_1):PAGE79',
 BOM_COST='MEM',
 WATTAGE='1/16W',
 TOLERANCE='5%',
 MATERIAL='CHIP',
 PHYS_PAGE='80',
 XY='(-2775,4100)',
 ROT='2',
 VER='1',
 PACK_TYPE='0402LF',
 LOCATION='R63',
 CDS_LIB='pure_quanta',
 CDS_PART_NAME='Q_RES_0402LF-33,5%,1/16W,CHIP,CS03302JB10',
 PART_NUMBER='CS03302JB10',
 VALUE='33',
 PRIM_FILE='./archive_libs/logical/q_res/chips/chips.prt';

PART_NAME
 R64 'Q_RES_0402LF-1K,1%,1/16W,EMPTY,CS21002FB06':;

SECTION_NUMBER 1
 '@T6G_MB_LIB.T6G(SCH_1):PAGE82_I166@PURE_QUANTA.Q_RES(CHIPS)':
 C_PATH='@t6g_mb_lib.t6g(sch_1):page82_i166@pure_quanta.q_res(chips)',
 P_PATH='@t6g_mb_lib.t6g(sch_1):page83_i166@pure_quanta.q_res(chips)',
 PATH='I166',
 DRAWING='@T6G_MB_LIB.T6G(SCH_1):PAGE82',
 WATTAGE='1/16W',
 TOLERANCE='1%',
 MATERIAL='EMPTY',
 PHYS_PAGE='83',
 XY='(-7075,3000)',
 ROT='0',
 VER='1',
 PACK_TYPE='0402LF',
 LOCATION='R64',
 CDS_LIB='pure_quanta',
 CDS_PART_NAME='Q_RES_0402LF-1K,1%,1/16W,EMPTY,CS21002FB06',
 PART_NUMBER='CS21002FB06',
 VALUE='1K',
 PRIM_FILE='./archive_libs/logical/q_res/chips/chips.prt';

PART_NAME
 R65 'Q_RES_0402LF-33.2,1%,1/16W,CHIP,CS03322FB03':;

SECTION_NUMBER 1
 '@T6G_MB_LIB.T6G(SCH_1):PAGE252_I74@PURE_QUANTA.Q_RES(CHIPS)':
 C_PATH='@t6g_mb_lib.t6g(sch_1):page252_i74@pure_quanta.q_res(chips)',
 P_PATH='@t6g_mb_lib.t6g(sch_1):page250_i74@pure_quanta.q_res(chips)',
 PATH='I74',
 DRAWING='@T6G_MB_LIB.T6G(SCH_1):PAGE252',
 WATTAGE='1/16W',
 TOLERANCE='1%',
 MATERIAL='CHIP',
 PHYS_PAGE='250',
 XY='(-2525,4775)',
 ROT='2',
 VER='1',
 PACK_TYPE='0402LF',
 LOCATION='R65',
 CDS_LIB='pure_quanta',
 CDS_PART_NAME='Q_RES_0402LF-33.2,1%,1/16W,CHIP,CS03322FB03',
 PART_NUMBER='CS03322FB03',
 VALUE='33.2',
 PRIM_FILE='./archive_libs/logical/q_res/chips/chips.prt';

PART_NAME
 R66 'Q_RES_0402LF-2.2K,5%,1/16W,CHIP,CS22202JB07':;

SECTION_NUMBER 1
 '@T6G_MB_LIB.T6G(SCH_1):PAGE252_I40@PURE_QUANTA.Q_RES(CHIPS)':
 C_PATH='@t6g_mb_lib.t6g(sch_1):page252_i40@pure_quanta.q_res(chips)',
 P_PATH='@t6g_mb_lib.t6g(sch_1):page250_i40@pure_quanta.q_res(chips)',
 PATH='I40',
 DRAWING='@T6G_MB_LIB.T6G(SCH_1):PAGE252',
 WATTAGE='1/16W',
 TOLERANCE='5%',
 MATERIAL='CHIP',
 PHYS_PAGE='250',
 XY='(-2125,900)',
 ROT='0',
 VER='1',
 PACK_TYPE='0402LF',
 LOCATION='R66',
 CDS_LIB='pure_quanta',
 CDS_PART_NAME='Q_RES_0402LF-2.2K,5%,1/16W,CHIP,CS22202JB07',
 PART_NUMBER='CS22202JB07',
 VALUE='2.2K',
 PRIM_FILE='./archive_libs/logical/q_res/chips/chips.prt';

PART_NAME
 R67 'Q_RES_0402LF-2.2K,5%,1/16W,CHIP,CS22202JB07':;

SECTION_NUMBER 1
 '@T6G_MB_LIB.T6G(SCH_1):PAGE252_I39@PURE_QUANTA.Q_RES(CHIPS)':
 C_PATH='@t6g_mb_lib.t6g(sch_1):page252_i39@pure_quanta.q_res(chips)',
 P_PATH='@t6g_mb_lib.t6g(sch_1):page250_i39@pure_quanta.q_res(chips)',
 PATH='I39',
 DRAWING='@T6G_MB_LIB.T6G(SCH_1):PAGE252',
 WATTAGE='1/16W',
 TOLERANCE='5%',
 MATERIAL='CHIP',
 PHYS_PAGE='250',
 XY='(-2125,850)',
 ROT='0',
 VER='1',
 PACK_TYPE='0402LF',
 LOCATION='R67',
 CDS_LIB='pure_quanta',
 CDS_PART_NAME='Q_RES_0402LF-2.2K,5%,1/16W,CHIP,CS22202JB07',
 PART_NUMBER='CS22202JB07',
 VALUE='2.2K',
 PRIM_FILE='./archive_libs/logical/q_res/chips/chips.prt';

PART_NAME
 R68 'Q_RES_0402LF-1K,1%,1/16W,EMPTY,CS21002FB06':;

SECTION_NUMBER 1
 '@T6G_MB_LIB.T6G(SCH_1):PAGE361_I120@PURE_QUANTA.Q_RES(CHIPS)':
 C_PATH='@t6g_mb_lib.t6g(sch_1):page361_i120@pure_quanta.q_res(chips)',
 P_PATH='@t6g_mb_lib.t6g(sch_1):page238_i120@pure_quanta.q_res(chips)',
 PATH='I120',
 DRAWING='@T6G_MB_LIB.T6G(SCH_1):PAGE361',
 WATTAGE='1/16W',
 TOLERANCE='1%',
 MATERIAL='EMPTY',
 PHYS_PAGE='238',
 XY='(2075,1375)',
 ROT='0',
 VER='2',
 PACK_TYPE='0402LF',
 LOCATION='R68',
 CDS_LIB='pure_quanta',
 CDS_PART_NAME='Q_RES_0402LF-1K,1%,1/16W,EMPTY,CS21002FB06',
 PART_NUMBER='CS21002FB06',
 VALUE='1K',
 PRIM_FILE='./archive_libs/logical/q_res/chips/chips.prt';

PART_NAME
 R69 'Q_RES_0402LF-10K,1%,1/16W,CHIP,CS31002FB08':;

SECTION_NUMBER 1
 '@T6G_MB_LIB.T6G(SCH_1):PAGE361_I121@PURE_QUANTA.Q_RES(CHIPS)':
 C_PATH='@t6g_mb_lib.t6g(sch_1):page361_i121@pure_quanta.q_res(chips)',
 P_PATH='@t6g_mb_lib.t6g(sch_1):page238_i121@pure_quanta.q_res(chips)',
 PATH='I121',
 DRAWING='@T6G_MB_LIB.T6G(SCH_1):PAGE361',
 WATTAGE='1/16W',
 TOLERANCE='1%',
 MATERIAL='CHIP',
 PHYS_PAGE='238',
 XY='(2075,825)',
 ROT='0',
 VER='2',
 PACK_TYPE='0402LF',
 LOCATION='R69',
 CDS_LIB='pure_quanta',
 CDS_PART_NAME='Q_RES_0402LF-10K,1%,1/16W,CHIP,CS31002FB08',
 PART_NUMBER='CS31002FB08',
 VALUE='10K',
 PRIM_FILE='./archive_libs/logical/q_res/chips/chips.prt';

PART_NAME
 R70 'Q_RES_0402LF-0,5%,1/16W,CHIP,CS00002JB13':;

SECTION_NUMBER 1
 '@T6G_MB_LIB.T6G(SCH_1):PAGE79_I19@PURE_QUANTA.Q_RES(CHIPS)':
 C_PATH='@t6g_mb_lib.t6g(sch_1):page79_i19@pure_quanta.q_res(chips)',
 P_PATH='@t6g_mb_lib.t6g(sch_1):page80_i19@pure_quanta.q_res(chips)',
 PATH='I19',
 DRAWING='@T6G_MB_LIB.T6G(SCH_1):PAGE79',
 BOM_COST='MEM',
 WATTAGE='1/16W',
 TOLERANCE='5%',
 MATERIAL='CHIP',
 PHYS_PAGE='80',
 XY='(-6850,3000)',
 ROT='2',
 VER='1',
 PACK_TYPE='0402LF',
 LOCATION='R70',
 CDS_LIB='pure_quanta',
 CDS_PART_NAME='Q_RES_0402LF-0,5%,1/16W,CHIP,CS00002JB13',
 PART_NUMBER='CS00002JB13',
 VALUE='0',
 PRIM_FILE='./archive_libs/logical/q_res/chips/chips.prt';

PART_NAME
 R71 'Q_RES_0402LF-33,5%,1/16W,CHIP,CS03302JB10':;

SECTION_NUMBER 1
 '@T6G_MB_LIB.T6G(SCH_1):PAGE83_I27@PURE_QUANTA.Q_RES(CHIPS)':
 C_PATH='@t6g_mb_lib.t6g(sch_1):page83_i27@pure_quanta.q_res(chips)',
 P_PATH='@t6g_mb_lib.t6g(sch_1):page84_i27@pure_quanta.q_res(chips)',
 PATH='I27',
 DRAWING='@T6G_MB_LIB.T6G(SCH_1):PAGE83',
 BOM_COST='MEM',
 WATTAGE='1/16W',
 TOLERANCE='5%',
 MATERIAL='CHIP',
 PHYS_PAGE='84',
 XY='(-1500,5525)',
 ROT='0',
 VER='1',
 PACK_TYPE='0402LF',
 LOCATION='R71',
 CDS_LIB='pure_quanta',
 CDS_PART_NAME='Q_RES_0402LF-33,5%,1/16W,CHIP,CS03302JB10',
 PART_NUMBER='CS03302JB10',
 VALUE='33',
 PRIM_FILE='./archive_libs/logical/q_res/chips/chips.prt';

PART_NAME
 R72 'Q_RES_0402LF-22,1%,1/16W,CHIP,CS02202FB02':;

SECTION_NUMBER 1
 '@T6G_MB_LIB.T6G(SCH_1):PAGE336_I100@PURE_QUANTA.Q_RES(CHIPS)':
 C_PATH='@t6g_mb_lib.t6g(sch_1):page336_i100@pure_quanta.q_res(chips)',
 P_PATH='@t6g_mb_lib.t6g(sch_1):page132_i100@pure_quanta.q_res(chips)',
 PATH='I100',
 DRAWING='@T6G_MB_LIB.T6G(SCH_1):PAGE336',
 WATTAGE='1/16W',
 TOLERANCE='1%',
 MATERIAL='CHIP',
 PHYS_PAGE='132',
 XY='(1450,6600)',
 ROT='0',
 VER='1',
 PACK_TYPE='0402LF',
 LOCATION='R72',
 CDS_LIB='pure_quanta',
 CDS_PART_NAME='Q_RES_0402LF-22,1%,1/16W,CHIP,CS02202FB02',
 PART_NUMBER='CS02202FB02',
 VALUE='22',
 PRIM_FILE='./archive_libs/logical/q_res/chips/chips.prt';

PART_NAME
 R73 'Q_RES_0402LF-22,1%,1/16W,CHIP,CS02202FB02':;

SECTION_NUMBER 1
 '@T6G_MB_LIB.T6G(SCH_1):PAGE336_I101@PURE_QUANTA.Q_RES(CHIPS)':
 C_PATH='@t6g_mb_lib.t6g(sch_1):page336_i101@pure_quanta.q_res(chips)',
 P_PATH='@t6g_mb_lib.t6g(sch_1):page132_i101@pure_quanta.q_res(chips)',
 PATH='I101',
 DRAWING='@T6G_MB_LIB.T6G(SCH_1):PAGE336',
 WATTAGE='1/16W',
 TOLERANCE='1%',
 MATERIAL='CHIP',
 PHYS_PAGE='132',
 XY='(1450,6450)',
 ROT='0',
 VER='1',
 PACK_TYPE='0402LF',
 LOCATION='R73',
 CDS_LIB='pure_quanta',
 CDS_PART_NAME='Q_RES_0402LF-22,1%,1/16W,CHIP,CS02202FB02',
 PART_NUMBER='CS02202FB02',
 VALUE='22',
 PRIM_FILE='./archive_libs/logical/q_res/chips/chips.prt';

PART_NAME
 R74 'Q_RES_0402LF-0,5%,1/16W,CHIP,CS00002JB13':;

SECTION_NUMBER 1
 '@T6G_MB_LIB.T6G(SCH_1):PAGE336_I102@PURE_QUANTA.Q_RES(CHIPS)':
 C_PATH='@t6g_mb_lib.t6g(sch_1):page336_i102@pure_quanta.q_res(chips)',
 P_PATH='@t6g_mb_lib.t6g(sch_1):page132_i102@pure_quanta.q_res(chips)',
 PATH='I102',
 DRAWING='@T6G_MB_LIB.T6G(SCH_1):PAGE336',
 WATTAGE='1/16W',
 TOLERANCE='5%',
 MATERIAL='CHIP',
 PHYS_PAGE='132',
 XY='(1450,5325)',
 ROT='0',
 VER='1',
 PACK_TYPE='0402LF',
 LOCATION='R74',
 CDS_LIB='pure_quanta',
 CDS_PART_NAME='Q_RES_0402LF-0,5%,1/16W,CHIP,CS00002JB13',
 PART_NUMBER='CS00002JB13',
 VALUE='0',
 PRIM_FILE='./archive_libs/logical/q_res/chips/chips.prt';

PART_NAME
 R75 'Q_RES_0402LF-0,5%,1/16W,CHIP,CS00002JB13':;

SECTION_NUMBER 1
 '@T6G_MB_LIB.T6G(SCH_1):PAGE336_I103@PURE_QUANTA.Q_RES(CHIPS)':
 C_PATH='@t6g_mb_lib.t6g(sch_1):page336_i103@pure_quanta.q_res(chips)',
 P_PATH='@t6g_mb_lib.t6g(sch_1):page132_i103@pure_quanta.q_res(chips)',
 PATH='I103',
 DRAWING='@T6G_MB_LIB.T6G(SCH_1):PAGE336',
 WATTAGE='1/16W',
 TOLERANCE='5%',
 MATERIAL='CHIP',
 PHYS_PAGE='132',
 XY='(1450,5175)',
 ROT='0',
 VER='1',
 PACK_TYPE='0402LF',
 LOCATION='R75',
 CDS_LIB='pure_quanta',
 CDS_PART_NAME='Q_RES_0402LF-0,5%,1/16W,CHIP,CS00002JB13',
 PART_NUMBER='CS00002JB13',
 VALUE='0',
 PRIM_FILE='./archive_libs/logical/q_res/chips/chips.prt';

PART_NAME
 R76 'Q_RES_0402LF-0,5%,1/16W,CHIP,CS00002JB13':;

SECTION_NUMBER 1
 '@T6G_MB_LIB.T6G(SCH_1):PAGE336_I104@PURE_QUANTA.Q_RES(CHIPS)':
 C_PATH='@t6g_mb_lib.t6g(sch_1):page336_i104@pure_quanta.q_res(chips)',
 P_PATH='@t6g_mb_lib.t6g(sch_1):page132_i104@pure_quanta.q_res(chips)',
 PATH='I104',
 DRAWING='@T6G_MB_LIB.T6G(SCH_1):PAGE336',
 WATTAGE='1/16W',
 TOLERANCE='5%',
 MATERIAL='CHIP',
 PHYS_PAGE='132',
 XY='(1450,5025)',
 ROT='0',
 VER='1',
 PACK_TYPE='0402LF',
 LOCATION='R76',
 CDS_LIB='pure_quanta',
 CDS_PART_NAME='Q_RES_0402LF-0,5%,1/16W,CHIP,CS00002JB13',
 PART_NUMBER='CS00002JB13',
 VALUE='0',
 PRIM_FILE='./archive_libs/logical/q_res/chips/chips.prt';

PART_NAME
 R77 'Q_RES_0402LF-100K,1%,1/16W,CHIP,CS41002FB09':;

SECTION_NUMBER 1
 '@T6G_MB_LIB.T6G(SCH_1):PAGE336_I131@PURE_QUANTA.Q_RES(CHIPS)':
 C_PATH='@t6g_mb_lib.t6g(sch_1):page336_i131@pure_quanta.q_res(chips)',
 P_PATH='@t6g_mb_lib.t6g(sch_1):page132_i131@pure_quanta.q_res(chips)',
 PATH='I131',
 DRAWING='@T6G_MB_LIB.T6G(SCH_1):PAGE336',
 WATTAGE='1/16W',
 TOLERANCE='1%',
 MATERIAL='CHIP',
 PHYS_PAGE='132',
 XY='(3025,4475)',
 ROT='0',
 VER='1',
 PACK_TYPE='0402LF',
 LOCATION='R77',
 CDS_LIB='pure_quanta',
 CDS_PART_NAME='Q_RES_0402LF-100K,1%,1/16W,CHIP,CS41002FB09',
 PART_NUMBER='CS41002FB09',
 VALUE='100K',
 PRIM_FILE='./archive_libs/logical/q_res/chips/chips.prt';

PART_NAME
 R78 'Q_RES_0402LF-4.7K,5%,1/16W,EMPTY,CS24702JB10':;

SECTION_NUMBER 1
 '@T6G_MB_LIB.T6G(SCH_1):PAGE137_I31@PURE_QUANTA.Q_RES(CHIPS)':
 C_PATH='@t6g_mb_lib.t6g(sch_1):page137_i31@pure_quanta.q_res(chips)',
 P_PATH='@t6g_mb_lib.t6g(sch_1):page160_i31@pure_quanta.q_res(chips)',
 PATH='I31',
 DRAWING='@T6G_MB_LIB.T6G(SCH_1):PAGE137',
 WATTAGE='1/16W',
 TOLERANCE='5%',
 MATERIAL='EMPTY',
 PHYS_PAGE='160',
 XY='(-4225,1775)',
 ROT='0',
 VER='2',
 PACK_TYPE='0402LF',
 LOCATION='R78',
 CDS_LIB='pure_quanta',
 CDS_PART_NAME='Q_RES_0402LF-4.7K,5%,1/16W,EMPTY,CS24702JB10',
 PART_NUMBER='CS24702JB10',
 VALUE='4.7K',
 PRIM_FILE='./archive_libs/logical/q_res/chips/chips.prt';

PART_NAME
 R79 'Q_RES_0402LF-100K,1%,1/16W,CHIP,CS41002FB09':;

SECTION_NUMBER 1
 '@T6G_MB_LIB.T6G(SCH_1):PAGE336_I132@PURE_QUANTA.Q_RES(CHIPS)':
 C_PATH='@t6g_mb_lib.t6g(sch_1):page336_i132@pure_quanta.q_res(chips)',
 P_PATH='@t6g_mb_lib.t6g(sch_1):page132_i132@pure_quanta.q_res(chips)',
 PATH='I132',
 DRAWING='@T6G_MB_LIB.T6G(SCH_1):PAGE336',
 WATTAGE='1/16W',
 TOLERANCE='1%',
 MATERIAL='CHIP',
 PHYS_PAGE='132',
 XY='(3025,4325)',
 ROT='0',
 VER='1',
 PACK_TYPE='0402LF',
 LOCATION='R79',
 CDS_LIB='pure_quanta',
 CDS_PART_NAME='Q_RES_0402LF-100K,1%,1/16W,CHIP,CS41002FB09',
 PART_NUMBER='CS41002FB09',
 VALUE='100K',
 PRIM_FILE='./archive_libs/logical/q_res/chips/chips.prt';

PART_NAME
 R80 'Q_RES_0402LF-100K,1%,1/16W,CHIP,CS41002FB09':;

SECTION_NUMBER 1
 '@T6G_MB_LIB.T6G(SCH_1):PAGE336_I133@PURE_QUANTA.Q_RES(CHIPS)':
 C_PATH='@t6g_mb_lib.t6g(sch_1):page336_i133@pure_quanta.q_res(chips)',
 P_PATH='@t6g_mb_lib.t6g(sch_1):page132_i133@pure_quanta.q_res(chips)',
 PATH='I133',
 DRAWING='@T6G_MB_LIB.T6G(SCH_1):PAGE336',
 WATTAGE='1/16W',
 TOLERANCE='1%',
 MATERIAL='CHIP',
 PHYS_PAGE='132',
 XY='(3025,4175)',
 ROT='0',
 VER='1',
 PACK_TYPE='0402LF',
 LOCATION='R80',
 CDS_LIB='pure_quanta',
 CDS_PART_NAME='Q_RES_0402LF-100K,1%,1/16W,CHIP,CS41002FB09',
 PART_NUMBER='CS41002FB09',
 VALUE='100K',
 PRIM_FILE='./archive_libs/logical/q_res/chips/chips.prt';

PART_NAME
 R81 'Q_RES_0402LF-33,5%,1/16W,CHIP,CS03302JB10':;

SECTION_NUMBER 1
 '@T6G_MB_LIB.T6G(SCH_1):PAGE81_I106@PURE_QUANTA.Q_RES(CHIPS)':
 C_PATH='@t6g_mb_lib.t6g(sch_1):page81_i106@pure_quanta.q_res(chips)',
 P_PATH='@t6g_mb_lib.t6g(sch_1):page82_i106@pure_quanta.q_res(chips)',
 PATH='I106',
 DRAWING='@T6G_MB_LIB.T6G(SCH_1):PAGE81',
 BOM_COST='MEM',
 WATTAGE='1/16W',
 TOLERANCE='5%',
 MATERIAL='CHIP',
 PHYS_PAGE='82',
 XY='(-3250,5575)',
 ROT='0',
 VER='1',
 PACK_TYPE='0402LF',
 LOCATION='R81',
 CDS_LIB='pure_quanta',
 CDS_PART_NAME='Q_RES_0402LF-33,5%,1/16W,CHIP,CS03302JB10',
 PART_NUMBER='CS03302JB10',
 VALUE='33',
 PRIM_FILE='./archive_libs/logical/q_res/chips/chips.prt';

PART_NAME
 R82 'Q_RES_0402LF-100K,1%,1/16W,CHIP,CS41002FB09':;

SECTION_NUMBER 1
 '@T6G_MB_LIB.T6G(SCH_1):PAGE336_I134@PURE_QUANTA.Q_RES(CHIPS)':
 C_PATH='@t6g_mb_lib.t6g(sch_1):page336_i134@pure_quanta.q_res(chips)',
 P_PATH='@t6g_mb_lib.t6g(sch_1):page132_i134@pure_quanta.q_res(chips)',
 PATH='I134',
 DRAWING='@T6G_MB_LIB.T6G(SCH_1):PAGE336',
 WATTAGE='1/16W',
 TOLERANCE='1%',
 MATERIAL='CHIP',
 PHYS_PAGE='132',
 XY='(3025,4025)',
 ROT='0',
 VER='1',
 PACK_TYPE='0402LF',
 LOCATION='R82',
 CDS_LIB='pure_quanta',
 CDS_PART_NAME='Q_RES_0402LF-100K,1%,1/16W,CHIP,CS41002FB09',
 PART_NUMBER='CS41002FB09',
 VALUE='100K',
 PRIM_FILE='./archive_libs/logical/q_res/chips/chips.prt';

PART_NAME
 R83 'Q_RES_0402LF-100K,1%,1/16W,CHIP,CS41002FB09':;

SECTION_NUMBER 1
 '@T6G_MB_LIB.T6G(SCH_1):PAGE336_I135@PURE_QUANTA.Q_RES(CHIPS)':
 C_PATH='@t6g_mb_lib.t6g(sch_1):page336_i135@pure_quanta.q_res(chips)',
 P_PATH='@t6g_mb_lib.t6g(sch_1):page132_i135@pure_quanta.q_res(chips)',
 PATH='I135',
 DRAWING='@T6G_MB_LIB.T6G(SCH_1):PAGE336',
 WATTAGE='1/16W',
 TOLERANCE='1%',
 MATERIAL='CHIP',
 PHYS_PAGE='132',
 XY='(3025,3875)',
 ROT='0',
 VER='1',
 PACK_TYPE='0402LF',
 LOCATION='R83',
 CDS_LIB='pure_quanta',
 CDS_PART_NAME='Q_RES_0402LF-100K,1%,1/16W,CHIP,CS41002FB09',
 PART_NUMBER='CS41002FB09',
 VALUE='100K',
 PRIM_FILE='./archive_libs/logical/q_res/chips/chips.prt';

PART_NAME
 R84 'Q_RES_0402LF-100K,1%,1/16W,CHIP,CS41002FB09':;

SECTION_NUMBER 1
 '@T6G_MB_LIB.T6G(SCH_1):PAGE336_I129@PURE_QUANTA.Q_RES(CHIPS)':
 C_PATH='@t6g_mb_lib.t6g(sch_1):page336_i129@pure_quanta.q_res(chips)',
 P_PATH='@t6g_mb_lib.t6g(sch_1):page132_i129@pure_quanta.q_res(chips)',
 PATH='I129',
 DRAWING='@T6G_MB_LIB.T6G(SCH_1):PAGE336',
 WATTAGE='1/16W',
 TOLERANCE='1%',
 MATERIAL='CHIP',
 PHYS_PAGE='132',
 XY='(3025,3725)',
 ROT='0',
 VER='1',
 PACK_TYPE='0402LF',
 LOCATION='R84',
 CDS_LIB='pure_quanta',
 CDS_PART_NAME='Q_RES_0402LF-100K,1%,1/16W,CHIP,CS41002FB09',
 PART_NUMBER='CS41002FB09',
 VALUE='100K',
 PRIM_FILE='./archive_libs/logical/q_res/chips/chips.prt';

PART_NAME
 R85 'Q_RES_0402LF-0,5%,1/16W,CHIP,CS00002JB13':;

SECTION_NUMBER 1
 '@T6G_MB_LIB.T6G(SCH_1):PAGE361_I124@PURE_QUANTA.Q_RES(CHIPS)':
 C_PATH='@t6g_mb_lib.t6g(sch_1):page361_i124@pure_quanta.q_res(chips)',
 P_PATH='@t6g_mb_lib.t6g(sch_1):page238_i124@pure_quanta.q_res(chips)',
 PATH='I124',
 DRAWING='@T6G_MB_LIB.T6G(SCH_1):PAGE361',
 WATTAGE='1/16W',
 TOLERANCE='5%',
 MATERIAL='CHIP',
 PHYS_PAGE='238',
 XY='(-2375,3350)',
 ROT='0',
 VER='1',
 PACK_TYPE='0402LF',
 LOCATION='R85',
 CDS_LIB='pure_quanta',
 CDS_PART_NAME='Q_RES_0402LF-0,5%,1/16W,CHIP,CS00002JB13',
 PART_NUMBER='CS00002JB13',
 VALUE='0',
 PRIM_FILE='./archive_libs/logical/q_res/chips/chips.prt';

PART_NAME
 R86 'Q_RES_0402LF-0,5%,1/16W,CHIP,CS00002JB13':;

SECTION_NUMBER 1
 '@T6G_MB_LIB.T6G(SCH_1):PAGE361_I125@PURE_QUANTA.Q_RES(CHIPS)':
 C_PATH='@t6g_mb_lib.t6g(sch_1):page361_i125@pure_quanta.q_res(chips)',
 P_PATH='@t6g_mb_lib.t6g(sch_1):page238_i125@pure_quanta.q_res(chips)',
 PATH='I125',
 DRAWING='@T6G_MB_LIB.T6G(SCH_1):PAGE361',
 WATTAGE='1/16W',
 TOLERANCE='5%',
 MATERIAL='CHIP',
 PHYS_PAGE='238',
 XY='(-2375,3300)',
 ROT='0',
 VER='1',
 PACK_TYPE='0402LF',
 LOCATION='R86',
 CDS_LIB='pure_quanta',
 CDS_PART_NAME='Q_RES_0402LF-0,5%,1/16W,CHIP,CS00002JB13',
 PART_NUMBER='CS00002JB13',
 VALUE='0',
 PRIM_FILE='./archive_libs/logical/q_res/chips/chips.prt';

PART_NAME
 R87 'Q_RES_0402LF-1K,1%,1/16W,CHIP,CS21002FB06':;

SECTION_NUMBER 1
 '@T6G_MB_LIB.T6G(SCH_1):PAGE336_I136@PURE_QUANTA.Q_RES(CHIPS)':
 C_PATH='@t6g_mb_lib.t6g(sch_1):page336_i136@pure_quanta.q_res(chips)',
 P_PATH='@t6g_mb_lib.t6g(sch_1):page132_i136@pure_quanta.q_res(chips)',
 PATH='I136',
 DRAWING='@T6G_MB_LIB.T6G(SCH_1):PAGE336',
 WATTAGE='1/16W',
 TOLERANCE='1%',
 MATERIAL='CHIP',
 PHYS_PAGE='132',
 XY='(3025,3550)',
 ROT='0',
 VER='1',
 PACK_TYPE='0402LF',
 LOCATION='R87',
 CDS_LIB='pure_quanta',
 CDS_PART_NAME='Q_RES_0402LF-1K,1%,1/16W,CHIP,CS21002FB06',
 PART_NUMBER='CS21002FB06',
 VALUE='1K',
 PRIM_FILE='./archive_libs/logical/q_res/chips/chips.prt';

PART_NAME
 R88 'Q_RES_0402LF-1K,1%,1/16W,EMPTY,CS21002FB06':
 ROOM='';

SECTION_NUMBER 1
 '@T6G_MB_LIB.T6G(SCH_1):PAGE85_I526@PURE_QUANTA.Q_RES(CHIPS)':
 C_PATH='@t6g_mb_lib.t6g(sch_1):page85_i526@pure_quanta.q_res(chips)',
 P_PATH='@t6g_mb_lib.t6g(sch_1):page86_i526@pure_quanta.q_res(chips)',
 PATH='I526',
 DRAWING='@T6G_MB_LIB.T6G(SCH_1):PAGE85',
 BOM_COST='MEM',
 WATTAGE='1/16W',
 TOLERANCE='1%',
 MATERIAL='EMPTY',
 PHYS_PAGE='86',
 XY='(-8700,2400)',
 ROT='2',
 VER='2',
 PACK_TYPE='0402LF',
 LOCATION='R88',
 CDS_LIB='pure_quanta',
 CDS_PART_NAME='Q_RES_0402LF-1K,1%,1/16W,EMPTY,CS21002FB06',
 ROOM='',
 PART_NUMBER='CS21002FB06',
 VALUE='1K',
 PRIM_FILE='./archive_libs/logical/q_res/chips/chips.prt';

PART_NAME
 R89 'Q_RES_0402LF-1K,1%,1/16W,EMPTY,CS21002FB06':
 ROOM='';

SECTION_NUMBER 1
 '@T6G_MB_LIB.T6G(SCH_1):PAGE85_I528@PURE_QUANTA.Q_RES(CHIPS)':
 C_PATH='@t6g_mb_lib.t6g(sch_1):page85_i528@pure_quanta.q_res(chips)',
 P_PATH='@t6g_mb_lib.t6g(sch_1):page86_i528@pure_quanta.q_res(chips)',
 PATH='I528',
 DRAWING='@T6G_MB_LIB.T6G(SCH_1):PAGE85',
 BOM_COST='MEM',
 WATTAGE='1/16W',
 TOLERANCE='1%',
 MATERIAL='EMPTY',
 PHYS_PAGE='86',
 XY='(-8450,2400)',
 ROT='0',
 VER='2',
 PACK_TYPE='0402LF',
 LOCATION='R89',
 CDS_LIB='pure_quanta',
 CDS_PART_NAME='Q_RES_0402LF-1K,1%,1/16W,EMPTY,CS21002FB06',
 ROOM='',
 PART_NUMBER='CS21002FB06',
 VALUE='1K',
 PRIM_FILE='./archive_libs/logical/q_res/chips/chips.prt';

PART_NAME
 R90 'Q_RES_0402LF-1K,1%,1/16W,EMPTY,CS21002FB06':
 ROOM='';

SECTION_NUMBER 1
 '@T6G_MB_LIB.T6G(SCH_1):PAGE86_I365@PURE_QUANTA.Q_RES(CHIPS)':
 C_PATH='@t6g_mb_lib.t6g(sch_1):page86_i365@pure_quanta.q_res(chips)',
 P_PATH='@t6g_mb_lib.t6g(sch_1):page87_i365@pure_quanta.q_res(chips)',
 PATH='I365',
 DRAWING='@T6G_MB_LIB.T6G(SCH_1):PAGE86',
 BOM_COST='MEM',
 WATTAGE='1/16W',
 TOLERANCE='1%',
 MATERIAL='EMPTY',
 PHYS_PAGE='87',
 XY='(-8550,2425)',
 ROT='0',
 VER='2',
 PACK_TYPE='0402LF',
 LOCATION='R90',
 CDS_LIB='pure_quanta',
 CDS_PART_NAME='Q_RES_0402LF-1K,1%,1/16W,EMPTY,CS21002FB06',
 ROOM='',
 PART_NUMBER='CS21002FB06',
 VALUE='1K',
 PRIM_FILE='./archive_libs/logical/q_res/chips/chips.prt';

PART_NAME
 R91 'Q_RES_0402LF-1K,1%,1/16W,EMPTY,CS21002FB06':
 ROOM='';

SECTION_NUMBER 1
 '@T6G_MB_LIB.T6G(SCH_1):PAGE87_I365@PURE_QUANTA.Q_RES(CHIPS)':
 C_PATH='@t6g_mb_lib.t6g(sch_1):page87_i365@pure_quanta.q_res(chips)',
 P_PATH='@t6g_mb_lib.t6g(sch_1):page88_i365@pure_quanta.q_res(chips)',
 PATH='I365',
 DRAWING='@T6G_MB_LIB.T6G(SCH_1):PAGE87',
 BOM_COST='MEM',
 WATTAGE='1/16W',
 TOLERANCE='1%',
 MATERIAL='EMPTY',
 PHYS_PAGE='88',
 XY='(-8550,2625)',
 ROT='0',
 VER='2',
 PACK_TYPE='0402LF',
 LOCATION='R91',
 CDS_LIB='pure_quanta',
 CDS_PART_NAME='Q_RES_0402LF-1K,1%,1/16W,EMPTY,CS21002FB06',
 ROOM='',
 PART_NUMBER='CS21002FB06',
 VALUE='1K',
 PRIM_FILE='./archive_libs/logical/q_res/chips/chips.prt';

PART_NAME
 R92 'Q_RES_0402LF-1K,1%,1/16W,EMPTY,CS21002FB06':
 ROOM='';

SECTION_NUMBER 1
 '@T6G_MB_LIB.T6G(SCH_1):PAGE88_I367@PURE_QUANTA.Q_RES(CHIPS)':
 C_PATH='@t6g_mb_lib.t6g(sch_1):page88_i367@pure_quanta.q_res(chips)',
 P_PATH='@t6g_mb_lib.t6g(sch_1):page89_i367@pure_quanta.q_res(chips)',
 PATH='I367',
 DRAWING='@T6G_MB_LIB.T6G(SCH_1):PAGE88',
 BOM_COST='MEM',
 WATTAGE='1/16W',
 TOLERANCE='1%',
 MATERIAL='EMPTY',
 PHYS_PAGE='89',
 XY='(-8375,2450)',
 ROT='0',
 VER='2',
 PACK_TYPE='0402LF',
 LOCATION='R92',
 CDS_LIB='pure_quanta',
 CDS_PART_NAME='Q_RES_0402LF-1K,1%,1/16W,EMPTY,CS21002FB06',
 ROOM='',
 PART_NUMBER='CS21002FB06',
 VALUE='1K',
 PRIM_FILE='./archive_libs/logical/q_res/chips/chips.prt';

PART_NAME
 R93 'Q_RES_0402LF-1K,1%,1/16W,EMPTY,CS21002FB06':
 ROOM='';

SECTION_NUMBER 1
 '@T6G_MB_LIB.T6G(SCH_1):PAGE89_I364@PURE_QUANTA.Q_RES(CHIPS)':
 C_PATH='@t6g_mb_lib.t6g(sch_1):page89_i364@pure_quanta.q_res(chips)',
 P_PATH='@t6g_mb_lib.t6g(sch_1):page90_i364@pure_quanta.q_res(chips)',
 PATH='I364',
 DRAWING='@T6G_MB_LIB.T6G(SCH_1):PAGE89',
 BOM_COST='MEM',
 WATTAGE='1/16W',
 TOLERANCE='1%',
 MATERIAL='EMPTY',
 PHYS_PAGE='90',
 XY='(-8600,2475)',
 ROT='0',
 VER='2',
 PACK_TYPE='0402LF',
 LOCATION='R93',
 CDS_LIB='pure_quanta',
 CDS_PART_NAME='Q_RES_0402LF-1K,1%,1/16W,EMPTY,CS21002FB06',
 ROOM='',
 PART_NUMBER='CS21002FB06',
 VALUE='1K',
 PRIM_FILE='./archive_libs/logical/q_res/chips/chips.prt';

PART_NAME
 R94 'Q_RES_0402LF-1K,1%,1/16W,EMPTY,CS21002FB06':
 ROOM='';

SECTION_NUMBER 1
 '@T6G_MB_LIB.T6G(SCH_1):PAGE90_I365@PURE_QUANTA.Q_RES(CHIPS)':
 C_PATH='@t6g_mb_lib.t6g(sch_1):page90_i365@pure_quanta.q_res(chips)',
 P_PATH='@t6g_mb_lib.t6g(sch_1):page91_i365@pure_quanta.q_res(chips)',
 PATH='I365',
 DRAWING='@T6G_MB_LIB.T6G(SCH_1):PAGE90',
 BOM_COST='MEM',
 WATTAGE='1/16W',
 TOLERANCE='1%',
 MATERIAL='EMPTY',
 PHYS_PAGE='91',
 XY='(-8425,2625)',
 ROT='0',
 VER='2',
 PACK_TYPE='0402LF',
 LOCATION='R94',
 CDS_LIB='pure_quanta',
 CDS_PART_NAME='Q_RES_0402LF-1K,1%,1/16W,EMPTY,CS21002FB06',
 ROOM='',
 PART_NUMBER='CS21002FB06',
 VALUE='1K',
 PRIM_FILE='./archive_libs/logical/q_res/chips/chips.prt';

PART_NAME
 R95 'Q_RES_0402LF-1K,1%,1/16W,EMPTY,CS21002FB06':
 ROOM='';

SECTION_NUMBER 1
 '@T6G_MB_LIB.T6G(SCH_1):PAGE91_I190@PURE_QUANTA.Q_RES(CHIPS)':
 C_PATH='@t6g_mb_lib.t6g(sch_1):page91_i190@pure_quanta.q_res(chips)',
 P_PATH='@t6g_mb_lib.t6g(sch_1):page92_i190@pure_quanta.q_res(chips)',
 PATH='I190',
 DRAWING='@T6G_MB_LIB.T6G(SCH_1):PAGE91',
 BOM_COST='MEM',
 WATTAGE='1/16W',
 TOLERANCE='1%',
 MATERIAL='EMPTY',
 PHYS_PAGE='92',
 XY='(-8475,2300)',
 ROT='2',
 VER='2',
 PACK_TYPE='0402LF',
 LOCATION='R95',
 CDS_LIB='pure_quanta',
 CDS_PART_NAME='Q_RES_0402LF-1K,1%,1/16W,EMPTY,CS21002FB06',
 ROOM='',
 PART_NUMBER='CS21002FB06',
 VALUE='1K',
 PRIM_FILE='./archive_libs/logical/q_res/chips/chips.prt';

PART_NAME
 R96 'Q_RES_0402LF-1K,1%,1/16W,EMPTY,CS21002FB06':
 ROOM='';

SECTION_NUMBER 1
 '@T6G_MB_LIB.T6G(SCH_1):PAGE91_I187@PURE_QUANTA.Q_RES(CHIPS)':
 C_PATH='@t6g_mb_lib.t6g(sch_1):page91_i187@pure_quanta.q_res(chips)',
 P_PATH='@t6g_mb_lib.t6g(sch_1):page92_i187@pure_quanta.q_res(chips)',
 PATH='I187',
 DRAWING='@T6G_MB_LIB.T6G(SCH_1):PAGE91',
 BOM_COST='MEM',
 WATTAGE='1/16W',
 TOLERANCE='1%',
 MATERIAL='EMPTY',
 PHYS_PAGE='92',
 XY='(-8225,2300)',
 ROT='0',
 VER='2',
 PACK_TYPE='0402LF',
 LOCATION='R96',
 CDS_LIB='pure_quanta',
 CDS_PART_NAME='Q_RES_0402LF-1K,1%,1/16W,EMPTY,CS21002FB06',
 ROOM='',
 PART_NUMBER='CS21002FB06',
 VALUE='1K',
 PRIM_FILE='./archive_libs/logical/q_res/chips/chips.prt';

PART_NAME
 R97 'Q_RES_0402LF-1K,1%,1/16W,EMPTY,CS21002FB06':
 ROOM='';

SECTION_NUMBER 1
 '@T6G_MB_LIB.T6G(SCH_1):PAGE92_I191@PURE_QUANTA.Q_RES(CHIPS)':
 C_PATH='@t6g_mb_lib.t6g(sch_1):page92_i191@pure_quanta.q_res(chips)',
 P_PATH='@t6g_mb_lib.t6g(sch_1):page93_i191@pure_quanta.q_res(chips)',
 PATH='I191',
 DRAWING='@T6G_MB_LIB.T6G(SCH_1):PAGE92',
 BOM_COST='MEM',
 WATTAGE='1/16W',
 TOLERANCE='1%',
 MATERIAL='EMPTY',
 PHYS_PAGE='93',
 XY='(-8400,2250)',
 ROT='0',
 VER='2',
 PACK_TYPE='0402LF',
 LOCATION='R97',
 CDS_LIB='pure_quanta',
 CDS_PART_NAME='Q_RES_0402LF-1K,1%,1/16W,EMPTY,CS21002FB06',
 ROOM='',
 PART_NUMBER='CS21002FB06',
 VALUE='1K',
 PRIM_FILE='./archive_libs/logical/q_res/chips/chips.prt';

PART_NAME
 R98 'Q_RES_0402LF-1K,1%,1/16W,EMPTY,CS21002FB06':
 ROOM='';

SECTION_NUMBER 1
 '@T6G_MB_LIB.T6G(SCH_1):PAGE93_I189@PURE_QUANTA.Q_RES(CHIPS)':
 C_PATH='@t6g_mb_lib.t6g(sch_1):page93_i189@pure_quanta.q_res(chips)',
 P_PATH='@t6g_mb_lib.t6g(sch_1):page94_i189@pure_quanta.q_res(chips)',
 PATH='I189',
 DRAWING='@T6G_MB_LIB.T6G(SCH_1):PAGE93',
 BOM_COST='MEM',
 WATTAGE='1/16W',
 TOLERANCE='1%',
 MATERIAL='EMPTY',
 PHYS_PAGE='94',
 XY='(-8350,2350)',
 ROT='0',
 VER='2',
 PACK_TYPE='0402LF',
 LOCATION='R98',
 CDS_LIB='pure_quanta',
 CDS_PART_NAME='Q_RES_0402LF-1K,1%,1/16W,EMPTY,CS21002FB06',
 ROOM='',
 PART_NUMBER='CS21002FB06',
 VALUE='1K',
 PRIM_FILE='./archive_libs/logical/q_res/chips/chips.prt';

PART_NAME
 R99 'Q_RES_0402LF-1K,1%,1/16W,EMPTY,CS21002FB06':
 ROOM='';

SECTION_NUMBER 1
 '@T6G_MB_LIB.T6G(SCH_1):PAGE94_I189@PURE_QUANTA.Q_RES(CHIPS)':
 C_PATH='@t6g_mb_lib.t6g(sch_1):page94_i189@pure_quanta.q_res(chips)',
 P_PATH='@t6g_mb_lib.t6g(sch_1):page95_i189@pure_quanta.q_res(chips)',
 PATH='I189',
 DRAWING='@T6G_MB_LIB.T6G(SCH_1):PAGE94',
 BOM_COST='MEM',
 WATTAGE='1/16W',
 TOLERANCE='1%',
 MATERIAL='EMPTY',
 PHYS_PAGE='95',
 XY='(-8325,2225)',
 ROT='0',
 VER='2',
 PACK_TYPE='0402LF',
 LOCATION='R99',
 CDS_LIB='pure_quanta',
 CDS_PART_NAME='Q_RES_0402LF-1K,1%,1/16W,EMPTY,CS21002FB06',
 ROOM='',
 PART_NUMBER='CS21002FB06',
 VALUE='1K',
 PRIM_FILE='./archive_libs/logical/q_res/chips/chips.prt';

PART_NAME
 R100 'Q_RES_0402LF-1K,1%,1/16W,EMPTY,CS21002FB06':
 ROOM='';

SECTION_NUMBER 1
 '@T6G_MB_LIB.T6G(SCH_1):PAGE95_I189@PURE_QUANTA.Q_RES(CHIPS)':
 C_PATH='@t6g_mb_lib.t6g(sch_1):page95_i189@pure_quanta.q_res(chips)',
 P_PATH='@t6g_mb_lib.t6g(sch_1):page96_i189@pure_quanta.q_res(chips)',
 PATH='I189',
 DRAWING='@T6G_MB_LIB.T6G(SCH_1):PAGE95',
 BOM_COST='MEM',
 WATTAGE='1/16W',
 TOLERANCE='1%',
 MATERIAL='EMPTY',
 PHYS_PAGE='96',
 XY='(-8350,2275)',
 ROT='0',
 VER='2',
 PACK_TYPE='0402LF',
 LOCATION='R100',
 CDS_LIB='pure_quanta',
 CDS_PART_NAME='Q_RES_0402LF-1K,1%,1/16W,EMPTY,CS21002FB06',
 ROOM='',
 PART_NUMBER='CS21002FB06',
 VALUE='1K',
 PRIM_FILE='./archive_libs/logical/q_res/chips/chips.prt';

PART_NAME
 R101 'Q_RES_0402LF-1K,1%,1/16W,EMPTY,CS21002FB06':
 ROOM='';

SECTION_NUMBER 1
 '@T6G_MB_LIB.T6G(SCH_1):PAGE96_I189@PURE_QUANTA.Q_RES(CHIPS)':
 C_PATH='@t6g_mb_lib.t6g(sch_1):page96_i189@pure_quanta.q_res(chips)',
 P_PATH='@t6g_mb_lib.t6g(sch_1):page97_i189@pure_quanta.q_res(chips)',
 PATH='I189',
 DRAWING='@T6G_MB_LIB.T6G(SCH_1):PAGE96',
 BOM_COST='MEM',
 WATTAGE='1/16W',
 TOLERANCE='1%',
 MATERIAL='EMPTY',
 PHYS_PAGE='97',
 XY='(-8350,1975)',
 ROT='0',
 VER='2',
 PACK_TYPE='0402LF',
 LOCATION='R101',
 CDS_LIB='pure_quanta',
 CDS_PART_NAME='Q_RES_0402LF-1K,1%,1/16W,EMPTY,CS21002FB06',
 ROOM='',
 PART_NUMBER='CS21002FB06',
 VALUE='1K',
 PRIM_FILE='./archive_libs/logical/q_res/chips/chips.prt';

PART_NAME
 R102 'Q_RES_0402LF-1K,1%,1/16W,EMPTY,CS21002FB06':
 ROOM='';

SECTION_NUMBER 1
 '@T6G_MB_LIB.T6G(SCH_1):PAGE97_I189@PURE_QUANTA.Q_RES(CHIPS)':
 C_PATH='@t6g_mb_lib.t6g(sch_1):page97_i189@pure_quanta.q_res(chips)',
 P_PATH='@t6g_mb_lib.t6g(sch_1):page98_i189@pure_quanta.q_res(chips)',
 PATH='I189',
 DRAWING='@T6G_MB_LIB.T6G(SCH_1):PAGE97',
 BOM_COST='MEM',
 WATTAGE='1/16W',
 TOLERANCE='1%',
 MATERIAL='EMPTY',
 PHYS_PAGE='98',
 XY='(-8525,2375)',
 ROT='2',
 VER='2',
 PACK_TYPE='0402LF',
 LOCATION='R102',
 CDS_LIB='pure_quanta',
 CDS_PART_NAME='Q_RES_0402LF-1K,1%,1/16W,EMPTY,CS21002FB06',
 ROOM='',
 PART_NUMBER='CS21002FB06',
 VALUE='1K',
 PRIM_FILE='./archive_libs/logical/q_res/chips/chips.prt';

PART_NAME
 R103 'Q_RES_0402LF-1K,1%,1/16W,EMPTY,CS21002FB06':
 ROOM='';

SECTION_NUMBER 1
 '@T6G_MB_LIB.T6G(SCH_1):PAGE97_I191@PURE_QUANTA.Q_RES(CHIPS)':
 C_PATH='@t6g_mb_lib.t6g(sch_1):page97_i191@pure_quanta.q_res(chips)',
 P_PATH='@t6g_mb_lib.t6g(sch_1):page98_i191@pure_quanta.q_res(chips)',
 PATH='I191',
 DRAWING='@T6G_MB_LIB.T6G(SCH_1):PAGE97',
 BOM_COST='MEM',
 WATTAGE='1/16W',
 TOLERANCE='1%',
 MATERIAL='EMPTY',
 PHYS_PAGE='98',
 XY='(-8275,2375)',
 ROT='0',
 VER='2',
 PACK_TYPE='0402LF',
 LOCATION='R103',
 CDS_LIB='pure_quanta',
 CDS_PART_NAME='Q_RES_0402LF-1K,1%,1/16W,EMPTY,CS21002FB06',
 ROOM='',
 PART_NUMBER='CS21002FB06',
 VALUE='1K',
 PRIM_FILE='./archive_libs/logical/q_res/chips/chips.prt';

PART_NAME
 R104 'Q_RES_0402LF-1K,1%,1/16W,EMPTY,CS21002FB06':
 ROOM='';

SECTION_NUMBER 1
 '@T6G_MB_LIB.T6G(SCH_1):PAGE98_I190@PURE_QUANTA.Q_RES(CHIPS)':
 C_PATH='@t6g_mb_lib.t6g(sch_1):page98_i190@pure_quanta.q_res(chips)',
 P_PATH='@t6g_mb_lib.t6g(sch_1):page99_i190@pure_quanta.q_res(chips)',
 PATH='I190',
 DRAWING='@T6G_MB_LIB.T6G(SCH_1):PAGE98',
 BOM_COST='MEM',
 WATTAGE='1/16W',
 TOLERANCE='1%',
 MATERIAL='EMPTY',
 PHYS_PAGE='99',
 XY='(-8500,2425)',
 ROT='0',
 VER='2',
 PACK_TYPE='0402LF',
 LOCATION='R104',
 CDS_LIB='pure_quanta',
 CDS_PART_NAME='Q_RES_0402LF-1K,1%,1/16W,EMPTY,CS21002FB06',
 ROOM='',
 PART_NUMBER='CS21002FB06',
 VALUE='1K',
 PRIM_FILE='./archive_libs/logical/q_res/chips/chips.prt';

PART_NAME
 R105 'Q_RES_0402LF-1K,1%,1/16W,EMPTY,CS21002FB06':
 ROOM='';

SECTION_NUMBER 1
 '@T6G_MB_LIB.T6G(SCH_1):PAGE99_I190@PURE_QUANTA.Q_RES(CHIPS)':
 C_PATH='@t6g_mb_lib.t6g(sch_1):page99_i190@pure_quanta.q_res(chips)',
 P_PATH='@t6g_mb_lib.t6g(sch_1):page100_i190@pure_quanta.q_res(chips)',
 PATH='I190',
 DRAWING='@T6G_MB_LIB.T6G(SCH_1):PAGE99',
 BOM_COST='MEM',
 WATTAGE='1/16W',
 TOLERANCE='1%',
 MATERIAL='EMPTY',
 PHYS_PAGE='100',
 XY='(-8575,2300)',
 ROT='0',
 VER='2',
 PACK_TYPE='0402LF',
 LOCATION='R105',
 CDS_LIB='pure_quanta',
 CDS_PART_NAME='Q_RES_0402LF-1K,1%,1/16W,EMPTY,CS21002FB06',
 ROOM='',
 PART_NUMBER='CS21002FB06',
 VALUE='1K',
 PRIM_FILE='./archive_libs/logical/q_res/chips/chips.prt';

PART_NAME
 R106 'Q_RES_0402LF-1K,1%,1/16W,EMPTY,CS21002FB06':
 ROOM='';

SECTION_NUMBER 1
 '@T6G_MB_LIB.T6G(SCH_1):PAGE100_I190@PURE_QUANTA.Q_RES(CHIPS)':
 C_PATH='@t6g_mb_lib.t6g(sch_1):page100_i190@pure_quanta.q_res(chips)',
 P_PATH='@t6g_mb_lib.t6g(sch_1):page101_i190@pure_quanta.q_res(chips)',
 PATH='I190',
 DRAWING='@T6G_MB_LIB.T6G(SCH_1):PAGE100',
 BOM_COST='MEM',
 WATTAGE='1/16W',
 TOLERANCE='1%',
 MATERIAL='EMPTY',
 PHYS_PAGE='101',
 XY='(-8475,2475)',
 ROT='0',
 VER='2',
 PACK_TYPE='0402LF',
 LOCATION='R106',
 CDS_LIB='pure_quanta',
 CDS_PART_NAME='Q_RES_0402LF-1K,1%,1/16W,EMPTY,CS21002FB06',
 ROOM='',
 PART_NUMBER='CS21002FB06',
 VALUE='1K',
 PRIM_FILE='./archive_libs/logical/q_res/chips/chips.prt';

PART_NAME
 R107 'Q_RES_0402LF-1K,1%,1/16W,EMPTY,CS21002FB06':
 ROOM='';

SECTION_NUMBER 1
 '@T6G_MB_LIB.T6G(SCH_1):PAGE101_I190@PURE_QUANTA.Q_RES(CHIPS)':
 C_PATH='@t6g_mb_lib.t6g(sch_1):page101_i190@pure_quanta.q_res(chips)',
 P_PATH='@t6g_mb_lib.t6g(sch_1):page102_i190@pure_quanta.q_res(chips)',
 PATH='I190',
 DRAWING='@T6G_MB_LIB.T6G(SCH_1):PAGE101',
 BOM_COST='MEM',
 WATTAGE='1/16W',
 TOLERANCE='1%',
 MATERIAL='EMPTY',
 PHYS_PAGE='102',
 XY='(-8500,2550)',
 ROT='0',
 VER='2',
 PACK_TYPE='0402LF',
 LOCATION='R107',
 CDS_LIB='pure_quanta',
 CDS_PART_NAME='Q_RES_0402LF-1K,1%,1/16W,EMPTY,CS21002FB06',
 ROOM='',
 PART_NUMBER='CS21002FB06',
 VALUE='1K',
 PRIM_FILE='./archive_libs/logical/q_res/chips/chips.prt';

PART_NAME
 R108 'Q_RES_0402LF-1K,1%,1/16W,EMPTY,CS21002FB06':
 ROOM='';

SECTION_NUMBER 1
 '@T6G_MB_LIB.T6G(SCH_1):PAGE102_I190@PURE_QUANTA.Q_RES(CHIPS)':
 C_PATH='@t6g_mb_lib.t6g(sch_1):page102_i190@pure_quanta.q_res(chips)',
 P_PATH='@t6g_mb_lib.t6g(sch_1):page103_i190@pure_quanta.q_res(chips)',
 PATH='I190',
 DRAWING='@T6G_MB_LIB.T6G(SCH_1):PAGE102',
 BOM_COST='MEM',
 WATTAGE='1/16W',
 TOLERANCE='1%',
 MATERIAL='EMPTY',
 PHYS_PAGE='103',
 XY='(-8475,2425)',
 ROT='0',
 VER='2',
 PACK_TYPE='0402LF',
 LOCATION='R108',
 CDS_LIB='pure_quanta',
 CDS_PART_NAME='Q_RES_0402LF-1K,1%,1/16W,EMPTY,CS21002FB06',
 ROOM='',
 PART_NUMBER='CS21002FB06',
 VALUE='1K',
 PRIM_FILE='./archive_libs/logical/q_res/chips/chips.prt';

PART_NAME
 R109 'Q_RES_0402LF-1K,1%,1/16W,EMPTY,CS21002FB06':
 ROOM='';

SECTION_NUMBER 1
 '@T6G_MB_LIB.T6G(SCH_1):PAGE103_I189@PURE_QUANTA.Q_RES(CHIPS)':
 C_PATH='@t6g_mb_lib.t6g(sch_1):page103_i189@pure_quanta.q_res(chips)',
 P_PATH='@t6g_mb_lib.t6g(sch_1):page104_i189@pure_quanta.q_res(chips)',
 PATH='I189',
 DRAWING='@T6G_MB_LIB.T6G(SCH_1):PAGE103',
 BOM_COST='MEM',
 WATTAGE='1/16W',
 TOLERANCE='1%',
 MATERIAL='EMPTY',
 PHYS_PAGE='104',
 XY='(-8525,2250)',
 ROT='2',
 VER='2',
 PACK_TYPE='0402LF',
 LOCATION='R109',
 CDS_LIB='pure_quanta',
 CDS_PART_NAME='Q_RES_0402LF-1K,1%,1/16W,EMPTY,CS21002FB06',
 ROOM='',
 PART_NUMBER='CS21002FB06',
 VALUE='1K',
 PRIM_FILE='./archive_libs/logical/q_res/chips/chips.prt';

PART_NAME
 R110 'Q_RES_0402LF-1K,1%,1/16W,EMPTY,CS21002FB06':
 ROOM='';

SECTION_NUMBER 1
 '@T6G_MB_LIB.T6G(SCH_1):PAGE103_I192@PURE_QUANTA.Q_RES(CHIPS)':
 C_PATH='@t6g_mb_lib.t6g(sch_1):page103_i192@pure_quanta.q_res(chips)',
 P_PATH='@t6g_mb_lib.t6g(sch_1):page104_i192@pure_quanta.q_res(chips)',
 PATH='I192',
 DRAWING='@T6G_MB_LIB.T6G(SCH_1):PAGE103',
 BOM_COST='MEM',
 WATTAGE='1/16W',
 TOLERANCE='1%',
 MATERIAL='EMPTY',
 PHYS_PAGE='104',
 XY='(-8275,2250)',
 ROT='0',
 VER='2',
 PACK_TYPE='0402LF',
 LOCATION='R110',
 CDS_LIB='pure_quanta',
 CDS_PART_NAME='Q_RES_0402LF-1K,1%,1/16W,EMPTY,CS21002FB06',
 ROOM='',
 PART_NUMBER='CS21002FB06',
 VALUE='1K',
 PRIM_FILE='./archive_libs/logical/q_res/chips/chips.prt';

PART_NAME
 R111 'Q_RES_0402LF-1K,1%,1/16W,EMPTY,CS21002FB06':
 ROOM='';

SECTION_NUMBER 1
 '@T6G_MB_LIB.T6G(SCH_1):PAGE104_I190@PURE_QUANTA.Q_RES(CHIPS)':
 C_PATH='@t6g_mb_lib.t6g(sch_1):page104_i190@pure_quanta.q_res(chips)',
 P_PATH='@t6g_mb_lib.t6g(sch_1):page105_i190@pure_quanta.q_res(chips)',
 PATH='I190',
 DRAWING='@T6G_MB_LIB.T6G(SCH_1):PAGE104',
 BOM_COST='MEM',
 WATTAGE='1/16W',
 TOLERANCE='1%',
 MATERIAL='EMPTY',
 PHYS_PAGE='105',
 XY='(-8350,2300)',
 ROT='0',
 VER='2',
 PACK_TYPE='0402LF',
 LOCATION='R111',
 CDS_LIB='pure_quanta',
 CDS_PART_NAME='Q_RES_0402LF-1K,1%,1/16W,EMPTY,CS21002FB06',
 ROOM='',
 PART_NUMBER='CS21002FB06',
 VALUE='1K',
 PRIM_FILE='./archive_libs/logical/q_res/chips/chips.prt';

PART_NAME
 R112 'Q_RES_0402LF-1K,1%,1/16W,EMPTY,CS21002FB06':
 ROOM='';

SECTION_NUMBER 1
 '@T6G_MB_LIB.T6G(SCH_1):PAGE105_I190@PURE_QUANTA.Q_RES(CHIPS)':
 C_PATH='@t6g_mb_lib.t6g(sch_1):page105_i190@pure_quanta.q_res(chips)',
 P_PATH='@t6g_mb_lib.t6g(sch_1):page106_i190@pure_quanta.q_res(chips)',
 PATH='I190',
 DRAWING='@T6G_MB_LIB.T6G(SCH_1):PAGE105',
 BOM_COST='MEM',
 WATTAGE='1/16W',
 TOLERANCE='1%',
 MATERIAL='EMPTY',
 PHYS_PAGE='106',
 XY='(-8350,2250)',
 ROT='0',
 VER='2',
 PACK_TYPE='0402LF',
 LOCATION='R112',
 CDS_LIB='pure_quanta',
 CDS_PART_NAME='Q_RES_0402LF-1K,1%,1/16W,EMPTY,CS21002FB06',
 ROOM='',
 PART_NUMBER='CS21002FB06',
 VALUE='1K',
 PRIM_FILE='./archive_libs/logical/q_res/chips/chips.prt';

PART_NAME
 R113 'Q_RES_0402LF-1K,1%,1/16W,EMPTY,CS21002FB06':
 ROOM='';

SECTION_NUMBER 1
 '@T6G_MB_LIB.T6G(SCH_1):PAGE106_I190@PURE_QUANTA.Q_RES(CHIPS)':
 C_PATH='@t6g_mb_lib.t6g(sch_1):page106_i190@pure_quanta.q_res(chips)',
 P_PATH='@t6g_mb_lib.t6g(sch_1):page107_i190@pure_quanta.q_res(chips)',
 PATH='I190',
 DRAWING='@T6G_MB_LIB.T6G(SCH_1):PAGE106',
 BOM_COST='MEM',
 WATTAGE='1/16W',
 TOLERANCE='1%',
 MATERIAL='EMPTY',
 PHYS_PAGE='107',
 XY='(-8250,2225)',
 ROT='0',
 VER='2',
 PACK_TYPE='0402LF',
 LOCATION='R113',
 CDS_LIB='pure_quanta',
 CDS_PART_NAME='Q_RES_0402LF-1K,1%,1/16W,EMPTY,CS21002FB06',
 ROOM='',
 PART_NUMBER='CS21002FB06',
 VALUE='1K',
 PRIM_FILE='./archive_libs/logical/q_res/chips/chips.prt';

PART_NAME
 R114 'Q_RES_0402LF-1K,1%,1/16W,EMPTY,CS21002FB06':
 ROOM='';

SECTION_NUMBER 1
 '@T6G_MB_LIB.T6G(SCH_1):PAGE107_I190@PURE_QUANTA.Q_RES(CHIPS)':
 C_PATH='@t6g_mb_lib.t6g(sch_1):page107_i190@pure_quanta.q_res(chips)',
 P_PATH='@t6g_mb_lib.t6g(sch_1):page108_i190@pure_quanta.q_res(chips)',
 PATH='I190',
 DRAWING='@T6G_MB_LIB.T6G(SCH_1):PAGE107',
 BOM_COST='MEM',
 WATTAGE='1/16W',
 TOLERANCE='1%',
 MATERIAL='EMPTY',
 PHYS_PAGE='108',
 XY='(-8375,2225)',
 ROT='0',
 VER='2',
 PACK_TYPE='0402LF',
 LOCATION='R114',
 CDS_LIB='pure_quanta',
 CDS_PART_NAME='Q_RES_0402LF-1K,1%,1/16W,EMPTY,CS21002FB06',
 ROOM='',
 PART_NUMBER='CS21002FB06',
 VALUE='1K',
 PRIM_FILE='./archive_libs/logical/q_res/chips/chips.prt';

PART_NAME
 R115 'Q_RES_0402LF-1K,1%,1/16W,EMPTY,CS21002FB06':
 ROOM='';

SECTION_NUMBER 1
 '@T6G_MB_LIB.T6G(SCH_1):PAGE108_I190@PURE_QUANTA.Q_RES(CHIPS)':
 C_PATH='@t6g_mb_lib.t6g(sch_1):page108_i190@pure_quanta.q_res(chips)',
 P_PATH='@t6g_mb_lib.t6g(sch_1):page109_i190@pure_quanta.q_res(chips)',
 PATH='I190',
 DRAWING='@T6G_MB_LIB.T6G(SCH_1):PAGE108',
 BOM_COST='MEM',
 WATTAGE='1/16W',
 TOLERANCE='1%',
 MATERIAL='EMPTY',
 PHYS_PAGE='109',
 XY='(-8325,2300)',
 ROT='0',
 VER='2',
 PACK_TYPE='0402LF',
 LOCATION='R115',
 CDS_LIB='pure_quanta',
 CDS_PART_NAME='Q_RES_0402LF-1K,1%,1/16W,EMPTY,CS21002FB06',
 ROOM='',
 PART_NUMBER='CS21002FB06',
 VALUE='1K',
 PRIM_FILE='./archive_libs/logical/q_res/chips/chips.prt';

PART_NAME
 R116 'Q_RES_0402LF-33,5%,1/16W,CHIP,CS03302JB10':;

SECTION_NUMBER 1
 '@T6G_MB_LIB.T6G(SCH_1):PAGE132_I5@PURE_QUANTA.Q_RES(CHIPS)':
 C_PATH='@t6g_mb_lib.t6g(sch_1):page132_i5@pure_quanta.q_res(chips)',
 P_PATH='@t6g_mb_lib.t6g(sch_1):page155_i5@pure_quanta.q_res(chips)',
 PATH='I5',
 DRAWING='@T6G_MB_LIB.T6G(SCH_1):PAGE132',
 BOM_COST='PCH',
 WATTAGE='1/16W',
 TOLERANCE='5%',
 MATERIAL='CHIP',
 PHYS_PAGE='155',
 XY='(-5925,3450)',
 ROT='0',
 VER='1',
 PACK_TYPE='0402LF',
 LOCATION='R116',
 CDS_LIB='pure_quanta',
 CDS_PART_NAME='Q_RES_0402LF-33,5%,1/16W,CHIP,CS03302JB10',
 PART_NUMBER='CS03302JB10',
 VALUE='33',
 PRIM_FILE='./archive_libs/logical/q_res/chips/chips.prt';

PART_NAME
 R117 'Q_RES_0402LF-1K,1%,1/16W,CHIP,CS21002FB06':;

SECTION_NUMBER 1
 '@T6G_MB_LIB.T6G(SCH_1):PAGE182_I38@PURE_QUANTA.Q_RES(CHIPS)':
 C_PATH='@t6g_mb_lib.t6g(sch_1):page182_i38@pure_quanta.q_res(chips)',
 P_PATH='@t6g_mb_lib.t6g(sch_1):page207_i38@pure_quanta.q_res(chips)',
 PATH='I38',
 DRAWING='@T6G_MB_LIB.T6G(SCH_1):PAGE182',
 WATTAGE='1/16W',
 TOLERANCE='1%',
 MATERIAL='CHIP',
 PHYS_PAGE='207',
 XY='(-6225,6400)',
 ROT='0',
 VER='1',
 PACK_TYPE='0402LF',
 LOCATION='R117',
 CDS_LIB='pure_quanta',
 CDS_PART_NAME='Q_RES_0402LF-1K,1%,1/16W,CHIP,CS21002FB06',
 PART_NUMBER='CS21002FB06',
 VALUE='1K',
 PRIM_FILE='./archive_libs/logical/q_res/chips/chips.prt';

PART_NAME
 R118 'Q_RES_0402LF-0,5%,1/16W,CHIP,CS00002JB13':;

SECTION_NUMBER 1
 '@T6G_MB_LIB.T6G(SCH_1):PAGE182_I41@PURE_QUANTA.Q_RES(CHIPS)':
 C_PATH='@t6g_mb_lib.t6g(sch_1):page182_i41@pure_quanta.q_res(chips)',
 P_PATH='@t6g_mb_lib.t6g(sch_1):page207_i41@pure_quanta.q_res(chips)',
 PATH='I41',
 DRAWING='@T6G_MB_LIB.T6G(SCH_1):PAGE182',
 WATTAGE='1/16W',
 TOLERANCE='5%',
 MATERIAL='CHIP',
 PHYS_PAGE='207',
 XY='(-6075,4975)',
 ROT='0',
 VER='1',
 PACK_TYPE='0402LF',
 LOCATION='R118',
 CDS_LIB='pure_quanta',
 CDS_PART_NAME='Q_RES_0402LF-0,5%,1/16W,CHIP,CS00002JB13',
 PART_NUMBER='CS00002JB13',
 VALUE='0',
 PRIM_FILE='./archive_libs/logical/q_res/chips/chips.prt';

PART_NAME
 R119 'Q_RES_0402LF-0,5%,1/16W,CHIP,CS00002JB13':;

SECTION_NUMBER 1
 '@T6G_MB_LIB.T6G(SCH_1):PAGE182_I40@PURE_QUANTA.Q_RES(CHIPS)':
 C_PATH='@t6g_mb_lib.t6g(sch_1):page182_i40@pure_quanta.q_res(chips)',
 P_PATH='@t6g_mb_lib.t6g(sch_1):page207_i40@pure_quanta.q_res(chips)',
 PATH='I40',
 DRAWING='@T6G_MB_LIB.T6G(SCH_1):PAGE182',
 WATTAGE='1/16W',
 TOLERANCE='5%',
 MATERIAL='CHIP',
 PHYS_PAGE='207',
 XY='(-6075,4825)',
 ROT='0',
 VER='1',
 PACK_TYPE='0402LF',
 LOCATION='R119',
 CDS_LIB='pure_quanta',
 CDS_PART_NAME='Q_RES_0402LF-0,5%,1/16W,CHIP,CS00002JB13',
 PART_NUMBER='CS00002JB13',
 VALUE='0',
 PRIM_FILE='./archive_libs/logical/q_res/chips/chips.prt';

PART_NAME
 R120 'Q_RES_0402LF-33,5%,1/16W,CHIP,CS03302JB10':;

SECTION_NUMBER 1
 '@T6G_MB_LIB.T6G(SCH_1):PAGE182_I39@PURE_QUANTA.Q_RES(CHIPS)':
 C_PATH='@t6g_mb_lib.t6g(sch_1):page182_i39@pure_quanta.q_res(chips)',
 P_PATH='@t6g_mb_lib.t6g(sch_1):page207_i39@pure_quanta.q_res(chips)',
 PATH='I39',
 DRAWING='@T6G_MB_LIB.T6G(SCH_1):PAGE182',
 WATTAGE='1/16W',
 TOLERANCE='5%',
 MATERIAL='CHIP',
 PHYS_PAGE='207',
 XY='(-6075,4675)',
 ROT='0',
 VER='1',
 PACK_TYPE='0402LF',
 LOCATION='R120',
 CDS_LIB='pure_quanta',
 CDS_PART_NAME='Q_RES_0402LF-33,5%,1/16W,CHIP,CS03302JB10',
 PART_NUMBER='CS03302JB10',
 VALUE='33',
 PRIM_FILE='./archive_libs/logical/q_res/chips/chips.prt';

PART_NAME
 R121 'Q_RES_0402LF-0,5%,1/16W,CHIP,CS00002JB13':;

SECTION_NUMBER 1
 '@T6G_MB_LIB.T6G(SCH_1):PAGE361_I122@PURE_QUANTA.Q_RES(CHIPS)':
 C_PATH='@t6g_mb_lib.t6g(sch_1):page361_i122@pure_quanta.q_res(chips)',
 P_PATH='@t6g_mb_lib.t6g(sch_1):page238_i122@pure_quanta.q_res(chips)',
 PATH='I122',
 DRAWING='@T6G_MB_LIB.T6G(SCH_1):PAGE361',
 WATTAGE='1/16W',
 TOLERANCE='5%',
 MATERIAL='CHIP',
 PHYS_PAGE='238',
 XY='(-2325,1050)',
 ROT='0',
 VER='1',
 PACK_TYPE='0402LF',
 LOCATION='R121',
 CDS_LIB='pure_quanta',
 CDS_PART_NAME='Q_RES_0402LF-0,5%,1/16W,CHIP,CS00002JB13',
 PART_NUMBER='CS00002JB13',
 VALUE='0',
 PRIM_FILE='./archive_libs/logical/q_res/chips/chips.prt';

PART_NAME
 R122 'Q_RES_0402LF-0,5%,1/16W,CHIP,CS00002JB13':;

SECTION_NUMBER 1
 '@T6G_MB_LIB.T6G(SCH_1):PAGE182_I44@PURE_QUANTA.Q_RES(CHIPS)':
 C_PATH='@t6g_mb_lib.t6g(sch_1):page182_i44@pure_quanta.q_res(chips)',
 P_PATH='@t6g_mb_lib.t6g(sch_1):page207_i44@pure_quanta.q_res(chips)',
 PATH='I44',
 DRAWING='@T6G_MB_LIB.T6G(SCH_1):PAGE182',
 WATTAGE='1/16W',
 TOLERANCE='5%',
 MATERIAL='CHIP',
 PHYS_PAGE='207',
 XY='(-6000,6125)',
 ROT='0',
 VER='1',
 PACK_TYPE='0402LF',
 LOCATION='R122',
 CDS_LIB='pure_quanta',
 CDS_PART_NAME='Q_RES_0402LF-0,5%,1/16W,CHIP,CS00002JB13',
 PART_NUMBER='CS00002JB13',
 VALUE='0',
 PRIM_FILE='./archive_libs/logical/q_res/chips/chips.prt';

PART_NAME
 R123 'Q_RES_0402LF-0,5%,1/16W,CHIP,CS00002JB13':;

SECTION_NUMBER 1
 '@T6G_MB_LIB.T6G(SCH_1):PAGE182_I43@PURE_QUANTA.Q_RES(CHIPS)':
 C_PATH='@t6g_mb_lib.t6g(sch_1):page182_i43@pure_quanta.q_res(chips)',
 P_PATH='@t6g_mb_lib.t6g(sch_1):page207_i43@pure_quanta.q_res(chips)',
 PATH='I43',
 DRAWING='@T6G_MB_LIB.T6G(SCH_1):PAGE182',
 WATTAGE='1/16W',
 TOLERANCE='5%',
 MATERIAL='CHIP',
 PHYS_PAGE='207',
 XY='(-6000,5975)',
 ROT='0',
 VER='1',
 PACK_TYPE='0402LF',
 LOCATION='R123',
 CDS_LIB='pure_quanta',
 CDS_PART_NAME='Q_RES_0402LF-0,5%,1/16W,CHIP,CS00002JB13',
 PART_NUMBER='CS00002JB13',
 VALUE='0',
 PRIM_FILE='./archive_libs/logical/q_res/chips/chips.prt';

PART_NAME
 R124 'Q_RES_0402LF-1K,1%,1/16W,EMPTY,CS21002FB06':;

SECTION_NUMBER 1
 '@T6G_MB_LIB.T6G(SCH_1):PAGE182_I25@PURE_QUANTA.Q_RES(CHIPS)':
 C_PATH='@t6g_mb_lib.t6g(sch_1):page182_i25@pure_quanta.q_res(chips)',
 P_PATH='@t6g_mb_lib.t6g(sch_1):page207_i25@pure_quanta.q_res(chips)',
 PATH='I25',
 DRAWING='@T6G_MB_LIB.T6G(SCH_1):PAGE182',
 WATTAGE='1/16W',
 TOLERANCE='1%',
 MATERIAL='EMPTY',
 PHYS_PAGE='207',
 XY='(-6000,2350)',
 ROT='0',
 VER='2',
 PACK_TYPE='0402LF',
 LOCATION='R124',
 CDS_LIB='pure_quanta',
 CDS_PART_NAME='Q_RES_0402LF-1K,1%,1/16W,EMPTY,CS21002FB06',
 PART_NUMBER='CS21002FB06',
 VALUE='1K',
 PRIM_FILE='./archive_libs/logical/q_res/chips/chips.prt';

PART_NAME
 R125 'Q_RES_0402LF-0,5%,1/16W,CHIP,CS00002JB13':;

SECTION_NUMBER 1
 '@T6G_MB_LIB.T6G(SCH_1):PAGE361_I123@PURE_QUANTA.Q_RES(CHIPS)':
 C_PATH='@t6g_mb_lib.t6g(sch_1):page361_i123@pure_quanta.q_res(chips)',
 P_PATH='@t6g_mb_lib.t6g(sch_1):page238_i123@pure_quanta.q_res(chips)',
 PATH='I123',
 DRAWING='@T6G_MB_LIB.T6G(SCH_1):PAGE361',
 WATTAGE='1/16W',
 TOLERANCE='5%',
 MATERIAL='CHIP',
 PHYS_PAGE='238',
 XY='(-2325,1000)',
 ROT='0',
 VER='1',
 PACK_TYPE='0402LF',
 LOCATION='R125',
 CDS_LIB='pure_quanta',
 CDS_PART_NAME='Q_RES_0402LF-0,5%,1/16W,CHIP,CS00002JB13',
 PART_NUMBER='CS00002JB13',
 VALUE='0',
 PRIM_FILE='./archive_libs/logical/q_res/chips/chips.prt';

PART_NAME
 R126 'Q_RES_0402LF-10K,1%,1/16W,CHIP,CS31002FB08':;

SECTION_NUMBER 1
 '@T6G_MB_LIB.T6G(SCH_1):PAGE82_I163@PURE_QUANTA.Q_RES(CHIPS)':
 C_PATH='@t6g_mb_lib.t6g(sch_1):page82_i163@pure_quanta.q_res(chips)',
 P_PATH='@t6g_mb_lib.t6g(sch_1):page83_i163@pure_quanta.q_res(chips)',
 PATH='I163',
 DRAWING='@T6G_MB_LIB.T6G(SCH_1):PAGE82',
 BOM_COST='MEM',
 WATTAGE='1/16W',
 TOLERANCE='1%',
 MATERIAL='CHIP',
 PHYS_PAGE='83',
 XY='(-4250,3250)',
 ROT='0',
 VER='2',
 PACK_TYPE='0402LF',
 LOCATION='R126',
 CDS_LIB='pure_quanta',
 CDS_PART_NAME='Q_RES_0402LF-10K,1%,1/16W,CHIP,CS31002FB08',
 PART_NUMBER='CS31002FB08',
 VALUE='10K',
 PRIM_FILE='./archive_libs/logical/q_res/chips/chips.prt';

PART_NAME
 R127 'Q_RES_0402LF-1K,1%,1/16W,EMPTY,CS21002FB06':;

SECTION_NUMBER 1
 '@T6G_MB_LIB.T6G(SCH_1):PAGE76_I117@PURE_QUANTA.Q_RES(CHIPS)':
 C_PATH='@t6g_mb_lib.t6g(sch_1):page76_i117@pure_quanta.q_res(chips)',
 P_PATH='@t6g_mb_lib.t6g(sch_1):page77_i117@pure_quanta.q_res(chips)',
 PATH='I117',
 DRAWING='@T6G_MB_LIB.T6G(SCH_1):PAGE76',
 WATTAGE='1/16W',
 TOLERANCE='1%',
 MATERIAL='EMPTY',
 PHYS_PAGE='77',
 XY='(-1700,5625)',
 ROT='2',
 VER='2',
 PACK_TYPE='0402LF',
 LOCATION='R127',
 CDS_LIB='pure_quanta',
 CDS_PART_NAME='Q_RES_0402LF-1K,1%,1/16W,EMPTY,CS21002FB06',
 PART_NUMBER='CS21002FB06',
 VALUE='1K',
 PRIM_FILE='./archive_libs/logical/q_res/chips/chips.prt';

PART_NAME
 R128 'Q_RES_0402LF-1K,1%,1/16W,EMPTY,CS21002FB06':;

SECTION_NUMBER 1
 '@T6G_MB_LIB.T6G(SCH_1):PAGE76_I118@PURE_QUANTA.Q_RES(CHIPS)':
 C_PATH='@t6g_mb_lib.t6g(sch_1):page76_i118@pure_quanta.q_res(chips)',
 P_PATH='@t6g_mb_lib.t6g(sch_1):page77_i118@pure_quanta.q_res(chips)',
 PATH='I118',
 DRAWING='@T6G_MB_LIB.T6G(SCH_1):PAGE76',
 WATTAGE='1/16W',
 TOLERANCE='1%',
 MATERIAL='EMPTY',
 PHYS_PAGE='77',
 XY='(-1525,5625)',
 ROT='2',
 VER='2',
 PACK_TYPE='0402LF',
 LOCATION='R128',
 CDS_LIB='pure_quanta',
 CDS_PART_NAME='Q_RES_0402LF-1K,1%,1/16W,EMPTY,CS21002FB06',
 PART_NUMBER='CS21002FB06',
 VALUE='1K',
 PRIM_FILE='./archive_libs/logical/q_res/chips/chips.prt';

PART_NAME
 R129 'Q_RES_0402LF-1K,1%,1/16W,EMPTY,CS21002FB06':;

SECTION_NUMBER 1
 '@T6G_MB_LIB.T6G(SCH_1):PAGE76_I119@PURE_QUANTA.Q_RES(CHIPS)':
 C_PATH='@t6g_mb_lib.t6g(sch_1):page76_i119@pure_quanta.q_res(chips)',
 P_PATH='@t6g_mb_lib.t6g(sch_1):page77_i119@pure_quanta.q_res(chips)',
 PATH='I119',
 DRAWING='@T6G_MB_LIB.T6G(SCH_1):PAGE76',
 WATTAGE='1/16W',
 TOLERANCE='1%',
 MATERIAL='EMPTY',
 PHYS_PAGE='77',
 XY='(-1350,5625)',
 ROT='2',
 VER='2',
 PACK_TYPE='0402LF',
 LOCATION='R129',
 CDS_LIB='pure_quanta',
 CDS_PART_NAME='Q_RES_0402LF-1K,1%,1/16W,EMPTY,CS21002FB06',
 PART_NUMBER='CS21002FB06',
 VALUE='1K',
 PRIM_FILE='./archive_libs/logical/q_res/chips/chips.prt';

PART_NAME
 R130 'Q_RES_0402LF-10K,5%,1/16W,EMPTY,CS31002JB08':;

SECTION_NUMBER 1
 '@T6G_MB_LIB.T6G(SCH_1):PAGE349_I113@PURE_QUANTA.Q_RES(CHIPS)':
 C_PATH='@t6g_mb_lib.t6g(sch_1):page349_i113@pure_quanta.q_res(chips)',
 P_PATH='@t6g_mb_lib.t6g(sch_1):page151_i113@pure_quanta.q_res(chips)',
 PATH='I113',
 DRAWING='@T6G_MB_LIB.T6G(SCH_1):PAGE349',
 WATTAGE='1/16W',
 TOLERANCE='5%',
 MATERIAL='EMPTY',
 PHYS_PAGE='151',
 XY='(4450,1225)',
 ROT='1',
 VER='1',
 PACK_TYPE='0402LF',
 LOCATION='R130',
 CDS_LIB='pure_quanta',
 CDS_PART_NAME='Q_RES_0402LF-10K,5%,1/16W,EMPTY,CS31002JB08',
 PART_NUMBER='CS31002JB08',
 VALUE='10K',
 PRIM_FILE='./archive_libs/logical/q_res/chips/chips.prt';

PART_NAME
 R131 'Q_RES_0402LF-10K,5%,1/16W,CHIP,CS31002JB08':;

SECTION_NUMBER 1
 '@T6G_MB_LIB.T6G(SCH_1):PAGE349_I116@PURE_QUANTA.Q_RES(CHIPS)':
 C_PATH='@t6g_mb_lib.t6g(sch_1):page349_i116@pure_quanta.q_res(chips)',
 P_PATH='@t6g_mb_lib.t6g(sch_1):page151_i116@pure_quanta.q_res(chips)',
 PATH='I116',
 DRAWING='@T6G_MB_LIB.T6G(SCH_1):PAGE349',
 WATTAGE='1/16W',
 TOLERANCE='5%',
 MATERIAL='CHIP',
 PHYS_PAGE='151',
 XY='(4675,1200)',
 ROT='0',
 VER='2',
 PACK_TYPE='0402LF',
 LOCATION='R131',
 CDS_LIB='pure_quanta',
 CDS_PART_NAME='Q_RES_0402LF-10K,5%,1/16W,CHIP,CS31002JB08',
 PART_NUMBER='CS31002JB08',
 VALUE='10K',
 PRIM_FILE='./archive_libs/logical/q_res/chips/chips.prt';

PART_NAME
 R132 'Q_RES_0402LF-0,5%,1/16W,CHIP,CS00002JB13':;

SECTION_NUMBER 1
 '@T6G_MB_LIB.T6G(SCH_1):PAGE81_I168@PURE_QUANTA.Q_RES(CHIPS)':
 C_PATH='@t6g_mb_lib.t6g(sch_1):page81_i168@pure_quanta.q_res(chips)',
 P_PATH='@t6g_mb_lib.t6g(sch_1):page82_i168@pure_quanta.q_res(chips)',
 PATH='I168',
 DRAWING='@T6G_MB_LIB.T6G(SCH_1):PAGE81',
 BOM_COST='MEM',
 WATTAGE='1/16W',
 TOLERANCE='5%',
 MATERIAL='CHIP',
 PHYS_PAGE='82',
 XY='(-6450,4475)',
 ROT='0',
 VER='1',
 PACK_TYPE='0402LF',
 LOCATION='R132',
 CDS_LIB='pure_quanta',
 CDS_PART_NAME='Q_RES_0402LF-0,5%,1/16W,CHIP,CS00002JB13',
 PART_NUMBER='CS00002JB13',
 VALUE='0',
 PRIM_FILE='./archive_libs/logical/q_res/chips/chips.prt';

PART_NAME
 R133 'Q_RES_0402LF-0,5%,1/16W,CHIP,CS00002JB13':;

SECTION_NUMBER 1
 '@T6G_MB_LIB.T6G(SCH_1):PAGE81_I169@PURE_QUANTA.Q_RES(CHIPS)':
 C_PATH='@t6g_mb_lib.t6g(sch_1):page81_i169@pure_quanta.q_res(chips)',
 P_PATH='@t6g_mb_lib.t6g(sch_1):page82_i169@pure_quanta.q_res(chips)',
 PATH='I169',
 DRAWING='@T6G_MB_LIB.T6G(SCH_1):PAGE81',
 BOM_COST='MEM',
 WATTAGE='1/16W',
 TOLERANCE='5%',
 MATERIAL='CHIP',
 PHYS_PAGE='82',
 XY='(-6450,4425)',
 ROT='0',
 VER='1',
 PACK_TYPE='0402LF',
 LOCATION='R133',
 CDS_LIB='pure_quanta',
 CDS_PART_NAME='Q_RES_0402LF-0,5%,1/16W,CHIP,CS00002JB13',
 PART_NUMBER='CS00002JB13',
 VALUE='0',
 PRIM_FILE='./archive_libs/logical/q_res/chips/chips.prt';

PART_NAME
 R134 'Q_RES_0402LF-4.7K,5%,1/16W,EMPTY,CS24702JB10':;

SECTION_NUMBER 1
 '@T6G_MB_LIB.T6G(SCH_1):PAGE82_I156@PURE_QUANTA.Q_RES(CHIPS)':
 C_PATH='@t6g_mb_lib.t6g(sch_1):page82_i156@pure_quanta.q_res(chips)',
 P_PATH='@t6g_mb_lib.t6g(sch_1):page83_i156@pure_quanta.q_res(chips)',
 PATH='I156',
 DRAWING='@T6G_MB_LIB.T6G(SCH_1):PAGE82',
 WATTAGE='1/16W',
 TOLERANCE='5%',
 MATERIAL='EMPTY',
 PHYS_PAGE='83',
 XY='(-7050,4925)',
 ROT='0',
 VER='1',
 PACK_TYPE='0402LF',
 LOCATION='R134',
 CDS_LIB='pure_quanta',
 CDS_PART_NAME='Q_RES_0402LF-4.7K,5%,1/16W,EMPTY,CS24702JB10',
 PART_NUMBER='CS24702JB10',
 VALUE='4.7K',
 PRIM_FILE='./archive_libs/logical/q_res/chips/chips.prt';

PART_NAME
 R135 'Q_RES_0402LF-4.7K,5%,1/16W,EMPTY,CS24702JB10':;

SECTION_NUMBER 1
 '@T6G_MB_LIB.T6G(SCH_1):PAGE82_I157@PURE_QUANTA.Q_RES(CHIPS)':
 C_PATH='@t6g_mb_lib.t6g(sch_1):page82_i157@pure_quanta.q_res(chips)',
 P_PATH='@t6g_mb_lib.t6g(sch_1):page83_i157@pure_quanta.q_res(chips)',
 PATH='I157',
 DRAWING='@T6G_MB_LIB.T6G(SCH_1):PAGE82',
 WATTAGE='1/16W',
 TOLERANCE='5%',
 MATERIAL='EMPTY',
 PHYS_PAGE='83',
 XY='(-7050,4875)',
 ROT='0',
 VER='1',
 PACK_TYPE='0402LF',
 LOCATION='R135',
 CDS_LIB='pure_quanta',
 CDS_PART_NAME='Q_RES_0402LF-4.7K,5%,1/16W,EMPTY,CS24702JB10',
 PART_NUMBER='CS24702JB10',
 VALUE='4.7K',
 PRIM_FILE='./archive_libs/logical/q_res/chips/chips.prt';

PART_NAME
 R136 'Q_RES_0402LF-10K,1%,1/16W,EMPTY,CS31002FB08':;

SECTION_NUMBER 1
 '@T6G_MB_LIB.T6G(SCH_1):PAGE82_I162@PURE_QUANTA.Q_RES(CHIPS)':
 C_PATH='@t6g_mb_lib.t6g(sch_1):page82_i162@pure_quanta.q_res(chips)',
 P_PATH='@t6g_mb_lib.t6g(sch_1):page83_i162@pure_quanta.q_res(chips)',
 PATH='I162',
 DRAWING='@T6G_MB_LIB.T6G(SCH_1):PAGE82',
 WATTAGE='1/16W',
 TOLERANCE='1%',
 MATERIAL='EMPTY',
 PHYS_PAGE='83',
 XY='(-4050,3250)',
 ROT='0',
 VER='2',
 PACK_TYPE='0402LF',
 LOCATION='R136',
 CDS_LIB='pure_quanta',
 CDS_PART_NAME='Q_RES_0402LF-10K,1%,1/16W,EMPTY,CS31002FB08',
 PART_NUMBER='CS31002FB08',
 VALUE='10K',
 PRIM_FILE='./archive_libs/logical/q_res/chips/chips.prt';

PART_NAME
 R137 'Q_RES_0402LF-0,5%,1/16W,CHIP,CS00002JB13':;

SECTION_NUMBER 1
 '@T6G_MB_LIB.T6G(SCH_1):PAGE81_I59@PURE_QUANTA.Q_RES(CHIPS)':
 C_PATH='@t6g_mb_lib.t6g(sch_1):page81_i59@pure_quanta.q_res(chips)',
 P_PATH='@t6g_mb_lib.t6g(sch_1):page82_i59@pure_quanta.q_res(chips)',
 PATH='I59',
 DRAWING='@T6G_MB_LIB.T6G(SCH_1):PAGE81',
 BOM_COST='MEM',
 WATTAGE='1/16W',
 TOLERANCE='5%',
 MATERIAL='CHIP',
 PHYS_PAGE='82',
 XY='(-6450,5225)',
 ROT='0',
 VER='1',
 PACK_TYPE='0402LF',
 LOCATION='R137',
 CDS_LIB='pure_quanta',
 CDS_PART_NAME='Q_RES_0402LF-0,5%,1/16W,CHIP,CS00002JB13',
 PART_NUMBER='CS00002JB13',
 VALUE='0',
 PRIM_FILE='./archive_libs/logical/q_res/chips/chips.prt';

PART_NAME
 R138 'Q_RES_0402LF-4.7K,1%,1/16W,EMPTY,CS24702FB06':;

SECTION_NUMBER 1
 '@T6G_MB_LIB.T6G(SCH_1):PAGE345_I15@PURE_QUANTA.Q_RES(CHIPS)':
 C_PATH='@t6g_mb_lib.t6g(sch_1):page345_i15@pure_quanta.q_res(chips)',
 P_PATH='@t6g_mb_lib.t6g(sch_1):page144_i15@pure_quanta.q_res(chips)',
 PATH='I15',
 DRAWING='@T6G_MB_LIB.T6G(SCH_1):PAGE345',
 WATTAGE='1/16W',
 TOLERANCE='1%',
 MATERIAL='EMPTY',
 PHYS_PAGE='144',
 XY='(5400,3000)',
 ROT='0',
 VER='2',
 PACK_TYPE='0402LF',
 LOCATION='R138',
 CDS_LIB='pure_quanta',
 CDS_PART_NAME='Q_RES_0402LF-4.7K,1%,1/16W,EMPTY,CS24702FB06',
 PART_NUMBER='CS24702FB06',
 VALUE='4.7K',
 PRIM_FILE='./archive_libs/logical/q_res/chips/chips.prt';

PART_NAME
 R139 'Q_RES_0402LF-0,5%,1/16W,EMPTY,CS00002JB13':;

SECTION_NUMBER 1
 '@T6G_MB_LIB.T6G(SCH_1):PAGE138_I30@PURE_QUANTA.Q_RES(CHIPS)':
 C_PATH='@t6g_mb_lib.t6g(sch_1):page138_i30@pure_quanta.q_res(chips)',
 P_PATH='@t6g_mb_lib.t6g(sch_1):page161_i30@pure_quanta.q_res(chips)',
 PATH='I30',
 DRAWING='@T6G_MB_LIB.T6G(SCH_1):PAGE138',
 WATTAGE='1/16W',
 TOLERANCE='5%',
 MATERIAL='EMPTY',
 PHYS_PAGE='161',
 XY='(425,4525)',
 ROT='0',
 VER='1',
 PACK_TYPE='0402LF',
 LOCATION='R139',
 CDS_LIB='pure_quanta',
 CDS_PART_NAME='Q_RES_0402LF-0,5%,1/16W,EMPTY,CS00002JB13',
 PART_NUMBER='CS00002JB13',
 VALUE='0',
 PRIM_FILE='./archive_libs/logical/q_res/chips/chips.prt';

PART_NAME
 R140 'Q_RES_0402LF-0,5%,1/16W,EMPTY,CS00002JB13':;

SECTION_NUMBER 1
 '@T6G_MB_LIB.T6G(SCH_1):PAGE137_I98@PURE_QUANTA.Q_RES(CHIPS)':
 C_PATH='@t6g_mb_lib.t6g(sch_1):page137_i98@pure_quanta.q_res(chips)',
 P_PATH='@t6g_mb_lib.t6g(sch_1):page160_i98@pure_quanta.q_res(chips)',
 PATH='I98',
 DRAWING='@T6G_MB_LIB.T6G(SCH_1):PAGE137',
 WATTAGE='1/16W',
 TOLERANCE='5%',
 MATERIAL='EMPTY',
 PHYS_PAGE='160',
 XY='(-7850,2350)',
 ROT='0',
 VER='1',
 PACK_TYPE='0402LF',
 LOCATION='R140',
 CDS_LIB='pure_quanta',
 CDS_PART_NAME='Q_RES_0402LF-0,5%,1/16W,EMPTY,CS00002JB13',
 PART_NUMBER='CS00002JB13',
 VALUE='0',
 PRIM_FILE='./archive_libs/logical/q_res/chips/chips.prt';

PART_NAME
 R141 'Q_RES_0402LF-0,5%,1/16W,CHIP,CS00002JB13':;

SECTION_NUMBER 1
 '@T6G_MB_LIB.T6G(SCH_1):PAGE81_I57@PURE_QUANTA.Q_RES(CHIPS)':
 C_PATH='@t6g_mb_lib.t6g(sch_1):page81_i57@pure_quanta.q_res(chips)',
 P_PATH='@t6g_mb_lib.t6g(sch_1):page82_i57@pure_quanta.q_res(chips)',
 PATH='I57',
 DRAWING='@T6G_MB_LIB.T6G(SCH_1):PAGE81',
 BOM_COST='MEM',
 WATTAGE='1/16W',
 TOLERANCE='5%',
 MATERIAL='CHIP',
 PHYS_PAGE='82',
 XY='(-6450,5175)',
 ROT='0',
 VER='1',
 PACK_TYPE='0402LF',
 LOCATION='R141',
 CDS_LIB='pure_quanta',
 CDS_PART_NAME='Q_RES_0402LF-0,5%,1/16W,CHIP,CS00002JB13',
 PART_NUMBER='CS00002JB13',
 VALUE='0',
 PRIM_FILE='./archive_libs/logical/q_res/chips/chips.prt';

PART_NAME
 R142 'Q_RES_0402LF-0,5%,1/16W,EMPTY,CS00002JB13':;

SECTION_NUMBER 1
 '@T6G_MB_LIB.T6G(SCH_1):PAGE138_I35@PURE_QUANTA.Q_RES(CHIPS)':
 C_PATH='@t6g_mb_lib.t6g(sch_1):page138_i35@pure_quanta.q_res(chips)',
 P_PATH='@t6g_mb_lib.t6g(sch_1):page161_i35@pure_quanta.q_res(chips)',
 PATH='I35',
 DRAWING='@T6G_MB_LIB.T6G(SCH_1):PAGE138',
 WATTAGE='1/16W',
 TOLERANCE='5%',
 MATERIAL='EMPTY',
 PHYS_PAGE='161',
 XY='(1650,5000)',
 ROT='0',
 VER='1',
 PACK_TYPE='0402LF',
 LOCATION='R142',
 CDS_LIB='pure_quanta',
 CDS_PART_NAME='Q_RES_0402LF-0,5%,1/16W,EMPTY,CS00002JB13',
 PART_NUMBER='CS00002JB13',
 VALUE='0',
 PRIM_FILE='./archive_libs/logical/q_res/chips/chips.prt';

PART_NAME
 R143 'Q_RES_0402LF-0,5%,1/16W,EMPTY,CS00002JB13':;

SECTION_NUMBER 1
 '@T6G_MB_LIB.T6G(SCH_1):PAGE138_I34@PURE_QUANTA.Q_RES(CHIPS)':
 C_PATH='@t6g_mb_lib.t6g(sch_1):page138_i34@pure_quanta.q_res(chips)',
 P_PATH='@t6g_mb_lib.t6g(sch_1):page161_i34@pure_quanta.q_res(chips)',
 PATH='I34',
 DRAWING='@T6G_MB_LIB.T6G(SCH_1):PAGE138',
 WATTAGE='1/16W',
 TOLERANCE='5%',
 MATERIAL='EMPTY',
 PHYS_PAGE='161',
 XY='(1650,4925)',
 ROT='0',
 VER='1',
 PACK_TYPE='0402LF',
 LOCATION='R143',
 CDS_LIB='pure_quanta',
 CDS_PART_NAME='Q_RES_0402LF-0,5%,1/16W,EMPTY,CS00002JB13',
 PART_NUMBER='CS00002JB13',
 VALUE='0',
 PRIM_FILE='./archive_libs/logical/q_res/chips/chips.prt';

PART_NAME
 R144 'Q_RES_0402LF-0,5%,1/16W,EMPTY,CS00002JB13':;

SECTION_NUMBER 1
 '@T6G_MB_LIB.T6G(SCH_1):PAGE138_I15@PURE_QUANTA.Q_RES(CHIPS)':
 C_PATH='@t6g_mb_lib.t6g(sch_1):page138_i15@pure_quanta.q_res(chips)',
 P_PATH='@t6g_mb_lib.t6g(sch_1):page161_i15@pure_quanta.q_res(chips)',
 PATH='I15',
 DRAWING='@T6G_MB_LIB.T6G(SCH_1):PAGE138',
 WATTAGE='1/16W',
 TOLERANCE='5%',
 MATERIAL='EMPTY',
 PHYS_PAGE='161',
 XY='(1650,2875)',
 ROT='0',
 VER='1',
 PACK_TYPE='0402LF',
 LOCATION='R144',
 CDS_LIB='pure_quanta',
 CDS_PART_NAME='Q_RES_0402LF-0,5%,1/16W,EMPTY,CS00002JB13',
 PART_NUMBER='CS00002JB13',
 VALUE='0',
 PRIM_FILE='./archive_libs/logical/q_res/chips/chips.prt';

PART_NAME
 R145 'Q_RES_0402LF-0,5%,1/16W,EMPTY,CS00002JB13':;

SECTION_NUMBER 1
 '@T6G_MB_LIB.T6G(SCH_1):PAGE138_I14@PURE_QUANTA.Q_RES(CHIPS)':
 C_PATH='@t6g_mb_lib.t6g(sch_1):page138_i14@pure_quanta.q_res(chips)',
 P_PATH='@t6g_mb_lib.t6g(sch_1):page161_i14@pure_quanta.q_res(chips)',
 PATH='I14',
 DRAWING='@T6G_MB_LIB.T6G(SCH_1):PAGE138',
 WATTAGE='1/16W',
 TOLERANCE='5%',
 MATERIAL='EMPTY',
 PHYS_PAGE='161',
 XY='(1650,2800)',
 ROT='0',
 VER='1',
 PACK_TYPE='0402LF',
 LOCATION='R145',
 CDS_LIB='pure_quanta',
 CDS_PART_NAME='Q_RES_0402LF-0,5%,1/16W,EMPTY,CS00002JB13',
 PART_NUMBER='CS00002JB13',
 VALUE='0',
 PRIM_FILE='./archive_libs/logical/q_res/chips/chips.prt';

PART_NAME
 R146 'Q_RES_0402LF-0,5%,1/16W,EMPTY,CS00002JB13':;

SECTION_NUMBER 1
 '@T6G_MB_LIB.T6G(SCH_1):PAGE138_I17@PURE_QUANTA.Q_RES(CHIPS)':
 C_PATH='@t6g_mb_lib.t6g(sch_1):page138_i17@pure_quanta.q_res(chips)',
 P_PATH='@t6g_mb_lib.t6g(sch_1):page161_i17@pure_quanta.q_res(chips)',
 PATH='I17',
 DRAWING='@T6G_MB_LIB.T6G(SCH_1):PAGE138',
 WATTAGE='1/16W',
 TOLERANCE='5%',
 MATERIAL='EMPTY',
 PHYS_PAGE='161',
 XY='(1700,3225)',
 ROT='0',
 VER='1',
 PACK_TYPE='0402LF',
 LOCATION='R146',
 CDS_LIB='pure_quanta',
 CDS_PART_NAME='Q_RES_0402LF-0,5%,1/16W,EMPTY,CS00002JB13',
 PART_NUMBER='CS00002JB13',
 VALUE='0',
 PRIM_FILE='./archive_libs/logical/q_res/chips/chips.prt';

PART_NAME
 R147 'Q_RES_0402LF-0,5%,1/16W,EMPTY,CS00002JB13':;

SECTION_NUMBER 1
 '@T6G_MB_LIB.T6G(SCH_1):PAGE138_I16@PURE_QUANTA.Q_RES(CHIPS)':
 C_PATH='@t6g_mb_lib.t6g(sch_1):page138_i16@pure_quanta.q_res(chips)',
 P_PATH='@t6g_mb_lib.t6g(sch_1):page161_i16@pure_quanta.q_res(chips)',
 PATH='I16',
 DRAWING='@T6G_MB_LIB.T6G(SCH_1):PAGE138',
 WATTAGE='1/16W',
 TOLERANCE='5%',
 MATERIAL='EMPTY',
 PHYS_PAGE='161',
 XY='(1700,3150)',
 ROT='0',
 VER='1',
 PACK_TYPE='0402LF',
 LOCATION='R147',
 CDS_LIB='pure_quanta',
 CDS_PART_NAME='Q_RES_0402LF-0,5%,1/16W,EMPTY,CS00002JB13',
 PART_NUMBER='CS00002JB13',
 VALUE='0',
 PRIM_FILE='./archive_libs/logical/q_res/chips/chips.prt';

PART_NAME
 R148 'Q_RES_0402LF-0,5%,1/16W,EMPTY,CS00002JB13':;

SECTION_NUMBER 1
 '@T6G_MB_LIB.T6G(SCH_1):PAGE138_I6@PURE_QUANTA.Q_RES(CHIPS)':
 C_PATH='@t6g_mb_lib.t6g(sch_1):page138_i6@pure_quanta.q_res(chips)',
 P_PATH='@t6g_mb_lib.t6g(sch_1):page161_i6@pure_quanta.q_res(chips)',
 PATH='I6',
 DRAWING='@T6G_MB_LIB.T6G(SCH_1):PAGE138',
 WATTAGE='1/16W',
 TOLERANCE='5%',
 MATERIAL='EMPTY',
 PHYS_PAGE='161',
 XY='(1725,1100)',
 ROT='0',
 VER='1',
 PACK_TYPE='0402LF',
 LOCATION='R148',
 CDS_LIB='pure_quanta',
 CDS_PART_NAME='Q_RES_0402LF-0,5%,1/16W,EMPTY,CS00002JB13',
 PART_NUMBER='CS00002JB13',
 VALUE='0',
 PRIM_FILE='./archive_libs/logical/q_res/chips/chips.prt';

PART_NAME
 R149 'Q_RES_0402LF-0,5%,1/16W,CHIP,CS00002JB13':;

SECTION_NUMBER 1
 '@T6G_MB_LIB.T6G(SCH_1):PAGE185_I2@PURE_QUANTA.Q_RES(CHIPS)':
 C_PATH='@t6g_mb_lib.t6g(sch_1):page185_i2@pure_quanta.q_res(chips)',
 P_PATH='@t6g_mb_lib.t6g(sch_1):page210_i2@pure_quanta.q_res(chips)',
 PATH='I2',
 DRAWING='@T6G_MB_LIB.T6G(SCH_1):PAGE185',
 WATTAGE='1/16W',
 TOLERANCE='5%',
 MATERIAL='CHIP',
 PHYS_PAGE='210',
 XY='(-5375,3200)',
 ROT='0',
 VER='1',
 PACK_TYPE='0402LF',
 LOCATION='R149',
 CDS_LIB='pure_quanta',
 CDS_PART_NAME='Q_RES_0402LF-0,5%,1/16W,CHIP,CS00002JB13',
 PART_NUMBER='CS00002JB13',
 VALUE='0',
 PRIM_FILE='./archive_libs/logical/q_res/chips/chips.prt';

PART_NAME
 R150 'Q_RES_0402LF-0,5%,1/16W,EMPTY,CS00002JB13':;

SECTION_NUMBER 1
 '@T6G_MB_LIB.T6G(SCH_1):PAGE137_I97@PURE_QUANTA.Q_RES(CHIPS)':
 C_PATH='@t6g_mb_lib.t6g(sch_1):page137_i97@pure_quanta.q_res(chips)',
 P_PATH='@t6g_mb_lib.t6g(sch_1):page160_i97@pure_quanta.q_res(chips)',
 PATH='I97',
 DRAWING='@T6G_MB_LIB.T6G(SCH_1):PAGE137',
 WATTAGE='1/16W',
 TOLERANCE='5%',
 MATERIAL='EMPTY',
 PHYS_PAGE='160',
 XY='(-7850,2250)',
 ROT='0',
 VER='1',
 PACK_TYPE='0402LF',
 LOCATION='R150',
 CDS_LIB='pure_quanta',
 CDS_PART_NAME='Q_RES_0402LF-0,5%,1/16W,EMPTY,CS00002JB13',
 PART_NUMBER='CS00002JB13',
 VALUE='0',
 PRIM_FILE='./archive_libs/logical/q_res/chips/chips.prt';

PART_NAME
 R151 'Q_RES_0402LF-0,5%,1/16W,CHIP,CS00002JB13':;

SECTION_NUMBER 1
 '@T6G_MB_LIB.T6G(SCH_1):PAGE137_I79@PURE_QUANTA.Q_RES(CHIPS)':
 C_PATH='@t6g_mb_lib.t6g(sch_1):page137_i79@pure_quanta.q_res(chips)',
 P_PATH='@t6g_mb_lib.t6g(sch_1):page160_i79@pure_quanta.q_res(chips)',
 PATH='I79',
 DRAWING='@T6G_MB_LIB.T6G(SCH_1):PAGE137',
 WATTAGE='1/16W',
 TOLERANCE='5%',
 MATERIAL='CHIP',
 PHYS_PAGE='160',
 XY='(-7750,800)',
 ROT='0',
 VER='1',
 PACK_TYPE='0402LF',
 LOCATION='R151',
 CDS_LIB='pure_quanta',
 CDS_PART_NAME='Q_RES_0402LF-0,5%,1/16W,CHIP,CS00002JB13',
 PART_NUMBER='CS00002JB13',
 VALUE='0',
 PRIM_FILE='./archive_libs/logical/q_res/chips/chips.prt';

PART_NAME
 R152 'Q_RES_0402LF-33,5%,1/16W,CHIP,CS03302JB10':;

SECTION_NUMBER 1
 '@T6G_MB_LIB.T6G(SCH_1):PAGE79_I153@PURE_QUANTA.Q_RES(CHIPS)':
 C_PATH='@t6g_mb_lib.t6g(sch_1):page79_i153@pure_quanta.q_res(chips)',
 P_PATH='@t6g_mb_lib.t6g(sch_1):page80_i153@pure_quanta.q_res(chips)',
 PATH='I153',
 DRAWING='@T6G_MB_LIB.T6G(SCH_1):PAGE79',
 BOM_COST='MEM',
 WATTAGE='1/16W',
 TOLERANCE='5%',
 MATERIAL='CHIP',
 PHYS_PAGE='80',
 XY='(-6850,3300)',
 ROT='2',
 VER='1',
 PACK_TYPE='0402LF',
 LOCATION='R152',
 CDS_LIB='pure_quanta',
 CDS_PART_NAME='Q_RES_0402LF-33,5%,1/16W,CHIP,CS03302JB10',
 PART_NUMBER='CS03302JB10',
 VALUE='33',
 PRIM_FILE='./archive_libs/logical/q_res/chips/chips.prt';

PART_NAME
 R153 'Q_RES_0402LF-0,5%,1/16W,CHIP,CS00002JB13':;

SECTION_NUMBER 1
 '@T6G_MB_LIB.T6G(SCH_1):PAGE345_I27@PURE_QUANTA.Q_RES(CHIPS)':
 C_PATH='@t6g_mb_lib.t6g(sch_1):page345_i27@pure_quanta.q_res(chips)',
 P_PATH='@t6g_mb_lib.t6g(sch_1):page144_i27@pure_quanta.q_res(chips)',
 PATH='I27',
 DRAWING='@T6G_MB_LIB.T6G(SCH_1):PAGE345',
 WATTAGE='1/16W',
 TOLERANCE='5%',
 MATERIAL='CHIP',
 PHYS_PAGE='144',
 XY='(6375,3275)',
 ROT='0',
 VER='1',
 PACK_TYPE='0402LF',
 LOCATION='R153',
 CDS_LIB='pure_quanta',
 CDS_PART_NAME='Q_RES_0402LF-0,5%,1/16W,CHIP,CS00002JB13',
 PART_NUMBER='CS00002JB13',
 VALUE='0',
 PRIM_FILE='./archive_libs/logical/q_res/chips/chips.prt';

PART_NAME
 R154 'Q_RES_0402LF-1K,1%,1/16W,EMPTY,CS21002FB06':;

SECTION_NUMBER 1
 '@T6G_MB_LIB.T6G(SCH_1):PAGE185_I67@PURE_QUANTA.Q_RES(CHIPS)':
 C_PATH='@t6g_mb_lib.t6g(sch_1):page185_i67@pure_quanta.q_res(chips)',
 P_PATH='@t6g_mb_lib.t6g(sch_1):page210_i67@pure_quanta.q_res(chips)',
 PATH='I67',
 DRAWING='@T6G_MB_LIB.T6G(SCH_1):PAGE185',
 WATTAGE='1/16W',
 TOLERANCE='1%',
 MATERIAL='EMPTY',
 PHYS_PAGE='210',
 XY='(-4775,7750)',
 ROT='0',
 VER='2',
 PACK_TYPE='0402LF',
 LOCATION='R154',
 CDS_LIB='pure_quanta',
 CDS_PART_NAME='Q_RES_0402LF-1K,1%,1/16W,EMPTY,CS21002FB06',
 PART_NUMBER='CS21002FB06',
 VALUE='1K',
 PRIM_FILE='./archive_libs/logical/q_res/chips/chips.prt';

PART_NAME
 R155 'Q_RES_0402LF-1K,1%,1/16W,EMPTY,CS21002FB06':;

SECTION_NUMBER 1
 '@T6G_MB_LIB.T6G(SCH_1):PAGE345_I32@PURE_QUANTA.Q_RES(CHIPS)':
 C_PATH='@t6g_mb_lib.t6g(sch_1):page345_i32@pure_quanta.q_res(chips)',
 P_PATH='@t6g_mb_lib.t6g(sch_1):page144_i32@pure_quanta.q_res(chips)',
 PATH='I32',
 DRAWING='@T6G_MB_LIB.T6G(SCH_1):PAGE345',
 WATTAGE='1/16W',
 TOLERANCE='1%',
 MATERIAL='EMPTY',
 PHYS_PAGE='144',
 XY='(6925,3850)',
 ROT='2',
 VER='2',
 PACK_TYPE='0402LF',
 LOCATION='R155',
 CDS_LIB='pure_quanta',
 CDS_PART_NAME='Q_RES_0402LF-1K,1%,1/16W,EMPTY,CS21002FB06',
 PART_NUMBER='CS21002FB06',
 VALUE='1K',
 PRIM_FILE='./archive_libs/logical/q_res/chips/chips.prt';

PART_NAME
 R156 'Q_RES_0402LF-0,5%,1/16W,CHIP,CS00002JB13':;

SECTION_NUMBER 1
 '@T6G_MB_LIB.T6G(SCH_1):PAGE27_I346@PURE_QUANTA.Q_RES(CHIPS)':
 C_PATH='@t6g_mb_lib.t6g(sch_1):page27_i346@pure_quanta.q_res(chips)',
 P_PATH='@t6g_mb_lib.t6g(sch_1):page27_i346@pure_quanta.q_res(chips)',
 PATH='I346',
 DRAWING='@T6G_MB_LIB.T6G(SCH_1):PAGE27',
 WATTAGE='1/16W',
 TOLERANCE='5%',
 MATERIAL='CHIP',
 PHYS_PAGE='27',
 XY='(-2725,4575)',
 ROT='0',
 VER='1',
 PACK_TYPE='0402LF',
 LOCATION='R156',
 CDS_LIB='pure_quanta',
 CDS_PART_NAME='Q_RES_0402LF-0,5%,1/16W,CHIP,CS00002JB13',
 PART_NUMBER='CS00002JB13',
 VALUE='0',
 PRIM_FILE='./archive_libs/logical/q_res/chips/chips.prt';

PART_NAME
 R157 'Q_RES_0402LF-0,5%,1/16W,CHIP,CS00002JB13':;

SECTION_NUMBER 1
 '@T6G_MB_LIB.T6G(SCH_1):PAGE27_I347@PURE_QUANTA.Q_RES(CHIPS)':
 C_PATH='@t6g_mb_lib.t6g(sch_1):page27_i347@pure_quanta.q_res(chips)',
 P_PATH='@t6g_mb_lib.t6g(sch_1):page27_i347@pure_quanta.q_res(chips)',
 PATH='I347',
 DRAWING='@T6G_MB_LIB.T6G(SCH_1):PAGE27',
 WATTAGE='1/16W',
 TOLERANCE='5%',
 MATERIAL='CHIP',
 PHYS_PAGE='27',
 XY='(-2725,4525)',
 ROT='0',
 VER='1',
 PACK_TYPE='0402LF',
 LOCATION='R157',
 CDS_LIB='pure_quanta',
 CDS_PART_NAME='Q_RES_0402LF-0,5%,1/16W,CHIP,CS00002JB13',
 PART_NUMBER='CS00002JB13',
 VALUE='0',
 PRIM_FILE='./archive_libs/logical/q_res/chips/chips.prt';

PART_NAME
 R158 'Q_RES_0402LF-33,5%,1/16W,CHIP,CS03302JB10':;

SECTION_NUMBER 1
 '@T6G_MB_LIB.T6G(SCH_1):PAGE80_I154@PURE_QUANTA.Q_RES(CHIPS)':
 C_PATH='@t6g_mb_lib.t6g(sch_1):page80_i154@pure_quanta.q_res(chips)',
 P_PATH='@t6g_mb_lib.t6g(sch_1):page81_i154@pure_quanta.q_res(chips)',
 PATH='I154',
 DRAWING='@T6G_MB_LIB.T6G(SCH_1):PAGE80',
 BOM_COST='MEM',
 WATTAGE='1/16W',
 TOLERANCE='5%',
 MATERIAL='CHIP',
 PHYS_PAGE='81',
 XY='(-3225,4175)',
 ROT='0',
 VER='1',
 PACK_TYPE='0402LF',
 LOCATION='R158',
 CDS_LIB='pure_quanta',
 CDS_PART_NAME='Q_RES_0402LF-33,5%,1/16W,CHIP,CS03302JB10',
 PART_NUMBER='CS03302JB10',
 VALUE='33',
 PRIM_FILE='./archive_libs/logical/q_res/chips/chips.prt';

PART_NAME
 R159 'Q_RES_0402LF-33,5%,1/16W,CHIP,CS03302JB10':;

SECTION_NUMBER 1
 '@T6G_MB_LIB.T6G(SCH_1):PAGE80_I111@PURE_QUANTA.Q_RES(CHIPS)':
 C_PATH='@t6g_mb_lib.t6g(sch_1):page80_i111@pure_quanta.q_res(chips)',
 P_PATH='@t6g_mb_lib.t6g(sch_1):page81_i111@pure_quanta.q_res(chips)',
 PATH='I111',
 DRAWING='@T6G_MB_LIB.T6G(SCH_1):PAGE80',
 BOM_COST='MEM',
 WATTAGE='1/16W',
 TOLERANCE='5%',
 MATERIAL='CHIP',
 PHYS_PAGE='81',
 XY='(-6425,5025)',
 ROT='0',
 VER='1',
 PACK_TYPE='0402LF',
 LOCATION='R159',
 CDS_LIB='pure_quanta',
 CDS_PART_NAME='Q_RES_0402LF-33,5%,1/16W,CHIP,CS03302JB10',
 PART_NUMBER='CS03302JB10',
 VALUE='33',
 PRIM_FILE='./archive_libs/logical/q_res/chips/chips.prt';

PART_NAME
 R160 'Q_RES_0402LF-33,5%,1/16W,CHIP,CS03302JB10':;

SECTION_NUMBER 1
 '@T6G_MB_LIB.T6G(SCH_1):PAGE79_I16@PURE_QUANTA.Q_RES(CHIPS)':
 C_PATH='@t6g_mb_lib.t6g(sch_1):page79_i16@pure_quanta.q_res(chips)',
 P_PATH='@t6g_mb_lib.t6g(sch_1):page80_i16@pure_quanta.q_res(chips)',
 PATH='I16',
 DRAWING='@T6G_MB_LIB.T6G(SCH_1):PAGE79',
 BOM_COST='MEM',
 WATTAGE='1/16W',
 TOLERANCE='5%',
 MATERIAL='CHIP',
 PHYS_PAGE='80',
 XY='(-6850,2700)',
 ROT='2',
 VER='1',
 PACK_TYPE='0402LF',
 LOCATION='R160',
 CDS_LIB='pure_quanta',
 CDS_PART_NAME='Q_RES_0402LF-33,5%,1/16W,CHIP,CS03302JB10',
 PART_NUMBER='CS03302JB10',
 VALUE='33',
 PRIM_FILE='./archive_libs/logical/q_res/chips/chips.prt';

PART_NAME
 R161 'Q_RES_0402LF-33,5%,1/16W,CHIP,CS03302JB10':;

SECTION_NUMBER 1
 '@T6G_MB_LIB.T6G(SCH_1):PAGE80_I161@PURE_QUANTA.Q_RES(CHIPS)':
 C_PATH='@t6g_mb_lib.t6g(sch_1):page80_i161@pure_quanta.q_res(chips)',
 P_PATH='@t6g_mb_lib.t6g(sch_1):page81_i161@pure_quanta.q_res(chips)',
 PATH='I161',
 DRAWING='@T6G_MB_LIB.T6G(SCH_1):PAGE80',
 BOM_COST='MEM',
 WATTAGE='1/16W',
 TOLERANCE='5%',
 MATERIAL='CHIP',
 PHYS_PAGE='81',
 XY='(-3225,4625)',
 ROT='0',
 VER='1',
 PACK_TYPE='0402LF',
 LOCATION='R161',
 CDS_LIB='pure_quanta',
 CDS_PART_NAME='Q_RES_0402LF-33,5%,1/16W,CHIP,CS03302JB10',
 PART_NUMBER='CS03302JB10',
 VALUE='33',
 PRIM_FILE='./archive_libs/logical/q_res/chips/chips.prt';

PART_NAME
 R162 'Q_RES_0402LF-0,5%,1/16W,CHIP,CS00002JB13':;

SECTION_NUMBER 1
 '@T6G_MB_LIB.T6G(SCH_1):PAGE137_I80@PURE_QUANTA.Q_RES(CHIPS)':
 C_PATH='@t6g_mb_lib.t6g(sch_1):page137_i80@pure_quanta.q_res(chips)',
 P_PATH='@t6g_mb_lib.t6g(sch_1):page160_i80@pure_quanta.q_res(chips)',
 PATH='I80',
 DRAWING='@T6G_MB_LIB.T6G(SCH_1):PAGE137',
 WATTAGE='1/16W',
 TOLERANCE='5%',
 MATERIAL='CHIP',
 PHYS_PAGE='160',
 XY='(-7750,700)',
 ROT='0',
 VER='1',
 PACK_TYPE='0402LF',
 LOCATION='R162',
 CDS_LIB='pure_quanta',
 CDS_PART_NAME='Q_RES_0402LF-0,5%,1/16W,CHIP,CS00002JB13',
 PART_NUMBER='CS00002JB13',
 VALUE='0',
 PRIM_FILE='./archive_libs/logical/q_res/chips/chips.prt';

PART_NAME
 R163 'Q_RES_0402LF-33,5%,1/16W,CHIP,CS03302JB10':;

SECTION_NUMBER 1
 '@T6G_MB_LIB.T6G(SCH_1):PAGE79_I54@PURE_QUANTA.Q_RES(CHIPS)':
 C_PATH='@t6g_mb_lib.t6g(sch_1):page79_i54@pure_quanta.q_res(chips)',
 P_PATH='@t6g_mb_lib.t6g(sch_1):page80_i54@pure_quanta.q_res(chips)',
 PATH='I54',
 DRAWING='@T6G_MB_LIB.T6G(SCH_1):PAGE79',
 BOM_COST='MEM',
 WATTAGE='1/16W',
 TOLERANCE='5%',
 MATERIAL='CHIP',
 PHYS_PAGE='80',
 XY='(-6850,5000)',
 ROT='2',
 VER='1',
 PACK_TYPE='0402LF',
 LOCATION='R163',
 CDS_LIB='pure_quanta',
 CDS_PART_NAME='Q_RES_0402LF-33,5%,1/16W,CHIP,CS03302JB10',
 PART_NUMBER='CS03302JB10',
 VALUE='33',
 PRIM_FILE='./archive_libs/logical/q_res/chips/chips.prt';

PART_NAME
 R164 'Q_RES_0402LF-33,5%,1/16W,CHIP,CS03302JB10':;

SECTION_NUMBER 1
 '@T6G_MB_LIB.T6G(SCH_1):PAGE79_I50@PURE_QUANTA.Q_RES(CHIPS)':
 C_PATH='@t6g_mb_lib.t6g(sch_1):page79_i50@pure_quanta.q_res(chips)',
 P_PATH='@t6g_mb_lib.t6g(sch_1):page80_i50@pure_quanta.q_res(chips)',
 PATH='I50',
 DRAWING='@T6G_MB_LIB.T6G(SCH_1):PAGE79',
 BOM_COST='MEM',
 WATTAGE='1/16W',
 TOLERANCE='5%',
 MATERIAL='CHIP',
 PHYS_PAGE='80',
 XY='(-6850,4700)',
 ROT='2',
 VER='1',
 PACK_TYPE='0402LF',
 LOCATION='R164',
 CDS_LIB='pure_quanta',
 CDS_PART_NAME='Q_RES_0402LF-33,5%,1/16W,CHIP,CS03302JB10',
 PART_NUMBER='CS03302JB10',
 VALUE='33',
 PRIM_FILE='./archive_libs/logical/q_res/chips/chips.prt';

PART_NAME
 R165 'Q_RES_0402LF-33,5%,1/16W,CHIP,CS03302JB10':;

SECTION_NUMBER 1
 '@T6G_MB_LIB.T6G(SCH_1):PAGE79_I47@PURE_QUANTA.Q_RES(CHIPS)':
 C_PATH='@t6g_mb_lib.t6g(sch_1):page79_i47@pure_quanta.q_res(chips)',
 P_PATH='@t6g_mb_lib.t6g(sch_1):page80_i47@pure_quanta.q_res(chips)',
 PATH='I47',
 DRAWING='@T6G_MB_LIB.T6G(SCH_1):PAGE79',
 BOM_COST='MEM',
 WATTAGE='1/16W',
 TOLERANCE='5%',
 MATERIAL='CHIP',
 PHYS_PAGE='80',
 XY='(-6850,4650)',
 ROT='2',
 VER='1',
 PACK_TYPE='0402LF',
 LOCATION='R165',
 CDS_LIB='pure_quanta',
 CDS_PART_NAME='Q_RES_0402LF-33,5%,1/16W,CHIP,CS03302JB10',
 PART_NUMBER='CS03302JB10',
 VALUE='33',
 PRIM_FILE='./archive_libs/logical/q_res/chips/chips.prt';

PART_NAME
 R166 'Q_RES_0402LF-33,5%,1/16W,CHIP,CS03302JB10':;

SECTION_NUMBER 1
 '@T6G_MB_LIB.T6G(SCH_1):PAGE79_I51@PURE_QUANTA.Q_RES(CHIPS)':
 C_PATH='@t6g_mb_lib.t6g(sch_1):page79_i51@pure_quanta.q_res(chips)',
 P_PATH='@t6g_mb_lib.t6g(sch_1):page80_i51@pure_quanta.q_res(chips)',
 PATH='I51',
 DRAWING='@T6G_MB_LIB.T6G(SCH_1):PAGE79',
 BOM_COST='MEM',
 WATTAGE='1/16W',
 TOLERANCE='5%',
 MATERIAL='CHIP',
 PHYS_PAGE='80',
 XY='(-6850,4850)',
 ROT='2',
 VER='1',
 PACK_TYPE='0402LF',
 LOCATION='R166',
 CDS_LIB='pure_quanta',
 CDS_PART_NAME='Q_RES_0402LF-33,5%,1/16W,CHIP,CS03302JB10',
 PART_NUMBER='CS03302JB10',
 VALUE='33',
 PRIM_FILE='./archive_libs/logical/q_res/chips/chips.prt';

PART_NAME
 R167 'Q_RES_0402LF-0,5%,1/16W,CHIP,CS00002JB13':;

SECTION_NUMBER 1
 '@T6G_MB_LIB.T6G(SCH_1):PAGE79_I45@PURE_QUANTA.Q_RES(CHIPS)':
 C_PATH='@t6g_mb_lib.t6g(sch_1):page79_i45@pure_quanta.q_res(chips)',
 P_PATH='@t6g_mb_lib.t6g(sch_1):page80_i45@pure_quanta.q_res(chips)',
 PATH='I45',
 DRAWING='@T6G_MB_LIB.T6G(SCH_1):PAGE79',
 BOM_COST='MEM',
 WATTAGE='1/16W',
 TOLERANCE='5%',
 MATERIAL='CHIP',
 PHYS_PAGE='80',
 XY='(-6850,4550)',
 ROT='2',
 VER='1',
 PACK_TYPE='0402LF',
 LOCATION='R167',
 CDS_LIB='pure_quanta',
 CDS_PART_NAME='Q_RES_0402LF-0,5%,1/16W,CHIP,CS00002JB13',
 PART_NUMBER='CS00002JB13',
 VALUE='0',
 PRIM_FILE='./archive_libs/logical/q_res/chips/chips.prt';

PART_NAME
 R168 'Q_RES_0402LF-0,5%,1/16W,CHIP,CS00002JB13':;

SECTION_NUMBER 1
 '@T6G_MB_LIB.T6G(SCH_1):PAGE79_I24@PURE_QUANTA.Q_RES(CHIPS)':
 C_PATH='@t6g_mb_lib.t6g(sch_1):page79_i24@pure_quanta.q_res(chips)',
 P_PATH='@t6g_mb_lib.t6g(sch_1):page80_i24@pure_quanta.q_res(chips)',
 PATH='I24',
 DRAWING='@T6G_MB_LIB.T6G(SCH_1):PAGE79',
 BOM_COST='MEM',
 WATTAGE='1/16W',
 TOLERANCE='5%',
 MATERIAL='CHIP',
 PHYS_PAGE='80',
 XY='(-6825,3900)',
 ROT='2',
 VER='1',
 PACK_TYPE='0402LF',
 LOCATION='R168',
 CDS_LIB='pure_quanta',
 CDS_PART_NAME='Q_RES_0402LF-0,5%,1/16W,CHIP,CS00002JB13',
 PART_NUMBER='CS00002JB13',
 VALUE='0',
 PRIM_FILE='./archive_libs/logical/q_res/chips/chips.prt';

PART_NAME
 R169 'Q_RES_0402LF-33,5%,1/16W,CHIP,CS03302JB10':;

SECTION_NUMBER 1
 '@T6G_MB_LIB.T6G(SCH_1):PAGE79_I48@PURE_QUANTA.Q_RES(CHIPS)':
 C_PATH='@t6g_mb_lib.t6g(sch_1):page79_i48@pure_quanta.q_res(chips)',
 P_PATH='@t6g_mb_lib.t6g(sch_1):page80_i48@pure_quanta.q_res(chips)',
 PATH='I48',
 DRAWING='@T6G_MB_LIB.T6G(SCH_1):PAGE79',
 BOM_COST='MEM',
 WATTAGE='1/16W',
 TOLERANCE='5%',
 MATERIAL='CHIP',
 PHYS_PAGE='80',
 XY='(-6850,4800)',
 ROT='2',
 VER='1',
 PACK_TYPE='0402LF',
 LOCATION='R169',
 CDS_LIB='pure_quanta',
 CDS_PART_NAME='Q_RES_0402LF-33,5%,1/16W,CHIP,CS03302JB10',
 PART_NUMBER='CS03302JB10',
 VALUE='33',
 PRIM_FILE='./archive_libs/logical/q_res/chips/chips.prt';

PART_NAME
 R170 'Q_RES_0402LF-33,5%,1/16W,CHIP,CS03302JB10':;

SECTION_NUMBER 1
 '@T6G_MB_LIB.T6G(SCH_1):PAGE79_I53@PURE_QUANTA.Q_RES(CHIPS)':
 C_PATH='@t6g_mb_lib.t6g(sch_1):page79_i53@pure_quanta.q_res(chips)',
 P_PATH='@t6g_mb_lib.t6g(sch_1):page80_i53@pure_quanta.q_res(chips)',
 PATH='I53',
 DRAWING='@T6G_MB_LIB.T6G(SCH_1):PAGE79',
 BOM_COST='MEM',
 WATTAGE='1/16W',
 TOLERANCE='5%',
 MATERIAL='CHIP',
 PHYS_PAGE='80',
 XY='(-6850,4950)',
 ROT='2',
 VER='1',
 PACK_TYPE='0402LF',
 LOCATION='R170',
 CDS_LIB='pure_quanta',
 CDS_PART_NAME='Q_RES_0402LF-33,5%,1/16W,CHIP,CS03302JB10',
 PART_NUMBER='CS03302JB10',
 VALUE='33',
 PRIM_FILE='./archive_libs/logical/q_res/chips/chips.prt';

PART_NAME
 R171 'Q_RES_0402LF-33,5%,1/16W,CHIP,CS03302JB10':;

SECTION_NUMBER 1
 '@T6G_MB_LIB.T6G(SCH_1):PAGE79_I52@PURE_QUANTA.Q_RES(CHIPS)':
 C_PATH='@t6g_mb_lib.t6g(sch_1):page79_i52@pure_quanta.q_res(chips)',
 P_PATH='@t6g_mb_lib.t6g(sch_1):page80_i52@pure_quanta.q_res(chips)',
 PATH='I52',
 DRAWING='@T6G_MB_LIB.T6G(SCH_1):PAGE79',
 BOM_COST='MEM',
 WATTAGE='1/16W',
 TOLERANCE='5%',
 MATERIAL='CHIP',
 PHYS_PAGE='80',
 XY='(-6850,4900)',
 ROT='2',
 VER='1',
 PACK_TYPE='0402LF',
 LOCATION='R171',
 CDS_LIB='pure_quanta',
 CDS_PART_NAME='Q_RES_0402LF-33,5%,1/16W,CHIP,CS03302JB10',
 PART_NUMBER='CS03302JB10',
 VALUE='33',
 PRIM_FILE='./archive_libs/logical/q_res/chips/chips.prt';

PART_NAME
 R172 'Q_RES_0402LF-33,5%,1/16W,CHIP,CS03302JB10':;

SECTION_NUMBER 1
 '@T6G_MB_LIB.T6G(SCH_1):PAGE79_I43@PURE_QUANTA.Q_RES(CHIPS)':
 C_PATH='@t6g_mb_lib.t6g(sch_1):page79_i43@pure_quanta.q_res(chips)',
 P_PATH='@t6g_mb_lib.t6g(sch_1):page80_i43@pure_quanta.q_res(chips)',
 PATH='I43',
 DRAWING='@T6G_MB_LIB.T6G(SCH_1):PAGE79',
 BOM_COST='MEM',
 WATTAGE='1/16W',
 TOLERANCE='5%',
 MATERIAL='CHIP',
 PHYS_PAGE='80',
 XY='(-6850,4300)',
 ROT='2',
 VER='1',
 PACK_TYPE='0402LF',
 LOCATION='R172',
 CDS_LIB='pure_quanta',
 CDS_PART_NAME='Q_RES_0402LF-33,5%,1/16W,CHIP,CS03302JB10',
 PART_NUMBER='CS03302JB10',
 VALUE='33',
 PRIM_FILE='./archive_libs/logical/q_res/chips/chips.prt';

PART_NAME
 R173 'Q_RES_0402LF-33,5%,1/16W,CHIP,CS03302JB10':;

SECTION_NUMBER 1
 '@T6G_MB_LIB.T6G(SCH_1):PAGE80_I163@PURE_QUANTA.Q_RES(CHIPS)':
 C_PATH='@t6g_mb_lib.t6g(sch_1):page80_i163@pure_quanta.q_res(chips)',
 P_PATH='@t6g_mb_lib.t6g(sch_1):page81_i163@pure_quanta.q_res(chips)',
 PATH='I163',
 DRAWING='@T6G_MB_LIB.T6G(SCH_1):PAGE80',
 BOM_COST='MEM',
 WATTAGE='1/16W',
 TOLERANCE='5%',
 MATERIAL='CHIP',
 PHYS_PAGE='81',
 XY='(-3225,4675)',
 ROT='0',
 VER='1',
 PACK_TYPE='0402LF',
 LOCATION='R173',
 CDS_LIB='pure_quanta',
 CDS_PART_NAME='Q_RES_0402LF-33,5%,1/16W,CHIP,CS03302JB10',
 PART_NUMBER='CS03302JB10',
 VALUE='33',
 PRIM_FILE='./archive_libs/logical/q_res/chips/chips.prt';

PART_NAME
 R174 'Q_RES_0402LF-33,5%,1/16W,CHIP,CS03302JB10':;

SECTION_NUMBER 1
 '@T6G_MB_LIB.T6G(SCH_1):PAGE80_I160@PURE_QUANTA.Q_RES(CHIPS)':
 C_PATH='@t6g_mb_lib.t6g(sch_1):page80_i160@pure_quanta.q_res(chips)',
 P_PATH='@t6g_mb_lib.t6g(sch_1):page81_i160@pure_quanta.q_res(chips)',
 PATH='I160',
 DRAWING='@T6G_MB_LIB.T6G(SCH_1):PAGE80',
 BOM_COST='MEM',
 WATTAGE='1/16W',
 TOLERANCE='5%',
 MATERIAL='CHIP',
 PHYS_PAGE='81',
 XY='(-3225,4575)',
 ROT='0',
 VER='1',
 PACK_TYPE='0402LF',
 LOCATION='R174',
 CDS_LIB='pure_quanta',
 CDS_PART_NAME='Q_RES_0402LF-33,5%,1/16W,CHIP,CS03302JB10',
 PART_NUMBER='CS03302JB10',
 VALUE='33',
 PRIM_FILE='./archive_libs/logical/q_res/chips/chips.prt';

PART_NAME
 R175 'Q_RES_0402LF-0,5%,1/16W,CHIP,CS00002JB13':;

SECTION_NUMBER 1
 '@T6G_MB_LIB.T6G(SCH_1):PAGE185_I81@PURE_QUANTA.Q_RES(CHIPS)':
 C_PATH='@t6g_mb_lib.t6g(sch_1):page185_i81@pure_quanta.q_res(chips)',
 P_PATH='@t6g_mb_lib.t6g(sch_1):page210_i81@pure_quanta.q_res(chips)',
 PATH='I81',
 DRAWING='@T6G_MB_LIB.T6G(SCH_1):PAGE185',
 WATTAGE='1/16W',
 TOLERANCE='5%',
 MATERIAL='CHIP',
 PHYS_PAGE='210',
 XY='(-2700,6725)',
 ROT='0',
 VER='1',
 PACK_TYPE='0402LF',
 LOCATION='R175',
 CDS_LIB='pure_quanta',
 CDS_PART_NAME='Q_RES_0402LF-0,5%,1/16W,CHIP,CS00002JB13',
 PART_NUMBER='CS00002JB13',
 VALUE='0',
 PRIM_FILE='./archive_libs/logical/q_res/chips/chips.prt';

PART_NAME
 R176 'Q_RES_0402LF-33,5%,1/16W,CHIP,CS03302JB10':;

SECTION_NUMBER 1
 '@T6G_MB_LIB.T6G(SCH_1):PAGE80_I33@PURE_QUANTA.Q_RES(CHIPS)':
 C_PATH='@t6g_mb_lib.t6g(sch_1):page80_i33@pure_quanta.q_res(chips)',
 P_PATH='@t6g_mb_lib.t6g(sch_1):page81_i33@pure_quanta.q_res(chips)',
 PATH='I33',
 DRAWING='@T6G_MB_LIB.T6G(SCH_1):PAGE80',
 BOM_COST='MEM',
 WATTAGE='1/16W',
 TOLERANCE='5%',
 MATERIAL='CHIP',
 PHYS_PAGE='81',
 XY='(-6725,1775)',
 ROT='0',
 VER='1',
 PACK_TYPE='0402LF',
 LOCATION='R176',
 CDS_LIB='pure_quanta',
 CDS_PART_NAME='Q_RES_0402LF-33,5%,1/16W,CHIP,CS03302JB10',
 PART_NUMBER='CS03302JB10',
 VALUE='33',
 PRIM_FILE='./archive_libs/logical/q_res/chips/chips.prt';

PART_NAME
 R177 'Q_RES_0402LF-33,5%,1/16W,CHIP,CS03302JB10':;

SECTION_NUMBER 1
 '@T6G_MB_LIB.T6G(SCH_1):PAGE184_I52@PURE_QUANTA.Q_RES(CHIPS)':
 C_PATH='@t6g_mb_lib.t6g(sch_1):page184_i52@pure_quanta.q_res(chips)',
 P_PATH='@t6g_mb_lib.t6g(sch_1):page209_i52@pure_quanta.q_res(chips)',
 PATH='I52',
 DRAWING='@T6G_MB_LIB.T6G(SCH_1):PAGE184',
 BOM_COST='MEM',
 WATTAGE='1/16W',
 TOLERANCE='5%',
 MATERIAL='CHIP',
 PHYS_PAGE='209',
 XY='(-3650,4075)',
 ROT='0',
 VER='1',
 PACK_TYPE='0402LF',
 LOCATION='R177',
 CDS_LIB='pure_quanta',
 CDS_PART_NAME='Q_RES_0402LF-33,5%,1/16W,CHIP,CS03302JB10',
 PART_NUMBER='CS03302JB10',
 VALUE='33',
 PRIM_FILE='./archive_libs/logical/q_res/chips/chips.prt';

PART_NAME
 R178 'Q_RES_0402LF-1K,1%,1/16W,CHIP,CS21002FB06':;

SECTION_NUMBER 1
 '@T6G_MB_LIB.T6G(SCH_1):PAGE345_I24@PURE_QUANTA.Q_RES(CHIPS)':
 C_PATH='@t6g_mb_lib.t6g(sch_1):page345_i24@pure_quanta.q_res(chips)',
 P_PATH='@t6g_mb_lib.t6g(sch_1):page144_i24@pure_quanta.q_res(chips)',
 PATH='I24',
 DRAWING='@T6G_MB_LIB.T6G(SCH_1):PAGE345',
 WATTAGE='1/16W',
 TOLERANCE='1%',
 MATERIAL='CHIP',
 PHYS_PAGE='144',
 XY='(6925,2625)',
 ROT='0',
 VER='2',
 PACK_TYPE='0402LF',
 LOCATION='R178',
 CDS_LIB='pure_quanta',
 CDS_PART_NAME='Q_RES_0402LF-1K,1%,1/16W,CHIP,CS21002FB06',
 PART_NUMBER='CS21002FB06',
 VALUE='1K',
 PRIM_FILE='./archive_libs/logical/q_res/chips/chips.prt';

PART_NAME
 R179 'Q_RES_0402LF-33,5%,1/16W,CHIP,CS03302JB10':;

SECTION_NUMBER 1
 '@T6G_MB_LIB.T6G(SCH_1):PAGE81_I110@PURE_QUANTA.Q_RES(CHIPS)':
 C_PATH='@t6g_mb_lib.t6g(sch_1):page81_i110@pure_quanta.q_res(chips)',
 P_PATH='@t6g_mb_lib.t6g(sch_1):page82_i110@pure_quanta.q_res(chips)',
 PATH='I110',
 DRAWING='@T6G_MB_LIB.T6G(SCH_1):PAGE81',
 BOM_COST='MEM',
 WATTAGE='1/16W',
 TOLERANCE='5%',
 MATERIAL='CHIP',
 PHYS_PAGE='82',
 XY='(-3250,5775)',
 ROT='0',
 VER='1',
 PACK_TYPE='0402LF',
 LOCATION='R179',
 CDS_LIB='pure_quanta',
 CDS_PART_NAME='Q_RES_0402LF-33,5%,1/16W,CHIP,CS03302JB10',
 PART_NUMBER='CS03302JB10',
 VALUE='33',
 PRIM_FILE='./archive_libs/logical/q_res/chips/chips.prt';

PART_NAME
 R180 'Q_RES_0402LF-0,5%,1/16W,CHIP,CS00002JB13':;

SECTION_NUMBER 1
 '@T6G_MB_LIB.T6G(SCH_1):PAGE81_I45@PURE_QUANTA.Q_RES(CHIPS)':
 C_PATH='@t6g_mb_lib.t6g(sch_1):page81_i45@pure_quanta.q_res(chips)',
 P_PATH='@t6g_mb_lib.t6g(sch_1):page82_i45@pure_quanta.q_res(chips)',
 PATH='I45',
 DRAWING='@T6G_MB_LIB.T6G(SCH_1):PAGE81',
 BOM_COST='MEM',
 WATTAGE='1/16W',
 TOLERANCE='5%',
 MATERIAL='CHIP',
 PHYS_PAGE='82',
 XY='(-6450,4175)',
 ROT='0',
 VER='1',
 PACK_TYPE='0402LF',
 LOCATION='R180',
 CDS_LIB='pure_quanta',
 CDS_PART_NAME='Q_RES_0402LF-0,5%,1/16W,CHIP,CS00002JB13',
 PART_NUMBER='CS00002JB13',
 VALUE='0',
 PRIM_FILE='./archive_libs/logical/q_res/chips/chips.prt';

PART_NAME
 R181 'Q_RES_0402LF-0,5%,1/16W,CHIP,CS00002JB13':;

SECTION_NUMBER 1
 '@T6G_MB_LIB.T6G(SCH_1):PAGE81_I46@PURE_QUANTA.Q_RES(CHIPS)':
 C_PATH='@t6g_mb_lib.t6g(sch_1):page81_i46@pure_quanta.q_res(chips)',
 P_PATH='@t6g_mb_lib.t6g(sch_1):page82_i46@pure_quanta.q_res(chips)',
 PATH='I46',
 DRAWING='@T6G_MB_LIB.T6G(SCH_1):PAGE81',
 BOM_COST='MEM',
 WATTAGE='1/16W',
 TOLERANCE='5%',
 MATERIAL='CHIP',
 PHYS_PAGE='82',
 XY='(-6450,4225)',
 ROT='0',
 VER='1',
 PACK_TYPE='0402LF',
 LOCATION='R181',
 CDS_LIB='pure_quanta',
 CDS_PART_NAME='Q_RES_0402LF-0,5%,1/16W,CHIP,CS00002JB13',
 PART_NUMBER='CS00002JB13',
 VALUE='0',
 PRIM_FILE='./archive_libs/logical/q_res/chips/chips.prt';

PART_NAME
 R182 'Q_RES_0402LF-0,5%,1/16W,CHIP,CS00002JB13':;

SECTION_NUMBER 1
 '@T6G_MB_LIB.T6G(SCH_1):PAGE81_I101@PURE_QUANTA.Q_RES(CHIPS)':
 C_PATH='@t6g_mb_lib.t6g(sch_1):page81_i101@pure_quanta.q_res(chips)',
 P_PATH='@t6g_mb_lib.t6g(sch_1):page82_i101@pure_quanta.q_res(chips)',
 PATH='I101',
 DRAWING='@T6G_MB_LIB.T6G(SCH_1):PAGE81',
 BOM_COST='MEM',
 WATTAGE='1/16W',
 TOLERANCE='5%',
 MATERIAL='CHIP',
 PHYS_PAGE='82',
 XY='(-3200,4375)',
 ROT='0',
 VER='1',
 PACK_TYPE='0402LF',
 LOCATION='R182',
 CDS_LIB='pure_quanta',
 CDS_PART_NAME='Q_RES_0402LF-0,5%,1/16W,CHIP,CS00002JB13',
 PART_NUMBER='CS00002JB13',
 VALUE='0',
 PRIM_FILE='./archive_libs/logical/q_res/chips/chips.prt';

PART_NAME
 R183 'Q_RES_0402LF-0,5%,1/16W,CHIP,CS00002JB13':;

SECTION_NUMBER 1
 '@T6G_MB_LIB.T6G(SCH_1):PAGE81_I82@PURE_QUANTA.Q_RES(CHIPS)':
 C_PATH='@t6g_mb_lib.t6g(sch_1):page81_i82@pure_quanta.q_res(chips)',
 P_PATH='@t6g_mb_lib.t6g(sch_1):page82_i82@pure_quanta.q_res(chips)',
 PATH='I82',
 DRAWING='@T6G_MB_LIB.T6G(SCH_1):PAGE81',
 BOM_COST='MEM',
 WATTAGE='1/16W',
 TOLERANCE='5%',
 MATERIAL='CHIP',
 PHYS_PAGE='82',
 XY='(-3250,3575)',
 ROT='2',
 VER='1',
 PACK_TYPE='0402LF',
 LOCATION='R183',
 CDS_LIB='pure_quanta',
 CDS_PART_NAME='Q_RES_0402LF-0,5%,1/16W,CHIP,CS00002JB13',
 PART_NUMBER='CS00002JB13',
 VALUE='0',
 PRIM_FILE='./archive_libs/logical/q_res/chips/chips.prt';

PART_NAME
 R184 'Q_RES_0402LF-0,5%,1/16W,CHIP,CS00002JB13':;

SECTION_NUMBER 1
 '@T6G_MB_LIB.T6G(SCH_1):PAGE81_I48@PURE_QUANTA.Q_RES(CHIPS)':
 C_PATH='@t6g_mb_lib.t6g(sch_1):page81_i48@pure_quanta.q_res(chips)',
 P_PATH='@t6g_mb_lib.t6g(sch_1):page82_i48@pure_quanta.q_res(chips)',
 PATH='I48',
 DRAWING='@T6G_MB_LIB.T6G(SCH_1):PAGE81',
 BOM_COST='MEM',
 WATTAGE='1/16W',
 TOLERANCE='5%',
 MATERIAL='CHIP',
 PHYS_PAGE='82',
 XY='(-6450,4325)',
 ROT='0',
 VER='1',
 PACK_TYPE='0402LF',
 LOCATION='R184',
 CDS_LIB='pure_quanta',
 CDS_PART_NAME='Q_RES_0402LF-0,5%,1/16W,CHIP,CS00002JB13',
 PART_NUMBER='CS00002JB13',
 VALUE='0',
 PRIM_FILE='./archive_libs/logical/q_res/chips/chips.prt';

PART_NAME
 R185 'Q_RES_0402LF-0,5%,1/16W,CHIP,CS00002JB13':;

SECTION_NUMBER 1
 '@T6G_MB_LIB.T6G(SCH_1):PAGE81_I80@PURE_QUANTA.Q_RES(CHIPS)':
 C_PATH='@t6g_mb_lib.t6g(sch_1):page81_i80@pure_quanta.q_res(chips)',
 P_PATH='@t6g_mb_lib.t6g(sch_1):page82_i80@pure_quanta.q_res(chips)',
 PATH='I80',
 DRAWING='@T6G_MB_LIB.T6G(SCH_1):PAGE81',
 BOM_COST='MEM',
 WATTAGE='1/16W',
 TOLERANCE='5%',
 MATERIAL='CHIP',
 PHYS_PAGE='82',
 XY='(-3250,3525)',
 ROT='2',
 VER='1',
 PACK_TYPE='0402LF',
 LOCATION='R185',
 CDS_LIB='pure_quanta',
 CDS_PART_NAME='Q_RES_0402LF-0,5%,1/16W,CHIP,CS00002JB13',
 PART_NUMBER='CS00002JB13',
 VALUE='0',
 PRIM_FILE='./archive_libs/logical/q_res/chips/chips.prt';

PART_NAME
 R186 'Q_RES_0402LF-33,5%,1/16W,CHIP,CS03302JB10':;

SECTION_NUMBER 1
 '@T6G_MB_LIB.T6G(SCH_1):PAGE80_I129@PURE_QUANTA.Q_RES(CHIPS)':
 C_PATH='@t6g_mb_lib.t6g(sch_1):page80_i129@pure_quanta.q_res(chips)',
 P_PATH='@t6g_mb_lib.t6g(sch_1):page81_i129@pure_quanta.q_res(chips)',
 PATH='I129',
 DRAWING='@T6G_MB_LIB.T6G(SCH_1):PAGE80',
 BOM_COST='MEM',
 WATTAGE='1/16W',
 TOLERANCE='5%',
 MATERIAL='CHIP',
 PHYS_PAGE='81',
 XY='(-3225,4025)',
 ROT='0',
 VER='1',
 PACK_TYPE='0402LF',
 LOCATION='R186',
 CDS_LIB='pure_quanta',
 CDS_PART_NAME='Q_RES_0402LF-33,5%,1/16W,CHIP,CS03302JB10',
 PART_NUMBER='CS03302JB10',
 VALUE='33',
 PRIM_FILE='./archive_libs/logical/q_res/chips/chips.prt';

PART_NAME
 R187 'Q_RES_0402LF-0,5%,1/16W,CHIP,CS00002JB13':;

SECTION_NUMBER 1
 '@T6G_MB_LIB.T6G(SCH_1):PAGE81_I68@PURE_QUANTA.Q_RES(CHIPS)':
 C_PATH='@t6g_mb_lib.t6g(sch_1):page81_i68@pure_quanta.q_res(chips)',
 P_PATH='@t6g_mb_lib.t6g(sch_1):page82_i68@pure_quanta.q_res(chips)',
 PATH='I68',
 DRAWING='@T6G_MB_LIB.T6G(SCH_1):PAGE81',
 BOM_COST='MEM',
 WATTAGE='1/16W',
 TOLERANCE='5%',
 MATERIAL='CHIP',
 PHYS_PAGE='82',
 XY='(-6450,5775)',
 ROT='0',
 VER='1',
 PACK_TYPE='0402LF',
 LOCATION='R187',
 CDS_LIB='pure_quanta',
 CDS_PART_NAME='Q_RES_0402LF-0,5%,1/16W,CHIP,CS00002JB13',
 PART_NUMBER='CS00002JB13',
 VALUE='0',
 PRIM_FILE='./archive_libs/logical/q_res/chips/chips.prt';

PART_NAME
 R188 'Q_RES_0402LF-0,5%,1/16W,CHIP,CS00002JB13':;

SECTION_NUMBER 1
 '@T6G_MB_LIB.T6G(SCH_1):PAGE81_I61@PURE_QUANTA.Q_RES(CHIPS)':
 C_PATH='@t6g_mb_lib.t6g(sch_1):page81_i61@pure_quanta.q_res(chips)',
 P_PATH='@t6g_mb_lib.t6g(sch_1):page82_i61@pure_quanta.q_res(chips)',
 PATH='I61',
 DRAWING='@T6G_MB_LIB.T6G(SCH_1):PAGE81',
 BOM_COST='MEM',
 WATTAGE='1/16W',
 TOLERANCE='5%',
 MATERIAL='CHIP',
 PHYS_PAGE='82',
 XY='(-6450,5375)',
 ROT='0',
 VER='1',
 PACK_TYPE='0402LF',
 LOCATION='R188',
 CDS_LIB='pure_quanta',
 CDS_PART_NAME='Q_RES_0402LF-0,5%,1/16W,CHIP,CS00002JB13',
 PART_NUMBER='CS00002JB13',
 VALUE='0',
 PRIM_FILE='./archive_libs/logical/q_res/chips/chips.prt';

PART_NAME
 R189 'Q_RES_0402LF-0,5%,1/16W,CHIP,CS00002JB13':;

SECTION_NUMBER 1
 '@T6G_MB_LIB.T6G(SCH_1):PAGE81_I58@PURE_QUANTA.Q_RES(CHIPS)':
 C_PATH='@t6g_mb_lib.t6g(sch_1):page81_i58@pure_quanta.q_res(chips)',
 P_PATH='@t6g_mb_lib.t6g(sch_1):page82_i58@pure_quanta.q_res(chips)',
 PATH='I58',
 DRAWING='@T6G_MB_LIB.T6G(SCH_1):PAGE81',
 BOM_COST='MEM',
 WATTAGE='1/16W',
 TOLERANCE='5%',
 MATERIAL='CHIP',
 PHYS_PAGE='82',
 XY='(-6450,5325)',
 ROT='0',
 VER='1',
 PACK_TYPE='0402LF',
 LOCATION='R189',
 CDS_LIB='pure_quanta',
 CDS_PART_NAME='Q_RES_0402LF-0,5%,1/16W,CHIP,CS00002JB13',
 PART_NUMBER='CS00002JB13',
 VALUE='0',
 PRIM_FILE='./archive_libs/logical/q_res/chips/chips.prt';

PART_NAME
 R190 'Q_RES_0402LF-0,5%,1/16W,CHIP,CS00002JB13':;

SECTION_NUMBER 1
 '@T6G_MB_LIB.T6G(SCH_1):PAGE81_I64@PURE_QUANTA.Q_RES(CHIPS)':
 C_PATH='@t6g_mb_lib.t6g(sch_1):page81_i64@pure_quanta.q_res(chips)',
 P_PATH='@t6g_mb_lib.t6g(sch_1):page82_i64@pure_quanta.q_res(chips)',
 PATH='I64',
 DRAWING='@T6G_MB_LIB.T6G(SCH_1):PAGE81',
 BOM_COST='MEM',
 WATTAGE='1/16W',
 TOLERANCE='5%',
 MATERIAL='CHIP',
 PHYS_PAGE='82',
 XY='(-6450,5475)',
 ROT='0',
 VER='1',
 PACK_TYPE='0402LF',
 LOCATION='R190',
 CDS_LIB='pure_quanta',
 CDS_PART_NAME='Q_RES_0402LF-0,5%,1/16W,CHIP,CS00002JB13',
 PART_NUMBER='CS00002JB13',
 VALUE='0',
 PRIM_FILE='./archive_libs/logical/q_res/chips/chips.prt';

PART_NAME
 R191 'Q_RES_0402LF-0,5%,1/16W,EMPTY,CS00002JB13':;

SECTION_NUMBER 1
 '@T6G_MB_LIB.T6G(SCH_1):PAGE55_I297@PURE_QUANTA.Q_RES(CHIPS)':
 C_PATH='@t6g_mb_lib.t6g(sch_1):page55_i297@pure_quanta.q_res(chips)',
 P_PATH='@t6g_mb_lib.t6g(sch_1):page55_i297@pure_quanta.q_res(chips)',
 PATH='I297',
 DRAWING='@T6G_MB_LIB.T6G(SCH_1):PAGE55',
 BOM_COST='MEM',
 WATTAGE='1/16W',
 TOLERANCE='5%',
 MATERIAL='EMPTY',
 PHYS_PAGE='55',
 XY='(-6625,5775)',
 ROT='0',
 VER='1',
 PACK_TYPE='0402LF',
 LOCATION='R191',
 CDS_LIB='pure_quanta',
 CDS_PART_NAME='Q_RES_0402LF-0,5%,1/16W,EMPTY,CS00002JB13',
 PART_NUMBER='CS00002JB13',
 VALUE='0',
 PRIM_FILE='./archive_libs/logical/q_res/chips/chips.prt';

PART_NAME
 R192 'Q_RES_0402LF-0,5%,1/16W,EMPTY,CS00002JB13':;

SECTION_NUMBER 1
 '@T6G_MB_LIB.T6G(SCH_1):PAGE55_I298@PURE_QUANTA.Q_RES(CHIPS)':
 C_PATH='@t6g_mb_lib.t6g(sch_1):page55_i298@pure_quanta.q_res(chips)',
 P_PATH='@t6g_mb_lib.t6g(sch_1):page55_i298@pure_quanta.q_res(chips)',
 PATH='I298',
 DRAWING='@T6G_MB_LIB.T6G(SCH_1):PAGE55',
 BOM_COST='MEM',
 WATTAGE='1/16W',
 TOLERANCE='5%',
 MATERIAL='EMPTY',
 PHYS_PAGE='55',
 XY='(-6625,5725)',
 ROT='0',
 VER='1',
 PACK_TYPE='0402LF',
 LOCATION='R192',
 CDS_LIB='pure_quanta',
 CDS_PART_NAME='Q_RES_0402LF-0,5%,1/16W,EMPTY,CS00002JB13',
 PART_NUMBER='CS00002JB13',
 VALUE='0',
 PRIM_FILE='./archive_libs/logical/q_res/chips/chips.prt';

PART_NAME
 R193 'Q_RES_0402LF-0,5%,1/16W,CHIP,CS00002JB13':;

SECTION_NUMBER 1
 '@T6G_MB_LIB.T6G(SCH_1):PAGE80_I179@PURE_QUANTA.Q_RES(CHIPS)':
 C_PATH='@t6g_mb_lib.t6g(sch_1):page80_i179@pure_quanta.q_res(chips)',
 P_PATH='@t6g_mb_lib.t6g(sch_1):page81_i179@pure_quanta.q_res(chips)',
 PATH='I179',
 DRAWING='@T6G_MB_LIB.T6G(SCH_1):PAGE80',
 BOM_COST='MEM',
 WATTAGE='1/16W',
 TOLERANCE='5%',
 MATERIAL='CHIP',
 PHYS_PAGE='81',
 XY='(-3225,5925)',
 ROT='0',
 VER='1',
 PACK_TYPE='0402LF',
 LOCATION='R193',
 CDS_LIB='pure_quanta',
 CDS_PART_NAME='Q_RES_0402LF-0,5%,1/16W,CHIP,CS00002JB13',
 PART_NUMBER='CS00002JB13',
 VALUE='0',
 PRIM_FILE='./archive_libs/logical/q_res/chips/chips.prt';

PART_NAME
 R194 'Q_RES_0402LF-0,5%,1/16W,CHIP,CS00002JB13':;

SECTION_NUMBER 1
 '@T6G_MB_LIB.T6G(SCH_1):PAGE80_I100@PURE_QUANTA.Q_RES(CHIPS)':
 C_PATH='@t6g_mb_lib.t6g(sch_1):page80_i100@pure_quanta.q_res(chips)',
 P_PATH='@t6g_mb_lib.t6g(sch_1):page81_i100@pure_quanta.q_res(chips)',
 PATH='I100',
 DRAWING='@T6G_MB_LIB.T6G(SCH_1):PAGE80',
 BOM_COST='MEM',
 WATTAGE='1/16W',
 TOLERANCE='5%',
 MATERIAL='CHIP',
 PHYS_PAGE='81',
 XY='(-6425,4125)',
 ROT='0',
 VER='1',
 PACK_TYPE='0402LF',
 LOCATION='R194',
 CDS_LIB='pure_quanta',
 CDS_PART_NAME='Q_RES_0402LF-0,5%,1/16W,CHIP,CS00002JB13',
 PART_NUMBER='CS00002JB13',
 VALUE='0',
 PRIM_FILE='./archive_libs/logical/q_res/chips/chips.prt';

PART_NAME
 R195 'Q_RES_0402LF-33,5%,1/16W,CHIP,CS03302JB10':;

SECTION_NUMBER 1
 '@T6G_MB_LIB.T6G(SCH_1):PAGE80_I303@PURE_QUANTA.Q_RES(CHIPS)':
 C_PATH='@t6g_mb_lib.t6g(sch_1):page80_i303@pure_quanta.q_res(chips)',
 P_PATH='@t6g_mb_lib.t6g(sch_1):page81_i303@pure_quanta.q_res(chips)',
 PATH='I303',
 DRAWING='@T6G_MB_LIB.T6G(SCH_1):PAGE80',
 BOM_COST='MEM',
 WATTAGE='1/16W',
 TOLERANCE='5%',
 MATERIAL='CHIP',
 PHYS_PAGE='81',
 XY='(-3225,4125)',
 ROT='0',
 VER='1',
 PACK_TYPE='0402LF',
 LOCATION='R195',
 CDS_LIB='pure_quanta',
 CDS_PART_NAME='Q_RES_0402LF-33,5%,1/16W,CHIP,CS03302JB10',
 PART_NUMBER='CS03302JB10',
 VALUE='33',
 PRIM_FILE='./archive_libs/logical/q_res/chips/chips.prt';

PART_NAME
 R196 'Q_RES_0402LF-0,5%,1/16W,CHIP,CS00002JB13':;

SECTION_NUMBER 1
 '@T6G_MB_LIB.T6G(SCH_1):PAGE80_I109@PURE_QUANTA.Q_RES(CHIPS)':
 C_PATH='@t6g_mb_lib.t6g(sch_1):page80_i109@pure_quanta.q_res(chips)',
 P_PATH='@t6g_mb_lib.t6g(sch_1):page81_i109@pure_quanta.q_res(chips)',
 PATH='I109',
 DRAWING='@T6G_MB_LIB.T6G(SCH_1):PAGE80',
 BOM_COST='MEM',
 WATTAGE='1/16W',
 TOLERANCE='5%',
 MATERIAL='CHIP',
 PHYS_PAGE='81',
 XY='(-6425,4925)',
 ROT='0',
 VER='1',
 PACK_TYPE='0402LF',
 LOCATION='R196',
 CDS_LIB='pure_quanta',
 CDS_PART_NAME='Q_RES_0402LF-0,5%,1/16W,CHIP,CS00002JB13',
 PART_NUMBER='CS00002JB13',
 VALUE='0',
 PRIM_FILE='./archive_libs/logical/q_res/chips/chips.prt';

PART_NAME
 R197 'Q_RES_0402LF-0,5%,1/16W,CHIP,CS00002JB13':;

SECTION_NUMBER 1
 '@T6G_MB_LIB.T6G(SCH_1):PAGE80_I120@PURE_QUANTA.Q_RES(CHIPS)':
 C_PATH='@t6g_mb_lib.t6g(sch_1):page80_i120@pure_quanta.q_res(chips)',
 P_PATH='@t6g_mb_lib.t6g(sch_1):page81_i120@pure_quanta.q_res(chips)',
 PATH='I120',
 DRAWING='@T6G_MB_LIB.T6G(SCH_1):PAGE80',
 BOM_COST='MEM',
 WATTAGE='1/16W',
 TOLERANCE='5%',
 MATERIAL='CHIP',
 PHYS_PAGE='81',
 XY='(-6425,5675)',
 ROT='0',
 VER='1',
 PACK_TYPE='0402LF',
 LOCATION='R197',
 CDS_LIB='pure_quanta',
 CDS_PART_NAME='Q_RES_0402LF-0,5%,1/16W,CHIP,CS00002JB13',
 PART_NUMBER='CS00002JB13',
 VALUE='0',
 PRIM_FILE='./archive_libs/logical/q_res/chips/chips.prt';

PART_NAME
 R198 'Q_RES_0402LF-0,5%,1/16W,CHIP,CS00002JB13':;

SECTION_NUMBER 1
 '@T6G_MB_LIB.T6G(SCH_1):PAGE80_I122@PURE_QUANTA.Q_RES(CHIPS)':
 C_PATH='@t6g_mb_lib.t6g(sch_1):page80_i122@pure_quanta.q_res(chips)',
 P_PATH='@t6g_mb_lib.t6g(sch_1):page81_i122@pure_quanta.q_res(chips)',
 PATH='I122',
 DRAWING='@T6G_MB_LIB.T6G(SCH_1):PAGE80',
 BOM_COST='MEM',
 WATTAGE='1/16W',
 TOLERANCE='5%',
 MATERIAL='CHIP',
 PHYS_PAGE='81',
 XY='(-6425,6025)',
 ROT='0',
 VER='1',
 PACK_TYPE='0402LF',
 LOCATION='R198',
 CDS_LIB='pure_quanta',
 CDS_PART_NAME='Q_RES_0402LF-0,5%,1/16W,CHIP,CS00002JB13',
 PART_NUMBER='CS00002JB13',
 VALUE='0',
 PRIM_FILE='./archive_libs/logical/q_res/chips/chips.prt';

PART_NAME
 R199 'Q_RES_0402LF-33,5%,1/16W,CHIP,CS03302JB10':;

SECTION_NUMBER 1
 '@T6G_MB_LIB.T6G(SCH_1):PAGE80_I22@PURE_QUANTA.Q_RES(CHIPS)':
 C_PATH='@t6g_mb_lib.t6g(sch_1):page80_i22@pure_quanta.q_res(chips)',
 P_PATH='@t6g_mb_lib.t6g(sch_1):page81_i22@pure_quanta.q_res(chips)',
 PATH='I22',
 DRAWING='@T6G_MB_LIB.T6G(SCH_1):PAGE80',
 BOM_COST='MEM',
 WATTAGE='1/16W',
 TOLERANCE='5%',
 MATERIAL='CHIP',
 PHYS_PAGE='81',
 XY='(-6725,925)',
 ROT='0',
 VER='1',
 PACK_TYPE='0402LF',
 LOCATION='R199',
 CDS_LIB='pure_quanta',
 CDS_PART_NAME='Q_RES_0402LF-33,5%,1/16W,CHIP,CS03302JB10',
 PART_NUMBER='CS03302JB10',
 VALUE='33',
 PRIM_FILE='./archive_libs/logical/q_res/chips/chips.prt';

PART_NAME
 R200 'Q_RES_0402LF-4.7K,5%,1/16W,EMPTY,CS24702JB10':;

SECTION_NUMBER 1
 '@T6G_MB_LIB.T6G(SCH_1):PAGE137_I13@PURE_QUANTA.Q_RES(CHIPS)':
 C_PATH='@t6g_mb_lib.t6g(sch_1):page137_i13@pure_quanta.q_res(chips)',
 P_PATH='@t6g_mb_lib.t6g(sch_1):page160_i13@pure_quanta.q_res(chips)',
 PATH='I13',
 DRAWING='@T6G_MB_LIB.T6G(SCH_1):PAGE137',
 WATTAGE='1/16W',
 TOLERANCE='5%',
 MATERIAL='EMPTY',
 PHYS_PAGE='160',
 XY='(-6825,-2250)',
 ROT='0',
 VER='2',
 PACK_TYPE='0402LF',
 LOCATION='R200',
 CDS_LIB='pure_quanta',
 CDS_PART_NAME='Q_RES_0402LF-4.7K,5%,1/16W,EMPTY,CS24702JB10',
 PART_NUMBER='CS24702JB10',
 VALUE='4.7K',
 PRIM_FILE='./archive_libs/logical/q_res/chips/chips.prt';

PART_NAME
 R201 'Q_RES_0402LF-4.7K,5%,1/16W,EMPTY,CS24702JB10':;

SECTION_NUMBER 1
 '@T6G_MB_LIB.T6G(SCH_1):PAGE137_I62@PURE_QUANTA.Q_RES(CHIPS)':
 C_PATH='@t6g_mb_lib.t6g(sch_1):page137_i62@pure_quanta.q_res(chips)',
 P_PATH='@t6g_mb_lib.t6g(sch_1):page160_i62@pure_quanta.q_res(chips)',
 PATH='I62',
 DRAWING='@T6G_MB_LIB.T6G(SCH_1):PAGE137',
 WATTAGE='1/16W',
 TOLERANCE='5%',
 MATERIAL='EMPTY',
 PHYS_PAGE='160',
 XY='(-7050,125)',
 ROT='0',
 VER='2',
 PACK_TYPE='0402LF',
 LOCATION='R201',
 CDS_LIB='pure_quanta',
 CDS_PART_NAME='Q_RES_0402LF-4.7K,5%,1/16W,EMPTY,CS24702JB10',
 PART_NUMBER='CS24702JB10',
 VALUE='4.7K',
 PRIM_FILE='./archive_libs/logical/q_res/chips/chips.prt';

PART_NAME
 R202 'Q_RES_0402LF-0,5%,1/16W,CHIP,CS00002JB13':;

SECTION_NUMBER 1
 '@T6G_MB_LIB.T6G(SCH_1):PAGE137_I67@PURE_QUANTA.Q_RES(CHIPS)':
 C_PATH='@t6g_mb_lib.t6g(sch_1):page137_i67@pure_quanta.q_res(chips)',
 P_PATH='@t6g_mb_lib.t6g(sch_1):page160_i67@pure_quanta.q_res(chips)',
 PATH='I67',
 DRAWING='@T6G_MB_LIB.T6G(SCH_1):PAGE137',
 WATTAGE='1/16W',
 TOLERANCE='5%',
 MATERIAL='CHIP',
 PHYS_PAGE='160',
 XY='(-4400,800)',
 ROT='0',
 VER='1',
 PACK_TYPE='0402LF',
 LOCATION='R202',
 CDS_LIB='pure_quanta',
 CDS_PART_NAME='Q_RES_0402LF-0,5%,1/16W,CHIP,CS00002JB13',
 PART_NUMBER='CS00002JB13',
 VALUE='0',
 PRIM_FILE='./archive_libs/logical/q_res/chips/chips.prt';

PART_NAME
 R203 'Q_RES_0402LF-0,5%,1/16W,CHIP,CS00002JB13':;

SECTION_NUMBER 1
 '@T6G_MB_LIB.T6G(SCH_1):PAGE80_I106@PURE_QUANTA.Q_RES(CHIPS)':
 C_PATH='@t6g_mb_lib.t6g(sch_1):page80_i106@pure_quanta.q_res(chips)',
 P_PATH='@t6g_mb_lib.t6g(sch_1):page81_i106@pure_quanta.q_res(chips)',
 PATH='I106',
 DRAWING='@T6G_MB_LIB.T6G(SCH_1):PAGE80',
 BOM_COST='MEM',
 WATTAGE='1/16W',
 TOLERANCE='5%',
 MATERIAL='CHIP',
 PHYS_PAGE='81',
 XY='(-6425,4675)',
 ROT='0',
 VER='1',
 PACK_TYPE='0402LF',
 LOCATION='R203',
 CDS_LIB='pure_quanta',
 CDS_PART_NAME='Q_RES_0402LF-0,5%,1/16W,CHIP,CS00002JB13',
 PART_NUMBER='CS00002JB13',
 VALUE='0',
 PRIM_FILE='./archive_libs/logical/q_res/chips/chips.prt';

PART_NAME
 R204 'Q_RES_0402LF-0,5%,1/16W,CHIP,CS00002JB13':;

SECTION_NUMBER 1
 '@T6G_MB_LIB.T6G(SCH_1):PAGE81_I77@PURE_QUANTA.Q_RES(CHIPS)':
 C_PATH='@t6g_mb_lib.t6g(sch_1):page81_i77@pure_quanta.q_res(chips)',
 P_PATH='@t6g_mb_lib.t6g(sch_1):page82_i77@pure_quanta.q_res(chips)',
 PATH='I77',
 DRAWING='@T6G_MB_LIB.T6G(SCH_1):PAGE81',
 BOM_COST='MEM',
 WATTAGE='1/16W',
 TOLERANCE='5%',
 MATERIAL='CHIP',
 PHYS_PAGE='82',
 XY='(-6450,6125)',
 ROT='0',
 VER='1',
 PACK_TYPE='0402LF',
 LOCATION='R204',
 CDS_LIB='pure_quanta',
 CDS_PART_NAME='Q_RES_0402LF-0,5%,1/16W,CHIP,CS00002JB13',
 PART_NUMBER='CS00002JB13',
 VALUE='0',
 PRIM_FILE='./archive_libs/logical/q_res/chips/chips.prt';

PART_NAME
 R205 'Q_RES_0402LF-0,5%,1/16W,CHIP,CS00002JB13':;

SECTION_NUMBER 1
 '@T6G_MB_LIB.T6G(SCH_1):PAGE81_I74@PURE_QUANTA.Q_RES(CHIPS)':
 C_PATH='@t6g_mb_lib.t6g(sch_1):page81_i74@pure_quanta.q_res(chips)',
 P_PATH='@t6g_mb_lib.t6g(sch_1):page82_i74@pure_quanta.q_res(chips)',
 PATH='I74',
 DRAWING='@T6G_MB_LIB.T6G(SCH_1):PAGE81',
 BOM_COST='MEM',
 WATTAGE='1/16W',
 TOLERANCE='5%',
 MATERIAL='CHIP',
 PHYS_PAGE='82',
 XY='(-6450,6075)',
 ROT='0',
 VER='1',
 PACK_TYPE='0402LF',
 LOCATION='R205',
 CDS_LIB='pure_quanta',
 CDS_PART_NAME='Q_RES_0402LF-0,5%,1/16W,CHIP,CS00002JB13',
 PART_NUMBER='CS00002JB13',
 VALUE='0',
 PRIM_FILE='./archive_libs/logical/q_res/chips/chips.prt';

PART_NAME
 R206 'Q_RES_0402LF-0,5%,1/16W,CHIP,CS00002JB13':;

SECTION_NUMBER 1
 '@T6G_MB_LIB.T6G(SCH_1):PAGE137_I68@PURE_QUANTA.Q_RES(CHIPS)':
 C_PATH='@t6g_mb_lib.t6g(sch_1):page137_i68@pure_quanta.q_res(chips)',
 P_PATH='@t6g_mb_lib.t6g(sch_1):page160_i68@pure_quanta.q_res(chips)',
 PATH='I68',
 DRAWING='@T6G_MB_LIB.T6G(SCH_1):PAGE137',
 WATTAGE='1/16W',
 TOLERANCE='5%',
 MATERIAL='CHIP',
 PHYS_PAGE='160',
 XY='(-4375,700)',
 ROT='0',
 VER='1',
 PACK_TYPE='0402LF',
 LOCATION='R206',
 CDS_LIB='pure_quanta',
 CDS_PART_NAME='Q_RES_0402LF-0,5%,1/16W,CHIP,CS00002JB13',
 PART_NUMBER='CS00002JB13',
 VALUE='0',
 PRIM_FILE='./archive_libs/logical/q_res/chips/chips.prt';

PART_NAME
 R207 'Q_RES_0402LF-2.2K,5%,1/16W,CHIP,CS22202JB07':;

SECTION_NUMBER 1
 '@T6G_MB_LIB.T6G(SCH_1):PAGE28_I44@PURE_QUANTA.Q_RES(CHIPS)':
 C_PATH='@t6g_mb_lib.t6g(sch_1):page28_i44@pure_quanta.q_res(chips)',
 P_PATH='@t6g_mb_lib.t6g(sch_1):page28_i44@pure_quanta.q_res(chips)',
 PATH='I44',
 DRAWING='@T6G_MB_LIB.T6G(SCH_1):PAGE28',
 WATTAGE='1/16W',
 TOLERANCE='5%',
 MATERIAL='CHIP',
 PHYS_PAGE='28',
 XY='(-7775,8175)',
 ROT='0',
 VER='1',
 PACK_TYPE='0402LF',
 LOCATION='R207',
 CDS_LIB='pure_quanta',
 CDS_PART_NAME='Q_RES_0402LF-2.2K,5%,1/16W,CHIP,CS22202JB07',
 PART_NUMBER='CS22202JB07',
 VALUE='2.2K',
 PRIM_FILE='./archive_libs/logical/q_res/chips/chips.prt';

PART_NAME
 R208 'Q_RES_0402LF-33,5%,1/16W,CHIP,CS03302JB10':;

SECTION_NUMBER 1
 '@T6G_MB_LIB.T6G(SCH_1):PAGE80_I65@PURE_QUANTA.Q_RES(CHIPS)':
 C_PATH='@t6g_mb_lib.t6g(sch_1):page80_i65@pure_quanta.q_res(chips)',
 P_PATH='@t6g_mb_lib.t6g(sch_1):page81_i65@pure_quanta.q_res(chips)',
 PATH='I65',
 DRAWING='@T6G_MB_LIB.T6G(SCH_1):PAGE80',
 BOM_COST='MEM',
 WATTAGE='1/16W',
 TOLERANCE='5%',
 MATERIAL='CHIP',
 PHYS_PAGE='81',
 XY='(-6725,2825)',
 ROT='0',
 VER='1',
 PACK_TYPE='0402LF',
 LOCATION='R208',
 CDS_LIB='pure_quanta',
 CDS_PART_NAME='Q_RES_0402LF-33,5%,1/16W,CHIP,CS03302JB10',
 PART_NUMBER='CS03302JB10',
 VALUE='33',
 PRIM_FILE='./archive_libs/logical/q_res/chips/chips.prt';

PART_NAME
 R209 'Q_RES_0402LF-0,5%,1/16W,CHIP,CS00002JB13':;

SECTION_NUMBER 1
 '@T6G_MB_LIB.T6G(SCH_1):PAGE80_I61@PURE_QUANTA.Q_RES(CHIPS)':
 C_PATH='@t6g_mb_lib.t6g(sch_1):page80_i61@pure_quanta.q_res(chips)',
 P_PATH='@t6g_mb_lib.t6g(sch_1):page81_i61@pure_quanta.q_res(chips)',
 PATH='I61',
 DRAWING='@T6G_MB_LIB.T6G(SCH_1):PAGE80',
 BOM_COST='MEM',
 WATTAGE='1/16W',
 TOLERANCE='5%',
 MATERIAL='CHIP',
 PHYS_PAGE='81',
 XY='(-6725,2475)',
 ROT='0',
 VER='1',
 PACK_TYPE='0402LF',
 LOCATION='R209',
 CDS_LIB='pure_quanta',
 CDS_PART_NAME='Q_RES_0402LF-0,5%,1/16W,CHIP,CS00002JB13',
 PART_NUMBER='CS00002JB13',
 VALUE='0',
 PRIM_FILE='./archive_libs/logical/q_res/chips/chips.prt';

PART_NAME
 R210 'Q_RES_0402LF-0,5%,1/16W,CHIP,CS00002JB13':;

SECTION_NUMBER 1
 '@T6G_MB_LIB.T6G(SCH_1):PAGE79_I81@PURE_QUANTA.Q_RES(CHIPS)':
 C_PATH='@t6g_mb_lib.t6g(sch_1):page79_i81@pure_quanta.q_res(chips)',
 P_PATH='@t6g_mb_lib.t6g(sch_1):page80_i81@pure_quanta.q_res(chips)',
 PATH='I81',
 DRAWING='@T6G_MB_LIB.T6G(SCH_1):PAGE79',
 BOM_COST='MEM',
 WATTAGE='1/16W',
 TOLERANCE='5%',
 MATERIAL='CHIP',
 PHYS_PAGE='80',
 XY='(-2775,4650)',
 ROT='2',
 VER='1',
 PACK_TYPE='0402LF',
 LOCATION='R210',
 CDS_LIB='pure_quanta',
 CDS_PART_NAME='Q_RES_0402LF-0,5%,1/16W,CHIP,CS00002JB13',
 PART_NUMBER='CS00002JB13',
 VALUE='0',
 PRIM_FILE='./archive_libs/logical/q_res/chips/chips.prt';

PART_NAME
 R211 'Q_RES_0402LF-0,5%,1/16W,CHIP,CS00002JB13':;

SECTION_NUMBER 1
 '@T6G_MB_LIB.T6G(SCH_1):PAGE79_I80@PURE_QUANTA.Q_RES(CHIPS)':
 C_PATH='@t6g_mb_lib.t6g(sch_1):page79_i80@pure_quanta.q_res(chips)',
 P_PATH='@t6g_mb_lib.t6g(sch_1):page80_i80@pure_quanta.q_res(chips)',
 PATH='I80',
 DRAWING='@T6G_MB_LIB.T6G(SCH_1):PAGE79',
 BOM_COST='MEM',
 WATTAGE='1/16W',
 TOLERANCE='5%',
 MATERIAL='CHIP',
 PHYS_PAGE='80',
 XY='(-2775,4600)',
 ROT='2',
 VER='1',
 PACK_TYPE='0402LF',
 LOCATION='R211',
 CDS_LIB='pure_quanta',
 CDS_PART_NAME='Q_RES_0402LF-0,5%,1/16W,CHIP,CS00002JB13',
 PART_NUMBER='CS00002JB13',
 VALUE='0',
 PRIM_FILE='./archive_libs/logical/q_res/chips/chips.prt';

PART_NAME
 R212 'Q_RES_0402LF-33,5%,1/16W,CHIP,CS03302JB10':;

SECTION_NUMBER 1
 '@T6G_MB_LIB.T6G(SCH_1):PAGE28_I96@PURE_QUANTA.Q_RES(CHIPS)':
 C_PATH='@t6g_mb_lib.t6g(sch_1):page28_i96@pure_quanta.q_res(chips)',
 P_PATH='@t6g_mb_lib.t6g(sch_1):page28_i96@pure_quanta.q_res(chips)',
 PATH='I96',
 DRAWING='@T6G_MB_LIB.T6G(SCH_1):PAGE28',
 WATTAGE='1/16W',
 TOLERANCE='5%',
 MATERIAL='CHIP',
 PHYS_PAGE='28',
 XY='(-6850,10825)',
 ROT='2',
 VER='1',
 PACK_TYPE='0402LF',
 LOCATION='R212',
 CDS_LIB='pure_quanta',
 CDS_PART_NAME='Q_RES_0402LF-33,5%,1/16W,CHIP,CS03302JB10',
 PART_NUMBER='CS03302JB10',
 VALUE='33',
 PRIM_FILE='./archive_libs/logical/q_res/chips/chips.prt';

PART_NAME
 R213 'Q_RES_0402LF-0,5%,1/16W,CHIP,CS00002JB13':;

SECTION_NUMBER 1
 '@T6G_MB_LIB.T6G(SCH_1):PAGE28_I95@PURE_QUANTA.Q_RES(CHIPS)':
 C_PATH='@t6g_mb_lib.t6g(sch_1):page28_i95@pure_quanta.q_res(chips)',
 P_PATH='@t6g_mb_lib.t6g(sch_1):page28_i95@pure_quanta.q_res(chips)',
 PATH='I95',
 DRAWING='@T6G_MB_LIB.T6G(SCH_1):PAGE28',
 WATTAGE='1/16W',
 TOLERANCE='5%',
 MATERIAL='CHIP',
 PHYS_PAGE='28',
 XY='(-6850,10775)',
 ROT='2',
 VER='1',
 PACK_TYPE='0402LF',
 LOCATION='R213',
 CDS_LIB='pure_quanta',
 CDS_PART_NAME='Q_RES_0402LF-0,5%,1/16W,CHIP,CS00002JB13',
 PART_NUMBER='CS00002JB13',
 VALUE='0',
 PRIM_FILE='./archive_libs/logical/q_res/chips/chips.prt';

PART_NAME
 R214 'Q_RES_0402LF-33,5%,1/16W,CHIP,CS03302JB10':;

SECTION_NUMBER 1
 '@T6G_MB_LIB.T6G(SCH_1):PAGE315_I44@PURE_QUANTA.Q_RES(CHIPS)':
 C_PATH='@t6g_mb_lib.t6g(sch_1):page315_i44@pure_quanta.q_res(chips)',
 P_PATH='@t6g_mb_lib.t6g(sch_1):page269_i44@pure_quanta.q_res(chips)',
 PATH='I44',
 DRAWING='@T6G_MB_LIB.T6G(SCH_1):PAGE315',
 BOM_COST='MEM',
 WATTAGE='1/16W',
 TOLERANCE='5%',
 MATERIAL='CHIP',
 PHYS_PAGE='269',
 XY='(350,2525)',
 ROT='0',
 VER='1',
 PACK_TYPE='0402LF',
 LOCATION='R214',
 CDS_LIB='pure_quanta',
 CDS_PART_NAME='Q_RES_0402LF-33,5%,1/16W,CHIP,CS03302JB10',
 PART_NUMBER='CS03302JB10',
 VALUE='33',
 PRIM_FILE='./archive_libs/logical/q_res/chips/chips.prt';

PART_NAME
 R215 'Q_RES_0402LF-33,5%,1/16W,CHIP,CS03302JB10':;

SECTION_NUMBER 1
 '@T6G_MB_LIB.T6G(SCH_1):PAGE80_I104@PURE_QUANTA.Q_RES(CHIPS)':
 C_PATH='@t6g_mb_lib.t6g(sch_1):page80_i104@pure_quanta.q_res(chips)',
 P_PATH='@t6g_mb_lib.t6g(sch_1):page81_i104@pure_quanta.q_res(chips)',
 PATH='I104',
 DRAWING='@T6G_MB_LIB.T6G(SCH_1):PAGE80',
 BOM_COST='MEM',
 WATTAGE='1/16W',
 TOLERANCE='5%',
 MATERIAL='CHIP',
 PHYS_PAGE='81',
 XY='(-6425,4525)',
 ROT='0',
 VER='1',
 PACK_TYPE='0402LF',
 LOCATION='R215',
 CDS_LIB='pure_quanta',
 CDS_PART_NAME='Q_RES_0402LF-33,5%,1/16W,CHIP,CS03302JB10',
 PART_NUMBER='CS03302JB10',
 VALUE='33',
 PRIM_FILE='./archive_libs/logical/q_res/chips/chips.prt';

PART_NAME
 R216 'Q_RES_0402LF-33,5%,1/16W,CHIP,CS03302JB10':;

SECTION_NUMBER 1
 '@T6G_MB_LIB.T6G(SCH_1):PAGE80_I117@PURE_QUANTA.Q_RES(CHIPS)':
 C_PATH='@t6g_mb_lib.t6g(sch_1):page80_i117@pure_quanta.q_res(chips)',
 P_PATH='@t6g_mb_lib.t6g(sch_1):page81_i117@pure_quanta.q_res(chips)',
 PATH='I117',
 DRAWING='@T6G_MB_LIB.T6G(SCH_1):PAGE80',
 BOM_COST='MEM',
 WATTAGE='1/16W',
 TOLERANCE='5%',
 MATERIAL='CHIP',
 PHYS_PAGE='81',
 XY='(-6425,5425)',
 ROT='0',
 VER='1',
 PACK_TYPE='0402LF',
 LOCATION='R216',
 CDS_LIB='pure_quanta',
 CDS_PART_NAME='Q_RES_0402LF-33,5%,1/16W,CHIP,CS03302JB10',
 PART_NUMBER='CS03302JB10',
 VALUE='33',
 PRIM_FILE='./archive_libs/logical/q_res/chips/chips.prt';

PART_NAME
 R217 'Q_RES_0402LF-33,5%,1/16W,CHIP,CS03302JB10':;

SECTION_NUMBER 1
 '@T6G_MB_LIB.T6G(SCH_1):PAGE80_I118@PURE_QUANTA.Q_RES(CHIPS)':
 C_PATH='@t6g_mb_lib.t6g(sch_1):page80_i118@pure_quanta.q_res(chips)',
 P_PATH='@t6g_mb_lib.t6g(sch_1):page81_i118@pure_quanta.q_res(chips)',
 PATH='I118',
 DRAWING='@T6G_MB_LIB.T6G(SCH_1):PAGE80',
 BOM_COST='MEM',
 WATTAGE='1/16W',
 TOLERANCE='5%',
 MATERIAL='CHIP',
 PHYS_PAGE='81',
 XY='(-6425,5525)',
 ROT='0',
 VER='1',
 PACK_TYPE='0402LF',
 LOCATION='R217',
 CDS_LIB='pure_quanta',
 CDS_PART_NAME='Q_RES_0402LF-33,5%,1/16W,CHIP,CS03302JB10',
 PART_NUMBER='CS03302JB10',
 VALUE='33',
 PRIM_FILE='./archive_libs/logical/q_res/chips/chips.prt';

PART_NAME
 R218 'Q_RES_0402LF-33,5%,1/16W,CHIP,CS03302JB10':;

SECTION_NUMBER 1
 '@T6G_MB_LIB.T6G(SCH_1):PAGE80_I32@PURE_QUANTA.Q_RES(CHIPS)':
 C_PATH='@t6g_mb_lib.t6g(sch_1):page80_i32@pure_quanta.q_res(chips)',
 P_PATH='@t6g_mb_lib.t6g(sch_1):page81_i32@pure_quanta.q_res(chips)',
 PATH='I32',
 DRAWING='@T6G_MB_LIB.T6G(SCH_1):PAGE80',
 BOM_COST='MEM',
 WATTAGE='1/16W',
 TOLERANCE='5%',
 MATERIAL='CHIP',
 PHYS_PAGE='81',
 XY='(-6725,1625)',
 ROT='0',
 VER='1',
 PACK_TYPE='0402LF',
 LOCATION='R218',
 CDS_LIB='pure_quanta',
 CDS_PART_NAME='Q_RES_0402LF-33,5%,1/16W,CHIP,CS03302JB10',
 PART_NUMBER='CS03302JB10',
 VALUE='33',
 PRIM_FILE='./archive_libs/logical/q_res/chips/chips.prt';

PART_NAME
 R219 'Q_RES_0402LF-33,5%,1/16W,CHIP,CS03302JB10':;

SECTION_NUMBER 1
 '@T6G_MB_LIB.T6G(SCH_1):PAGE80_I108@PURE_QUANTA.Q_RES(CHIPS)':
 C_PATH='@t6g_mb_lib.t6g(sch_1):page80_i108@pure_quanta.q_res(chips)',
 P_PATH='@t6g_mb_lib.t6g(sch_1):page81_i108@pure_quanta.q_res(chips)',
 PATH='I108',
 DRAWING='@T6G_MB_LIB.T6G(SCH_1):PAGE80',
 BOM_COST='MEM',
 WATTAGE='1/16W',
 TOLERANCE='5%',
 MATERIAL='CHIP',
 PHYS_PAGE='81',
 XY='(-6425,4775)',
 ROT='0',
 VER='1',
 PACK_TYPE='0402LF',
 LOCATION='R219',
 CDS_LIB='pure_quanta',
 CDS_PART_NAME='Q_RES_0402LF-33,5%,1/16W,CHIP,CS03302JB10',
 PART_NUMBER='CS03302JB10',
 VALUE='33',
 PRIM_FILE='./archive_libs/logical/q_res/chips/chips.prt';

PART_NAME
 R220 'Q_RES_0402LF-33,5%,1/16W,CHIP,CS03302JB10':;

SECTION_NUMBER 1
 '@T6G_MB_LIB.T6G(SCH_1):PAGE81_I109@PURE_QUANTA.Q_RES(CHIPS)':
 C_PATH='@t6g_mb_lib.t6g(sch_1):page81_i109@pure_quanta.q_res(chips)',
 P_PATH='@t6g_mb_lib.t6g(sch_1):page82_i109@pure_quanta.q_res(chips)',
 PATH='I109',
 DRAWING='@T6G_MB_LIB.T6G(SCH_1):PAGE81',
 BOM_COST='MEM',
 WATTAGE='1/16W',
 TOLERANCE='5%',
 MATERIAL='CHIP',
 PHYS_PAGE='82',
 XY='(-3250,5725)',
 ROT='0',
 VER='1',
 PACK_TYPE='0402LF',
 LOCATION='R220',
 CDS_LIB='pure_quanta',
 CDS_PART_NAME='Q_RES_0402LF-33,5%,1/16W,CHIP,CS03302JB10',
 PART_NUMBER='CS03302JB10',
 VALUE='33',
 PRIM_FILE='./archive_libs/logical/q_res/chips/chips.prt';

PART_NAME
 R221 'Q_RES_0402LF-33,5%,1/16W,CHIP,CS03302JB10':;

SECTION_NUMBER 1
 '@T6G_MB_LIB.T6G(SCH_1):PAGE81_I107@PURE_QUANTA.Q_RES(CHIPS)':
 C_PATH='@t6g_mb_lib.t6g(sch_1):page81_i107@pure_quanta.q_res(chips)',
 P_PATH='@t6g_mb_lib.t6g(sch_1):page82_i107@pure_quanta.q_res(chips)',
 PATH='I107',
 DRAWING='@T6G_MB_LIB.T6G(SCH_1):PAGE81',
 BOM_COST='MEM',
 WATTAGE='1/16W',
 TOLERANCE='5%',
 MATERIAL='CHIP',
 PHYS_PAGE='82',
 XY='(-3250,5525)',
 ROT='0',
 VER='1',
 PACK_TYPE='0402LF',
 LOCATION='R221',
 CDS_LIB='pure_quanta',
 CDS_PART_NAME='Q_RES_0402LF-33,5%,1/16W,CHIP,CS03302JB10',
 PART_NUMBER='CS03302JB10',
 VALUE='33',
 PRIM_FILE='./archive_libs/logical/q_res/chips/chips.prt';

PART_NAME
 R222 'Q_RES_0402LF-0,5%,1/16W,CHIP,CS00002JB13':;

SECTION_NUMBER 1
 '@T6G_MB_LIB.T6G(SCH_1):PAGE81_I52@PURE_QUANTA.Q_RES(CHIPS)':
 C_PATH='@t6g_mb_lib.t6g(sch_1):page81_i52@pure_quanta.q_res(chips)',
 P_PATH='@t6g_mb_lib.t6g(sch_1):page82_i52@pure_quanta.q_res(chips)',
 PATH='I52',
 DRAWING='@T6G_MB_LIB.T6G(SCH_1):PAGE81',
 BOM_COST='MEM',
 WATTAGE='1/16W',
 TOLERANCE='5%',
 MATERIAL='CHIP',
 PHYS_PAGE='82',
 XY='(-6450,4775)',
 ROT='0',
 VER='1',
 PACK_TYPE='0402LF',
 LOCATION='R222',
 CDS_LIB='pure_quanta',
 CDS_PART_NAME='Q_RES_0402LF-0,5%,1/16W,CHIP,CS00002JB13',
 PART_NUMBER='CS00002JB13',
 VALUE='0',
 PRIM_FILE='./archive_libs/logical/q_res/chips/chips.prt';

PART_NAME
 R223 'Q_RES_0402LF-0,5%,1/16W,CHIP,CS00002JB13':;

SECTION_NUMBER 1
 '@T6G_MB_LIB.T6G(SCH_1):PAGE81_I100@PURE_QUANTA.Q_RES(CHIPS)':
 C_PATH='@t6g_mb_lib.t6g(sch_1):page81_i100@pure_quanta.q_res(chips)',
 P_PATH='@t6g_mb_lib.t6g(sch_1):page82_i100@pure_quanta.q_res(chips)',
 PATH='I100',
 DRAWING='@T6G_MB_LIB.T6G(SCH_1):PAGE81',
 BOM_COST='MEM',
 WATTAGE='1/16W',
 TOLERANCE='5%',
 MATERIAL='CHIP',
 PHYS_PAGE='82',
 XY='(-3200,4325)',
 ROT='0',
 VER='1',
 PACK_TYPE='0402LF',
 LOCATION='R223',
 CDS_LIB='pure_quanta',
 CDS_PART_NAME='Q_RES_0402LF-0,5%,1/16W,CHIP,CS00002JB13',
 PART_NUMBER='CS00002JB13',
 VALUE='0',
 PRIM_FILE='./archive_libs/logical/q_res/chips/chips.prt';

PART_NAME
 R224 'Q_RES_0402LF-33,5%,1/16W,CHIP,CS03302JB10':;

SECTION_NUMBER 1
 '@T6G_MB_LIB.T6G(SCH_1):PAGE80_I36@PURE_QUANTA.Q_RES(CHIPS)':
 C_PATH='@t6g_mb_lib.t6g(sch_1):page80_i36@pure_quanta.q_res(chips)',
 P_PATH='@t6g_mb_lib.t6g(sch_1):page81_i36@pure_quanta.q_res(chips)',
 PATH='I36',
 DRAWING='@T6G_MB_LIB.T6G(SCH_1):PAGE80',
 BOM_COST='MEM',
 WATTAGE='1/16W',
 TOLERANCE='5%',
 MATERIAL='CHIP',
 PHYS_PAGE='81',
 XY='(-6725,1875)',
 ROT='0',
 VER='1',
 PACK_TYPE='0402LF',
 LOCATION='R224',
 CDS_LIB='pure_quanta',
 CDS_PART_NAME='Q_RES_0402LF-33,5%,1/16W,CHIP,CS03302JB10',
 PART_NUMBER='CS03302JB10',
 VALUE='33',
 PRIM_FILE='./archive_libs/logical/q_res/chips/chips.prt';

PART_NAME
 R225 'Q_RES_0402LF-33,5%,1/16W,CHIP,CS03302JB10':;

SECTION_NUMBER 1
 '@T6G_MB_LIB.T6G(SCH_1):PAGE167_I33@PURE_QUANTA.Q_RES(CHIPS)':
 C_PATH='@t6g_mb_lib.t6g(sch_1):page167_i33@pure_quanta.q_res(chips)',
 P_PATH='@t6g_mb_lib.t6g(sch_1):page192_i33@pure_quanta.q_res(chips)',
 PATH='I33',
 DRAWING='@T6G_MB_LIB.T6G(SCH_1):PAGE167',
 BOM_COST='MEM',
 WATTAGE='1/16W',
 TOLERANCE='5%',
 MATERIAL='CHIP',
 PHYS_PAGE='192',
 XY='(-5225,4100)',
 ROT='0',
 VER='1',
 PACK_TYPE='0402LF',
 LOCATION='R225',
 CDS_LIB='pure_quanta',
 CDS_PART_NAME='Q_RES_0402LF-33,5%,1/16W,CHIP,CS03302JB10',
 PART_NUMBER='CS03302JB10',
 VALUE='33',
 PRIM_FILE='./archive_libs/logical/q_res/chips/chips.prt';

PART_NAME
 R226 'Q_RES_0402LF-0,5%,1/16W,CHIP,CS00002JB13':;

SECTION_NUMBER 1
 '@T6G_MB_LIB.T6G(SCH_1):PAGE81_I111@PURE_QUANTA.Q_RES(CHIPS)':
 C_PATH='@t6g_mb_lib.t6g(sch_1):page81_i111@pure_quanta.q_res(chips)',
 P_PATH='@t6g_mb_lib.t6g(sch_1):page82_i111@pure_quanta.q_res(chips)',
 PATH='I111',
 DRAWING='@T6G_MB_LIB.T6G(SCH_1):PAGE81',
 BOM_COST='MEM',
 WATTAGE='1/16W',
 TOLERANCE='5%',
 MATERIAL='CHIP',
 PHYS_PAGE='82',
 XY='(-3250,5975)',
 ROT='0',
 VER='1',
 PACK_TYPE='0402LF',
 LOCATION='R226',
 CDS_LIB='pure_quanta',
 CDS_PART_NAME='Q_RES_0402LF-0,5%,1/16W,CHIP,CS00002JB13',
 PART_NUMBER='CS00002JB13',
 VALUE='0',
 PRIM_FILE='./archive_libs/logical/q_res/chips/chips.prt';

PART_NAME
 R227 'Q_RES_0402LF-33,5%,1/16W,CHIP,CS03302JB10':;

SECTION_NUMBER 1
 '@T6G_MB_LIB.T6G(SCH_1):PAGE81_I103@PURE_QUANTA.Q_RES(CHIPS)':
 C_PATH='@t6g_mb_lib.t6g(sch_1):page81_i103@pure_quanta.q_res(chips)',
 P_PATH='@t6g_mb_lib.t6g(sch_1):page82_i103@pure_quanta.q_res(chips)',
 PATH='I103',
 DRAWING='@T6G_MB_LIB.T6G(SCH_1):PAGE81',
 BOM_COST='MEM',
 WATTAGE='1/16W',
 TOLERANCE='5%',
 MATERIAL='CHIP',
 PHYS_PAGE='82',
 XY='(-3200,4975)',
 ROT='0',
 VER='1',
 PACK_TYPE='0402LF',
 LOCATION='R227',
 CDS_LIB='pure_quanta',
 CDS_PART_NAME='Q_RES_0402LF-33,5%,1/16W,CHIP,CS03302JB10',
 PART_NUMBER='CS03302JB10',
 VALUE='33',
 PRIM_FILE='./archive_libs/logical/q_res/chips/chips.prt';

PART_NAME
 R228 'Q_RES_0402LF-0,5%,1/16W,CHIP,CS00002JB13':;

SECTION_NUMBER 1
 '@T6G_MB_LIB.T6G(SCH_1):PAGE80_I66@PURE_QUANTA.Q_RES(CHIPS)':
 C_PATH='@t6g_mb_lib.t6g(sch_1):page80_i66@pure_quanta.q_res(chips)',
 P_PATH='@t6g_mb_lib.t6g(sch_1):page81_i66@pure_quanta.q_res(chips)',
 PATH='I66',
 DRAWING='@T6G_MB_LIB.T6G(SCH_1):PAGE80',
 BOM_COST='MEM',
 WATTAGE='1/16W',
 TOLERANCE='5%',
 MATERIAL='CHIP',
 PHYS_PAGE='81',
 XY='(-6725,2875)',
 ROT='0',
 VER='1',
 PACK_TYPE='0402LF',
 LOCATION='R228',
 CDS_LIB='pure_quanta',
 CDS_PART_NAME='Q_RES_0402LF-0,5%,1/16W,CHIP,CS00002JB13',
 PART_NUMBER='CS00002JB13',
 VALUE='0',
 PRIM_FILE='./archive_libs/logical/q_res/chips/chips.prt';

PART_NAME
 R229 'Q_RES_0402LF-33,5%,1/16W,CHIP,CS03302JB10':;

SECTION_NUMBER 1
 '@T6G_MB_LIB.T6G(SCH_1):PAGE80_I68@PURE_QUANTA.Q_RES(CHIPS)':
 C_PATH='@t6g_mb_lib.t6g(sch_1):page80_i68@pure_quanta.q_res(chips)',
 P_PATH='@t6g_mb_lib.t6g(sch_1):page81_i68@pure_quanta.q_res(chips)',
 PATH='I68',
 DRAWING='@T6G_MB_LIB.T6G(SCH_1):PAGE80',
 BOM_COST='MEM',
 WATTAGE='1/16W',
 TOLERANCE='5%',
 MATERIAL='CHIP',
 PHYS_PAGE='81',
 XY='(-6725,3075)',
 ROT='0',
 VER='1',
 PACK_TYPE='0402LF',
 LOCATION='R229',
 CDS_LIB='pure_quanta',
 CDS_PART_NAME='Q_RES_0402LF-33,5%,1/16W,CHIP,CS03302JB10',
 PART_NUMBER='CS03302JB10',
 VALUE='33',
 PRIM_FILE='./archive_libs/logical/q_res/chips/chips.prt';

PART_NAME
 R230 'Q_RES_0402LF-0,5%,1/16W,CHIP,CS00002JB13':;

SECTION_NUMBER 1
 '@T6G_MB_LIB.T6G(SCH_1):PAGE80_I67@PURE_QUANTA.Q_RES(CHIPS)':
 C_PATH='@t6g_mb_lib.t6g(sch_1):page80_i67@pure_quanta.q_res(chips)',
 P_PATH='@t6g_mb_lib.t6g(sch_1):page81_i67@pure_quanta.q_res(chips)',
 PATH='I67',
 DRAWING='@T6G_MB_LIB.T6G(SCH_1):PAGE80',
 BOM_COST='MEM',
 WATTAGE='1/16W',
 TOLERANCE='5%',
 MATERIAL='CHIP',
 PHYS_PAGE='81',
 XY='(-6725,3025)',
 ROT='0',
 VER='1',
 PACK_TYPE='0402LF',
 LOCATION='R230',
 CDS_LIB='pure_quanta',
 CDS_PART_NAME='Q_RES_0402LF-0,5%,1/16W,CHIP,CS00002JB13',
 PART_NUMBER='CS00002JB13',
 VALUE='0',
 PRIM_FILE='./archive_libs/logical/q_res/chips/chips.prt';

PART_NAME
 R231 'Q_RES_0402LF-0,5%,1/16W,CHIP,CS00002JB13':;

SECTION_NUMBER 1
 '@T6G_MB_LIB.T6G(SCH_1):PAGE81_I60@PURE_QUANTA.Q_RES(CHIPS)':
 C_PATH='@t6g_mb_lib.t6g(sch_1):page81_i60@pure_quanta.q_res(chips)',
 P_PATH='@t6g_mb_lib.t6g(sch_1):page82_i60@pure_quanta.q_res(chips)',
 PATH='I60',
 DRAWING='@T6G_MB_LIB.T6G(SCH_1):PAGE81',
 BOM_COST='MEM',
 WATTAGE='1/16W',
 TOLERANCE='5%',
 MATERIAL='CHIP',
 PHYS_PAGE='82',
 XY='(-6450,5275)',
 ROT='0',
 VER='1',
 PACK_TYPE='0402LF',
 LOCATION='R231',
 CDS_LIB='pure_quanta',
 CDS_PART_NAME='Q_RES_0402LF-0,5%,1/16W,CHIP,CS00002JB13',
 PART_NUMBER='CS00002JB13',
 VALUE='0',
 PRIM_FILE='./archive_libs/logical/q_res/chips/chips.prt';

PART_NAME
 R232 'Q_RES_0402LF-33,5%,1/16W,CHIP,CS03302JB10':;

SECTION_NUMBER 1
 '@T6G_MB_LIB.T6G(SCH_1):PAGE81_I51@PURE_QUANTA.Q_RES(CHIPS)':
 C_PATH='@t6g_mb_lib.t6g(sch_1):page81_i51@pure_quanta.q_res(chips)',
 P_PATH='@t6g_mb_lib.t6g(sch_1):page82_i51@pure_quanta.q_res(chips)',
 PATH='I51',
 DRAWING='@T6G_MB_LIB.T6G(SCH_1):PAGE81',
 BOM_COST='MEM',
 WATTAGE='1/16W',
 TOLERANCE='5%',
 MATERIAL='CHIP',
 PHYS_PAGE='82',
 XY='(-6450,4675)',
 ROT='0',
 VER='1',
 PACK_TYPE='0402LF',
 LOCATION='R232',
 CDS_LIB='pure_quanta',
 CDS_PART_NAME='Q_RES_0402LF-33,5%,1/16W,CHIP,CS03302JB10',
 PART_NUMBER='CS03302JB10',
 VALUE='33',
 PRIM_FILE='./archive_libs/logical/q_res/chips/chips.prt';

PART_NAME
 R233 'Q_RES_0402LF-0,5%,1/16W,CHIP,CS00002JB13':;

SECTION_NUMBER 1
 '@T6G_MB_LIB.T6G(SCH_1):PAGE81_I54@PURE_QUANTA.Q_RES(CHIPS)':
 C_PATH='@t6g_mb_lib.t6g(sch_1):page81_i54@pure_quanta.q_res(chips)',
 P_PATH='@t6g_mb_lib.t6g(sch_1):page82_i54@pure_quanta.q_res(chips)',
 PATH='I54',
 DRAWING='@T6G_MB_LIB.T6G(SCH_1):PAGE81',
 BOM_COST='MEM',
 WATTAGE='1/16W',
 TOLERANCE='5%',
 MATERIAL='CHIP',
 PHYS_PAGE='82',
 XY='(-6450,4875)',
 ROT='0',
 VER='1',
 PACK_TYPE='0402LF',
 LOCATION='R233',
 CDS_LIB='pure_quanta',
 CDS_PART_NAME='Q_RES_0402LF-0,5%,1/16W,CHIP,CS00002JB13',
 PART_NUMBER='CS00002JB13',
 VALUE='0',
 PRIM_FILE='./archive_libs/logical/q_res/chips/chips.prt';

PART_NAME
 R234 'Q_RES_0402LF-0,5%,1/16W,CHIP,CS00002JB13':;

SECTION_NUMBER 1
 '@T6G_MB_LIB.T6G(SCH_1):PAGE81_I75@PURE_QUANTA.Q_RES(CHIPS)':
 C_PATH='@t6g_mb_lib.t6g(sch_1):page81_i75@pure_quanta.q_res(chips)',
 P_PATH='@t6g_mb_lib.t6g(sch_1):page82_i75@pure_quanta.q_res(chips)',
 PATH='I75',
 DRAWING='@T6G_MB_LIB.T6G(SCH_1):PAGE81',
 BOM_COST='MEM',
 WATTAGE='1/16W',
 TOLERANCE='5%',
 MATERIAL='CHIP',
 PHYS_PAGE='82',
 XY='(-6450,6025)',
 ROT='0',
 VER='1',
 PACK_TYPE='0402LF',
 LOCATION='R234',
 CDS_LIB='pure_quanta',
 CDS_PART_NAME='Q_RES_0402LF-0,5%,1/16W,CHIP,CS00002JB13',
 PART_NUMBER='CS00002JB13',
 VALUE='0',
 PRIM_FILE='./archive_libs/logical/q_res/chips/chips.prt';

PART_NAME
 R235 'Q_RES_0402LF-0,5%,1/16W,CHIP,CS00002JB13':;

SECTION_NUMBER 1
 '@T6G_MB_LIB.T6G(SCH_1):PAGE81_I70@PURE_QUANTA.Q_RES(CHIPS)':
 C_PATH='@t6g_mb_lib.t6g(sch_1):page81_i70@pure_quanta.q_res(chips)',
 P_PATH='@t6g_mb_lib.t6g(sch_1):page82_i70@pure_quanta.q_res(chips)',
 PATH='I70',
 DRAWING='@T6G_MB_LIB.T6G(SCH_1):PAGE81',
 BOM_COST='MEM',
 WATTAGE='1/16W',
 TOLERANCE='5%',
 MATERIAL='CHIP',
 PHYS_PAGE='82',
 XY='(-6450,5825)',
 ROT='0',
 VER='1',
 PACK_TYPE='0402LF',
 LOCATION='R235',
 CDS_LIB='pure_quanta',
 CDS_PART_NAME='Q_RES_0402LF-0,5%,1/16W,CHIP,CS00002JB13',
 PART_NUMBER='CS00002JB13',
 VALUE='0',
 PRIM_FILE='./archive_libs/logical/q_res/chips/chips.prt';

PART_NAME
 R236 'Q_RES_0402LF-0,5%,1/16W,CHIP,CS00002JB13':;

SECTION_NUMBER 1
 '@T6G_MB_LIB.T6G(SCH_1):PAGE81_I66@PURE_QUANTA.Q_RES(CHIPS)':
 C_PATH='@t6g_mb_lib.t6g(sch_1):page81_i66@pure_quanta.q_res(chips)',
 P_PATH='@t6g_mb_lib.t6g(sch_1):page82_i66@pure_quanta.q_res(chips)',
 PATH='I66',
 DRAWING='@T6G_MB_LIB.T6G(SCH_1):PAGE81',
 BOM_COST='MEM',
 WATTAGE='1/16W',
 TOLERANCE='5%',
 MATERIAL='CHIP',
 PHYS_PAGE='82',
 XY='(-6450,5675)',
 ROT='0',
 VER='1',
 PACK_TYPE='0402LF',
 LOCATION='R236',
 CDS_LIB='pure_quanta',
 CDS_PART_NAME='Q_RES_0402LF-0,5%,1/16W,CHIP,CS00002JB13',
 PART_NUMBER='CS00002JB13',
 VALUE='0',
 PRIM_FILE='./archive_libs/logical/q_res/chips/chips.prt';

PART_NAME
 R237 'Q_RES_0402LF-0,5%,1/16W,CHIP,CS00002JB13':;

SECTION_NUMBER 1
 '@T6G_MB_LIB.T6G(SCH_1):PAGE81_I69@PURE_QUANTA.Q_RES(CHIPS)':
 C_PATH='@t6g_mb_lib.t6g(sch_1):page81_i69@pure_quanta.q_res(chips)',
 P_PATH='@t6g_mb_lib.t6g(sch_1):page82_i69@pure_quanta.q_res(chips)',
 PATH='I69',
 DRAWING='@T6G_MB_LIB.T6G(SCH_1):PAGE81',
 BOM_COST='MEM',
 WATTAGE='1/16W',
 TOLERANCE='5%',
 MATERIAL='CHIP',
 PHYS_PAGE='82',
 XY='(-6450,5725)',
 ROT='0',
 VER='1',
 PACK_TYPE='0402LF',
 LOCATION='R237',
 CDS_LIB='pure_quanta',
 CDS_PART_NAME='Q_RES_0402LF-0,5%,1/16W,CHIP,CS00002JB13',
 PART_NUMBER='CS00002JB13',
 VALUE='0',
 PRIM_FILE='./archive_libs/logical/q_res/chips/chips.prt';

PART_NAME
 R238 'Q_RES_0402LF-0,5%,1/16W,CHIP,CS00002JB13':;

SECTION_NUMBER 1
 '@T6G_MB_LIB.T6G(SCH_1):PAGE81_I71@PURE_QUANTA.Q_RES(CHIPS)':
 C_PATH='@t6g_mb_lib.t6g(sch_1):page81_i71@pure_quanta.q_res(chips)',
 P_PATH='@t6g_mb_lib.t6g(sch_1):page82_i71@pure_quanta.q_res(chips)',
 PATH='I71',
 DRAWING='@T6G_MB_LIB.T6G(SCH_1):PAGE81',
 BOM_COST='MEM',
 WATTAGE='1/16W',
 TOLERANCE='5%',
 MATERIAL='CHIP',
 PHYS_PAGE='82',
 XY='(-6450,5925)',
 ROT='0',
 VER='1',
 PACK_TYPE='0402LF',
 LOCATION='R238',
 CDS_LIB='pure_quanta',
 CDS_PART_NAME='Q_RES_0402LF-0,5%,1/16W,CHIP,CS00002JB13',
 PART_NUMBER='CS00002JB13',
 VALUE='0',
 PRIM_FILE='./archive_libs/logical/q_res/chips/chips.prt';

PART_NAME
 R239 'Q_RES_0402LF-0,5%,1/16W,CHIP,CS00002JB13':;

SECTION_NUMBER 1
 '@T6G_MB_LIB.T6G(SCH_1):PAGE81_I62@PURE_QUANTA.Q_RES(CHIPS)':
 C_PATH='@t6g_mb_lib.t6g(sch_1):page81_i62@pure_quanta.q_res(chips)',
 P_PATH='@t6g_mb_lib.t6g(sch_1):page82_i62@pure_quanta.q_res(chips)',
 PATH='I62',
 DRAWING='@T6G_MB_LIB.T6G(SCH_1):PAGE81',
 BOM_COST='MEM',
 WATTAGE='1/16W',
 TOLERANCE='5%',
 MATERIAL='CHIP',
 PHYS_PAGE='82',
 XY='(-6450,5425)',
 ROT='0',
 VER='1',
 PACK_TYPE='0402LF',
 LOCATION='R239',
 CDS_LIB='pure_quanta',
 CDS_PART_NAME='Q_RES_0402LF-0,5%,1/16W,CHIP,CS00002JB13',
 PART_NUMBER='CS00002JB13',
 VALUE='0',
 PRIM_FILE='./archive_libs/logical/q_res/chips/chips.prt';

PART_NAME
 R240 'Q_RES_0402LF-100,1%,1/16W,CHIP,CS11002FB07':;

SECTION_NUMBER 1
 '@T6G_MB_LIB.T6G(SCH_1):PAGE192_I65@PURE_QUANTA.Q_RES(CHIPS)':
 C_PATH='@t6g_mb_lib.t6g(sch_1):page192_i65@pure_quanta.q_res(chips)',
 P_PATH='@t6g_mb_lib.t6g(sch_1):page217_i65@pure_quanta.q_res(chips)',
 PATH='I65',
 DRAWING='@T6G_MB_LIB.T6G(SCH_1):PAGE192',
 WATTAGE='1/16W',
 TOLERANCE='1%',
 MATERIAL='CHIP',
 PHYS_PAGE='217',
 XY='(-2200,3375)',
 ROT='0',
 VER='1',
 PACK_TYPE='0402LF',
 LOCATION='R240',
 CDS_LIB='pure_quanta',
 CDS_PART_NAME='Q_RES_0402LF-100,1%,1/16W,CHIP,CS11002FB07',
 PART_NUMBER='CS11002FB07',
 VALUE='100',
 PRIM_FILE='./archive_libs/logical/q_res/chips/chips.prt';

PART_NAME
 R241 'Q_RES_0402LF-0,5%,1/16W,CHIP,CS00002JB13':;

SECTION_NUMBER 1
 '@T6G_MB_LIB.T6G(SCH_1):PAGE80_I114@PURE_QUANTA.Q_RES(CHIPS)':
 C_PATH='@t6g_mb_lib.t6g(sch_1):page80_i114@pure_quanta.q_res(chips)',
 P_PATH='@t6g_mb_lib.t6g(sch_1):page81_i114@pure_quanta.q_res(chips)',
 PATH='I114',
 DRAWING='@T6G_MB_LIB.T6G(SCH_1):PAGE80',
 BOM_COST='MEM',
 WATTAGE='1/16W',
 TOLERANCE='5%',
 MATERIAL='CHIP',
 PHYS_PAGE='81',
 XY='(-6425,5175)',
 ROT='0',
 VER='1',
 PACK_TYPE='0402LF',
 LOCATION='R241',
 CDS_LIB='pure_quanta',
 CDS_PART_NAME='Q_RES_0402LF-0,5%,1/16W,CHIP,CS00002JB13',
 PART_NUMBER='CS00002JB13',
 VALUE='0',
 PRIM_FILE='./archive_libs/logical/q_res/chips/chips.prt';

PART_NAME
 R242 'Q_RES_0402LF-0,5%,1/16W,CHIP,CS00002JB13':;

SECTION_NUMBER 1
 '@T6G_MB_LIB.T6G(SCH_1):PAGE80_I110@PURE_QUANTA.Q_RES(CHIPS)':
 C_PATH='@t6g_mb_lib.t6g(sch_1):page80_i110@pure_quanta.q_res(chips)',
 P_PATH='@t6g_mb_lib.t6g(sch_1):page81_i110@pure_quanta.q_res(chips)',
 PATH='I110',
 DRAWING='@T6G_MB_LIB.T6G(SCH_1):PAGE80',
 BOM_COST='MEM',
 WATTAGE='1/16W',
 TOLERANCE='5%',
 MATERIAL='CHIP',
 PHYS_PAGE='81',
 XY='(-6425,4975)',
 ROT='0',
 VER='1',
 PACK_TYPE='0402LF',
 LOCATION='R242',
 CDS_LIB='pure_quanta',
 CDS_PART_NAME='Q_RES_0402LF-0,5%,1/16W,CHIP,CS00002JB13',
 PART_NUMBER='CS00002JB13',
 VALUE='0',
 PRIM_FILE='./archive_libs/logical/q_res/chips/chips.prt';

PART_NAME
 R243 'Q_RES_0402LF-0,5%,1/16W,CHIP,CS00002JB13':;

SECTION_NUMBER 1
 '@T6G_MB_LIB.T6G(SCH_1):PAGE81_I63@PURE_QUANTA.Q_RES(CHIPS)':
 C_PATH='@t6g_mb_lib.t6g(sch_1):page81_i63@pure_quanta.q_res(chips)',
 P_PATH='@t6g_mb_lib.t6g(sch_1):page82_i63@pure_quanta.q_res(chips)',
 PATH='I63',
 DRAWING='@T6G_MB_LIB.T6G(SCH_1):PAGE81',
 BOM_COST='MEM',
 WATTAGE='1/16W',
 TOLERANCE='5%',
 MATERIAL='CHIP',
 PHYS_PAGE='82',
 XY='(-6450,5525)',
 ROT='0',
 VER='1',
 PACK_TYPE='0402LF',
 LOCATION='R243',
 CDS_LIB='pure_quanta',
 CDS_PART_NAME='Q_RES_0402LF-0,5%,1/16W,CHIP,CS00002JB13',
 PART_NUMBER='CS00002JB13',
 VALUE='0',
 PRIM_FILE='./archive_libs/logical/q_res/chips/chips.prt';

PART_NAME
 R244 'Q_RES_0402LF-0,5%,1/16W,CHIP,CS00002JB13':;

SECTION_NUMBER 1
 '@T6G_MB_LIB.T6G(SCH_1):PAGE81_I72@PURE_QUANTA.Q_RES(CHIPS)':
 C_PATH='@t6g_mb_lib.t6g(sch_1):page81_i72@pure_quanta.q_res(chips)',
 P_PATH='@t6g_mb_lib.t6g(sch_1):page82_i72@pure_quanta.q_res(chips)',
 PATH='I72',
 DRAWING='@T6G_MB_LIB.T6G(SCH_1):PAGE81',
 BOM_COST='MEM',
 WATTAGE='1/16W',
 TOLERANCE='5%',
 MATERIAL='CHIP',
 PHYS_PAGE='82',
 XY='(-6450,5875)',
 ROT='0',
 VER='1',
 PACK_TYPE='0402LF',
 LOCATION='R244',
 CDS_LIB='pure_quanta',
 CDS_PART_NAME='Q_RES_0402LF-0,5%,1/16W,CHIP,CS00002JB13',
 PART_NUMBER='CS00002JB13',
 VALUE='0',
 PRIM_FILE='./archive_libs/logical/q_res/chips/chips.prt';

PART_NAME
 R245 'Q_RES_0402LF-0,5%,1/16W,CHIP,CS00002JB13':;

SECTION_NUMBER 1
 '@T6G_MB_LIB.T6G(SCH_1):PAGE81_I67@PURE_QUANTA.Q_RES(CHIPS)':
 C_PATH='@t6g_mb_lib.t6g(sch_1):page81_i67@pure_quanta.q_res(chips)',
 P_PATH='@t6g_mb_lib.t6g(sch_1):page82_i67@pure_quanta.q_res(chips)',
 PATH='I67',
 DRAWING='@T6G_MB_LIB.T6G(SCH_1):PAGE81',
 BOM_COST='MEM',
 WATTAGE='1/16W',
 TOLERANCE='5%',
 MATERIAL='CHIP',
 PHYS_PAGE='82',
 XY='(-6450,5625)',
 ROT='0',
 VER='1',
 PACK_TYPE='0402LF',
 LOCATION='R245',
 CDS_LIB='pure_quanta',
 CDS_PART_NAME='Q_RES_0402LF-0,5%,1/16W,CHIP,CS00002JB13',
 PART_NUMBER='CS00002JB13',
 VALUE='0',
 PRIM_FILE='./archive_libs/logical/q_res/chips/chips.prt';

PART_NAME
 R246 'Q_RES_0402LF-0,5%,1/16W,CHIP,CS00002JB13':;

SECTION_NUMBER 1
 '@T6G_MB_LIB.T6G(SCH_1):PAGE81_I65@PURE_QUANTA.Q_RES(CHIPS)':
 C_PATH='@t6g_mb_lib.t6g(sch_1):page81_i65@pure_quanta.q_res(chips)',
 P_PATH='@t6g_mb_lib.t6g(sch_1):page82_i65@pure_quanta.q_res(chips)',
 PATH='I65',
 DRAWING='@T6G_MB_LIB.T6G(SCH_1):PAGE81',
 BOM_COST='MEM',
 WATTAGE='1/16W',
 TOLERANCE='5%',
 MATERIAL='CHIP',
 PHYS_PAGE='82',
 XY='(-6450,5575)',
 ROT='0',
 VER='1',
 PACK_TYPE='0402LF',
 LOCATION='R246',
 CDS_LIB='pure_quanta',
 CDS_PART_NAME='Q_RES_0402LF-0,5%,1/16W,CHIP,CS00002JB13',
 PART_NUMBER='CS00002JB13',
 VALUE='0',
 PRIM_FILE='./archive_libs/logical/q_res/chips/chips.prt';

PART_NAME
 R247 'Q_RES_0402LF-33,5%,1/16W,CHIP,CS03302JB10':;

SECTION_NUMBER 1
 '@T6G_MB_LIB.T6G(SCH_1):PAGE27_I401@PURE_QUANTA.Q_RES(CHIPS)':
 C_PATH='@t6g_mb_lib.t6g(sch_1):page27_i401@pure_quanta.q_res(chips)',
 P_PATH='@t6g_mb_lib.t6g(sch_1):page27_i401@pure_quanta.q_res(chips)',
 PATH='I401',
 DRAWING='@T6G_MB_LIB.T6G(SCH_1):PAGE27',
 BOM_COST='MEM',
 WATTAGE='1/16W',
 TOLERANCE='5%',
 MATERIAL='CHIP',
 PHYS_PAGE='27',
 XY='(-2725,4875)',
 ROT='0',
 VER='1',
 PACK_TYPE='0402LF',
 LOCATION='R247',
 CDS_LIB='pure_quanta',
 CDS_PART_NAME='Q_RES_0402LF-33,5%,1/16W,CHIP,CS03302JB10',
 PART_NUMBER='CS03302JB10',
 VALUE='33',
 PRIM_FILE='./archive_libs/logical/q_res/chips/chips.prt';

PART_NAME
 R248 'Q_RES_0402LF-33,5%,1/16W,CHIP,CS03302JB10':;

SECTION_NUMBER 1
 '@T6G_MB_LIB.T6G(SCH_1):PAGE28_I136@PURE_QUANTA.Q_RES(CHIPS)':
 C_PATH='@t6g_mb_lib.t6g(sch_1):page28_i136@pure_quanta.q_res(chips)',
 P_PATH='@t6g_mb_lib.t6g(sch_1):page28_i136@pure_quanta.q_res(chips)',
 PATH='I136',
 DRAWING='@T6G_MB_LIB.T6G(SCH_1):PAGE28',
 BOM_COST='MEM',
 WATTAGE='1/16W',
 TOLERANCE='5%',
 MATERIAL='CHIP',
 PHYS_PAGE='28',
 XY='(-6500,12675)',
 ROT='0',
 VER='1',
 PACK_TYPE='0402LF',
 LOCATION='R248',
 CDS_LIB='pure_quanta',
 CDS_PART_NAME='Q_RES_0402LF-33,5%,1/16W,CHIP,CS03302JB10',
 PART_NUMBER='CS03302JB10',
 VALUE='33',
 PRIM_FILE='./archive_libs/logical/q_res/chips/chips.prt';

PART_NAME
 R249 'Q_RES_0402LF-33,5%,1/16W,CHIP,CS03302JB10':;

SECTION_NUMBER 1
 '@T6G_MB_LIB.T6G(SCH_1):PAGE28_I135@PURE_QUANTA.Q_RES(CHIPS)':
 C_PATH='@t6g_mb_lib.t6g(sch_1):page28_i135@pure_quanta.q_res(chips)',
 P_PATH='@t6g_mb_lib.t6g(sch_1):page28_i135@pure_quanta.q_res(chips)',
 PATH='I135',
 DRAWING='@T6G_MB_LIB.T6G(SCH_1):PAGE28',
 BOM_COST='MEM',
 WATTAGE='1/16W',
 TOLERANCE='5%',
 MATERIAL='CHIP',
 PHYS_PAGE='28',
 XY='(-6500,12625)',
 ROT='0',
 VER='1',
 PACK_TYPE='0402LF',
 LOCATION='R249',
 CDS_LIB='pure_quanta',
 CDS_PART_NAME='Q_RES_0402LF-33,5%,1/16W,CHIP,CS03302JB10',
 PART_NUMBER='CS03302JB10',
 VALUE='33',
 PRIM_FILE='./archive_libs/logical/q_res/chips/chips.prt';

PART_NAME
 R250 'Q_RES_0402LF-0,5%,1/16W,CHIP,CS00002JB13':;

SECTION_NUMBER 1
 '@T6G_MB_LIB.T6G(SCH_1):PAGE80_I180@PURE_QUANTA.Q_RES(CHIPS)':
 C_PATH='@t6g_mb_lib.t6g(sch_1):page80_i180@pure_quanta.q_res(chips)',
 P_PATH='@t6g_mb_lib.t6g(sch_1):page81_i180@pure_quanta.q_res(chips)',
 PATH='I180',
 DRAWING='@T6G_MB_LIB.T6G(SCH_1):PAGE80',
 BOM_COST='MEM',
 WATTAGE='1/16W',
 TOLERANCE='5%',
 MATERIAL='CHIP',
 PHYS_PAGE='81',
 XY='(-3225,6125)',
 ROT='0',
 VER='1',
 PACK_TYPE='0402LF',
 LOCATION='R250',
 CDS_LIB='pure_quanta',
 CDS_PART_NAME='Q_RES_0402LF-0,5%,1/16W,CHIP,CS00002JB13',
 PART_NUMBER='CS00002JB13',
 VALUE='0',
 PRIM_FILE='./archive_libs/logical/q_res/chips/chips.prt';

PART_NAME
 R251 'Q_RES_0402LF-0,5%,1/16W,CHIP,CS00002JB13':;

SECTION_NUMBER 1
 '@T6G_MB_LIB.T6G(SCH_1):PAGE80_I162@PURE_QUANTA.Q_RES(CHIPS)':
 C_PATH='@t6g_mb_lib.t6g(sch_1):page80_i162@pure_quanta.q_res(chips)',
 P_PATH='@t6g_mb_lib.t6g(sch_1):page81_i162@pure_quanta.q_res(chips)',
 PATH='I162',
 DRAWING='@T6G_MB_LIB.T6G(SCH_1):PAGE80',
 BOM_COST='MEM',
 WATTAGE='1/16W',
 TOLERANCE='5%',
 MATERIAL='CHIP',
 PHYS_PAGE='81',
 XY='(-3225,4725)',
 ROT='0',
 VER='1',
 PACK_TYPE='0402LF',
 LOCATION='R251',
 CDS_LIB='pure_quanta',
 CDS_PART_NAME='Q_RES_0402LF-0,5%,1/16W,CHIP,CS00002JB13',
 PART_NUMBER='CS00002JB13',
 VALUE='0',
 PRIM_FILE='./archive_libs/logical/q_res/chips/chips.prt';

PART_NAME
 R252 'Q_RES_0402LF-0,5%,1/16W,CHIP,CS00002JB13':;

SECTION_NUMBER 1
 '@T6G_MB_LIB.T6G(SCH_1):PAGE80_I128@PURE_QUANTA.Q_RES(CHIPS)':
 C_PATH='@t6g_mb_lib.t6g(sch_1):page80_i128@pure_quanta.q_res(chips)',
 P_PATH='@t6g_mb_lib.t6g(sch_1):page81_i128@pure_quanta.q_res(chips)',
 PATH='I128',
 DRAWING='@T6G_MB_LIB.T6G(SCH_1):PAGE80',
 BOM_COST='MEM',
 WATTAGE='1/16W',
 TOLERANCE='5%',
 MATERIAL='CHIP',
 PHYS_PAGE='81',
 XY='(-3225,4075)',
 ROT='0',
 VER='1',
 PACK_TYPE='0402LF',
 LOCATION='R252',
 CDS_LIB='pure_quanta',
 CDS_PART_NAME='Q_RES_0402LF-0,5%,1/16W,CHIP,CS00002JB13',
 PART_NUMBER='CS00002JB13',
 VALUE='0',
 PRIM_FILE='./archive_libs/logical/q_res/chips/chips.prt';

PART_NAME
 R253 'Q_RES_0402LF-0,5%,1/16W,CHIP,CS00002JB13':;

SECTION_NUMBER 1
 '@T6G_MB_LIB.T6G(SCH_1):PAGE80_I116@PURE_QUANTA.Q_RES(CHIPS)':
 C_PATH='@t6g_mb_lib.t6g(sch_1):page80_i116@pure_quanta.q_res(chips)',
 P_PATH='@t6g_mb_lib.t6g(sch_1):page81_i116@pure_quanta.q_res(chips)',
 PATH='I116',
 DRAWING='@T6G_MB_LIB.T6G(SCH_1):PAGE80',
 BOM_COST='MEM',
 WATTAGE='1/16W',
 TOLERANCE='5%',
 MATERIAL='CHIP',
 PHYS_PAGE='81',
 XY='(-6425,5325)',
 ROT='0',
 VER='1',
 PACK_TYPE='0402LF',
 LOCATION='R253',
 CDS_LIB='pure_quanta',
 CDS_PART_NAME='Q_RES_0402LF-0,5%,1/16W,CHIP,CS00002JB13',
 PART_NUMBER='CS00002JB13',
 VALUE='0',
 PRIM_FILE='./archive_libs/logical/q_res/chips/chips.prt';

PART_NAME
 R254 'Q_RES_0402LF-0,5%,1/16W,CHIP,CS00002JB13':;

SECTION_NUMBER 1
 '@T6G_MB_LIB.T6G(SCH_1):PAGE80_I123@PURE_QUANTA.Q_RES(CHIPS)':
 C_PATH='@t6g_mb_lib.t6g(sch_1):page80_i123@pure_quanta.q_res(chips)',
 P_PATH='@t6g_mb_lib.t6g(sch_1):page81_i123@pure_quanta.q_res(chips)',
 PATH='I123',
 DRAWING='@T6G_MB_LIB.T6G(SCH_1):PAGE80',
 BOM_COST='MEM',
 WATTAGE='1/16W',
 TOLERANCE='5%',
 MATERIAL='CHIP',
 PHYS_PAGE='81',
 XY='(-6425,6075)',
 ROT='0',
 VER='1',
 PACK_TYPE='0402LF',
 LOCATION='R254',
 CDS_LIB='pure_quanta',
 CDS_PART_NAME='Q_RES_0402LF-0,5%,1/16W,CHIP,CS00002JB13',
 PART_NUMBER='CS00002JB13',
 VALUE='0',
 PRIM_FILE='./archive_libs/logical/q_res/chips/chips.prt';

PART_NAME
 R255 'Q_RES_0402LF-0,5%,1/16W,CHIP,CS00002JB13':;

SECTION_NUMBER 1
 '@T6G_MB_LIB.T6G(SCH_1):PAGE80_I121@PURE_QUANTA.Q_RES(CHIPS)':
 C_PATH='@t6g_mb_lib.t6g(sch_1):page80_i121@pure_quanta.q_res(chips)',
 P_PATH='@t6g_mb_lib.t6g(sch_1):page81_i121@pure_quanta.q_res(chips)',
 PATH='I121',
 DRAWING='@T6G_MB_LIB.T6G(SCH_1):PAGE80',
 BOM_COST='MEM',
 WATTAGE='1/16W',
 TOLERANCE='5%',
 MATERIAL='CHIP',
 PHYS_PAGE='81',
 XY='(-6425,5825)',
 ROT='0',
 VER='1',
 PACK_TYPE='0402LF',
 LOCATION='R255',
 CDS_LIB='pure_quanta',
 CDS_PART_NAME='Q_RES_0402LF-0,5%,1/16W,CHIP,CS00002JB13',
 PART_NUMBER='CS00002JB13',
 VALUE='0',
 PRIM_FILE='./archive_libs/logical/q_res/chips/chips.prt';

PART_NAME
 R256 'Q_RES_0402LF-0,5%,1/16W,EMPTY,CS00002JB13':;

SECTION_NUMBER 1
 '@T6G_MB_LIB.T6G(SCH_1):PAGE137_I92@PURE_QUANTA.Q_RES(CHIPS)':
 C_PATH='@t6g_mb_lib.t6g(sch_1):page137_i92@pure_quanta.q_res(chips)',
 P_PATH='@t6g_mb_lib.t6g(sch_1):page160_i92@pure_quanta.q_res(chips)',
 PATH='I92',
 DRAWING='@T6G_MB_LIB.T6G(SCH_1):PAGE137',
 WATTAGE='1/16W',
 TOLERANCE='5%',
 MATERIAL='EMPTY',
 PHYS_PAGE='160',
 XY='(-2750,2350)',
 ROT='0',
 VER='1',
 PACK_TYPE='0402LF',
 LOCATION='R256',
 CDS_LIB='pure_quanta',
 CDS_PART_NAME='Q_RES_0402LF-0,5%,1/16W,EMPTY,CS00002JB13',
 PART_NUMBER='CS00002JB13',
 VALUE='0',
 PRIM_FILE='./archive_libs/logical/q_res/chips/chips.prt';

PART_NAME
 R257 'Q_RES_0402LF-0,5%,1/16W,EMPTY,CS00002JB13':;

SECTION_NUMBER 1
 '@T6G_MB_LIB.T6G(SCH_1):PAGE137_I91@PURE_QUANTA.Q_RES(CHIPS)':
 C_PATH='@t6g_mb_lib.t6g(sch_1):page137_i91@pure_quanta.q_res(chips)',
 P_PATH='@t6g_mb_lib.t6g(sch_1):page160_i91@pure_quanta.q_res(chips)',
 PATH='I91',
 DRAWING='@T6G_MB_LIB.T6G(SCH_1):PAGE137',
 WATTAGE='1/16W',
 TOLERANCE='5%',
 MATERIAL='EMPTY',
 PHYS_PAGE='160',
 XY='(-2725,2250)',
 ROT='0',
 VER='1',
 PACK_TYPE='0402LF',
 LOCATION='R257',
 CDS_LIB='pure_quanta',
 CDS_PART_NAME='Q_RES_0402LF-0,5%,1/16W,EMPTY,CS00002JB13',
 PART_NUMBER='CS00002JB13',
 VALUE='0',
 PRIM_FILE='./archive_libs/logical/q_res/chips/chips.prt';

PART_NAME
 R258 'Q_RES_0402LF-0,5%,1/16W,CHIP,CS00002JB13':;

SECTION_NUMBER 1
 '@T6G_MB_LIB.T6G(SCH_1):PAGE80_I177@PURE_QUANTA.Q_RES(CHIPS)':
 C_PATH='@t6g_mb_lib.t6g(sch_1):page80_i177@pure_quanta.q_res(chips)',
 P_PATH='@t6g_mb_lib.t6g(sch_1):page81_i177@pure_quanta.q_res(chips)',
 PATH='I177',
 DRAWING='@T6G_MB_LIB.T6G(SCH_1):PAGE80',
 BOM_COST='MEM',
 WATTAGE='1/16W',
 TOLERANCE='5%',
 MATERIAL='CHIP',
 PHYS_PAGE='81',
 XY='(-3225,5725)',
 ROT='0',
 VER='1',
 PACK_TYPE='0402LF',
 LOCATION='R258',
 CDS_LIB='pure_quanta',
 CDS_PART_NAME='Q_RES_0402LF-0,5%,1/16W,CHIP,CS00002JB13',
 PART_NUMBER='CS00002JB13',
 VALUE='0',
 PRIM_FILE='./archive_libs/logical/q_res/chips/chips.prt';

PART_NAME
 R259 'Q_RES_0402LF-33,5%,1/16W,CHIP,CS03302JB10':;

SECTION_NUMBER 1
 '@T6G_MB_LIB.T6G(SCH_1):PAGE201_I48@PURE_QUANTA.Q_RES(CHIPS)':
 C_PATH='@t6g_mb_lib.t6g(sch_1):page201_i48@pure_quanta.q_res(chips)',
 P_PATH='@t6g_mb_lib.t6g(sch_1):page226_i48@pure_quanta.q_res(chips)',
 PATH='I48',
 DRAWING='@T6G_MB_LIB.T6G(SCH_1):PAGE201',
 BOM_COST='MEM',
 WATTAGE='1/16W',
 TOLERANCE='5%',
 MATERIAL='CHIP',
 PHYS_PAGE='226',
 XY='(-3575,4500)',
 ROT='0',
 VER='1',
 PACK_TYPE='0402LF',
 LOCATION='R259',
 CDS_LIB='pure_quanta',
 CDS_PART_NAME='Q_RES_0402LF-33,5%,1/16W,CHIP,CS03302JB10',
 PART_NUMBER='CS03302JB10',
 VALUE='33',
 PRIM_FILE='./archive_libs/logical/q_res/chips/chips.prt';

PART_NAME
 R260 'Q_RES_0402LF-0,5%,1/16W,CHIP,CS00002JB13':;

SECTION_NUMBER 1
 '@T6G_MB_LIB.T6G(SCH_1):PAGE81_I49@PURE_QUANTA.Q_RES(CHIPS)':
 C_PATH='@t6g_mb_lib.t6g(sch_1):page81_i49@pure_quanta.q_res(chips)',
 P_PATH='@t6g_mb_lib.t6g(sch_1):page82_i49@pure_quanta.q_res(chips)',
 PATH='I49',
 DRAWING='@T6G_MB_LIB.T6G(SCH_1):PAGE81',
 BOM_COST='MEM',
 WATTAGE='1/16W',
 TOLERANCE='5%',
 MATERIAL='CHIP',
 PHYS_PAGE='82',
 XY='(-6450,4525)',
 ROT='0',
 VER='1',
 PACK_TYPE='0402LF',
 LOCATION='R260',
 CDS_LIB='pure_quanta',
 CDS_PART_NAME='Q_RES_0402LF-0,5%,1/16W,CHIP,CS00002JB13',
 PART_NUMBER='CS00002JB13',
 VALUE='0',
 PRIM_FILE='./archive_libs/logical/q_res/chips/chips.prt';

PART_NAME
 R261 'Q_RES_0402LF-0,5%,1/16W,CHIP,CS00002JB13':;

SECTION_NUMBER 1
 '@T6G_MB_LIB.T6G(SCH_1):PAGE81_I50@PURE_QUANTA.Q_RES(CHIPS)':
 C_PATH='@t6g_mb_lib.t6g(sch_1):page81_i50@pure_quanta.q_res(chips)',
 P_PATH='@t6g_mb_lib.t6g(sch_1):page82_i50@pure_quanta.q_res(chips)',
 PATH='I50',
 DRAWING='@T6G_MB_LIB.T6G(SCH_1):PAGE81',
 BOM_COST='MEM',
 WATTAGE='1/16W',
 TOLERANCE='5%',
 MATERIAL='CHIP',
 PHYS_PAGE='82',
 XY='(-6450,4575)',
 ROT='0',
 VER='1',
 PACK_TYPE='0402LF',
 LOCATION='R261',
 CDS_LIB='pure_quanta',
 CDS_PART_NAME='Q_RES_0402LF-0,5%,1/16W,CHIP,CS00002JB13',
 PART_NUMBER='CS00002JB13',
 VALUE='0',
 PRIM_FILE='./archive_libs/logical/q_res/chips/chips.prt';

PART_NAME
 R262 'Q_RES_0402LF-0,5%,1/16W,CHIP,CS00002JB13':;

SECTION_NUMBER 1
 '@T6G_MB_LIB.T6G(SCH_1):PAGE81_I44@PURE_QUANTA.Q_RES(CHIPS)':
 C_PATH='@t6g_mb_lib.t6g(sch_1):page81_i44@pure_quanta.q_res(chips)',
 P_PATH='@t6g_mb_lib.t6g(sch_1):page82_i44@pure_quanta.q_res(chips)',
 PATH='I44',
 DRAWING='@T6G_MB_LIB.T6G(SCH_1):PAGE81',
 BOM_COST='MEM',
 WATTAGE='1/16W',
 TOLERANCE='5%',
 MATERIAL='CHIP',
 PHYS_PAGE='82',
 XY='(-6450,4125)',
 ROT='0',
 VER='1',
 PACK_TYPE='0402LF',
 LOCATION='R262',
 CDS_LIB='pure_quanta',
 CDS_PART_NAME='Q_RES_0402LF-0,5%,1/16W,CHIP,CS00002JB13',
 PART_NUMBER='CS00002JB13',
 VALUE='0',
 PRIM_FILE='./archive_libs/logical/q_res/chips/chips.prt';

PART_NAME
 R263 'Q_RES_0402LF-0,5%,1/16W,CHIP,CS00002JB13':;

SECTION_NUMBER 1
 '@T6G_MB_LIB.T6G(SCH_1):PAGE81_I47@PURE_QUANTA.Q_RES(CHIPS)':
 C_PATH='@t6g_mb_lib.t6g(sch_1):page81_i47@pure_quanta.q_res(chips)',
 P_PATH='@t6g_mb_lib.t6g(sch_1):page82_i47@pure_quanta.q_res(chips)',
 PATH='I47',
 DRAWING='@T6G_MB_LIB.T6G(SCH_1):PAGE81',
 BOM_COST='MEM',
 WATTAGE='1/16W',
 TOLERANCE='5%',
 MATERIAL='CHIP',
 PHYS_PAGE='82',
 XY='(-6450,4375)',
 ROT='0',
 VER='1',
 PACK_TYPE='0402LF',
 LOCATION='R263',
 CDS_LIB='pure_quanta',
 CDS_PART_NAME='Q_RES_0402LF-0,5%,1/16W,CHIP,CS00002JB13',
 PART_NUMBER='CS00002JB13',
 VALUE='0',
 PRIM_FILE='./archive_libs/logical/q_res/chips/chips.prt';

PART_NAME
 R264 'Q_RES_0402LF-0,5%,1/16W,CHIP,CS00002JB13':;

SECTION_NUMBER 1
 '@T6G_MB_LIB.T6G(SCH_1):PAGE81_I53@PURE_QUANTA.Q_RES(CHIPS)':
 C_PATH='@t6g_mb_lib.t6g(sch_1):page81_i53@pure_quanta.q_res(chips)',
 P_PATH='@t6g_mb_lib.t6g(sch_1):page82_i53@pure_quanta.q_res(chips)',
 PATH='I53',
 DRAWING='@T6G_MB_LIB.T6G(SCH_1):PAGE81',
 BOM_COST='MEM',
 WATTAGE='1/16W',
 TOLERANCE='5%',
 MATERIAL='CHIP',
 PHYS_PAGE='82',
 XY='(-6450,4725)',
 ROT='0',
 VER='1',
 PACK_TYPE='0402LF',
 LOCATION='R264',
 CDS_LIB='pure_quanta',
 CDS_PART_NAME='Q_RES_0402LF-0,5%,1/16W,CHIP,CS00002JB13',
 PART_NUMBER='CS00002JB13',
 VALUE='0',
 PRIM_FILE='./archive_libs/logical/q_res/chips/chips.prt';

PART_NAME
 R265 'Q_RES_0402LF-33,5%,1/16W,CHIP,CS03302JB10':;

SECTION_NUMBER 1
 '@T6G_MB_LIB.T6G(SCH_1):PAGE80_I126@PURE_QUANTA.Q_RES(CHIPS)':
 C_PATH='@t6g_mb_lib.t6g(sch_1):page80_i126@pure_quanta.q_res(chips)',
 P_PATH='@t6g_mb_lib.t6g(sch_1):page81_i126@pure_quanta.q_res(chips)',
 PATH='I126',
 DRAWING='@T6G_MB_LIB.T6G(SCH_1):PAGE80',
 BOM_COST='MEM',
 WATTAGE='1/16W',
 TOLERANCE='5%',
 MATERIAL='CHIP',
 PHYS_PAGE='81',
 XY='(-3225,3825)',
 ROT='0',
 VER='1',
 PACK_TYPE='0402LF',
 LOCATION='R265',
 CDS_LIB='pure_quanta',
 CDS_PART_NAME='Q_RES_0402LF-33,5%,1/16W,CHIP,CS03302JB10',
 PART_NUMBER='CS03302JB10',
 VALUE='33',
 PRIM_FILE='./archive_libs/logical/q_res/chips/chips.prt';

PART_NAME
 R266 'Q_RES_0402LF-33,5%,1/16W,CHIP,CS03302JB10':;

SECTION_NUMBER 1
 '@T6G_MB_LIB.T6G(SCH_1):PAGE81_I108@PURE_QUANTA.Q_RES(CHIPS)':
 C_PATH='@t6g_mb_lib.t6g(sch_1):page81_i108@pure_quanta.q_res(chips)',
 P_PATH='@t6g_mb_lib.t6g(sch_1):page82_i108@pure_quanta.q_res(chips)',
 PATH='I108',
 DRAWING='@T6G_MB_LIB.T6G(SCH_1):PAGE81',
 BOM_COST='MEM',
 WATTAGE='1/16W',
 TOLERANCE='5%',
 MATERIAL='CHIP',
 PHYS_PAGE='82',
 XY='(-3250,5825)',
 ROT='0',
 VER='1',
 PACK_TYPE='0402LF',
 LOCATION='R266',
 CDS_LIB='pure_quanta',
 CDS_PART_NAME='Q_RES_0402LF-33,5%,1/16W,CHIP,CS03302JB10',
 PART_NUMBER='CS03302JB10',
 VALUE='33',
 PRIM_FILE='./archive_libs/logical/q_res/chips/chips.prt';

PART_NAME
 R267 'Q_RES_0402LF-33,5%,1/16W,CHIP,CS03302JB10':;

SECTION_NUMBER 1
 '@T6G_MB_LIB.T6G(SCH_1):PAGE81_I73@PURE_QUANTA.Q_RES(CHIPS)':
 C_PATH='@t6g_mb_lib.t6g(sch_1):page81_i73@pure_quanta.q_res(chips)',
 P_PATH='@t6g_mb_lib.t6g(sch_1):page82_i73@pure_quanta.q_res(chips)',
 PATH='I73',
 DRAWING='@T6G_MB_LIB.T6G(SCH_1):PAGE81',
 BOM_COST='MEM',
 WATTAGE='1/16W',
 TOLERANCE='5%',
 MATERIAL='CHIP',
 PHYS_PAGE='82',
 XY='(-6450,5975)',
 ROT='0',
 VER='1',
 PACK_TYPE='0402LF',
 LOCATION='R267',
 CDS_LIB='pure_quanta',
 CDS_PART_NAME='Q_RES_0402LF-33,5%,1/16W,CHIP,CS03302JB10',
 PART_NUMBER='CS03302JB10',
 VALUE='33',
 PRIM_FILE='./archive_libs/logical/q_res/chips/chips.prt';

PART_NAME
 R268 'Q_RES_0402LF-0,5%,1/16W,CHIP,CS00002JB13':;

SECTION_NUMBER 1
 '@T6G_MB_LIB.T6G(SCH_1):PAGE81_I55@PURE_QUANTA.Q_RES(CHIPS)':
 C_PATH='@t6g_mb_lib.t6g(sch_1):page81_i55@pure_quanta.q_res(chips)',
 P_PATH='@t6g_mb_lib.t6g(sch_1):page82_i55@pure_quanta.q_res(chips)',
 PATH='I55',
 DRAWING='@T6G_MB_LIB.T6G(SCH_1):PAGE81',
 BOM_COST='MEM',
 WATTAGE='1/16W',
 TOLERANCE='5%',
 MATERIAL='CHIP',
 PHYS_PAGE='82',
 XY='(-6450,4925)',
 ROT='0',
 VER='1',
 PACK_TYPE='0402LF',
 LOCATION='R268',
 CDS_LIB='pure_quanta',
 CDS_PART_NAME='Q_RES_0402LF-0,5%,1/16W,CHIP,CS00002JB13',
 PART_NUMBER='CS00002JB13',
 VALUE='0',
 PRIM_FILE='./archive_libs/logical/q_res/chips/chips.prt';

PART_NAME
 R269 'Q_RES_0402LF-0,5%,1/16W,CHIP,CS00002JB13':;

SECTION_NUMBER 1
 '@T6G_MB_LIB.T6G(SCH_1):PAGE81_I56@PURE_QUANTA.Q_RES(CHIPS)':
 C_PATH='@t6g_mb_lib.t6g(sch_1):page81_i56@pure_quanta.q_res(chips)',
 P_PATH='@t6g_mb_lib.t6g(sch_1):page82_i56@pure_quanta.q_res(chips)',
 PATH='I56',
 DRAWING='@T6G_MB_LIB.T6G(SCH_1):PAGE81',
 BOM_COST='MEM',
 WATTAGE='1/16W',
 TOLERANCE='5%',
 MATERIAL='CHIP',
 PHYS_PAGE='82',
 XY='(-6450,4975)',
 ROT='0',
 VER='1',
 PACK_TYPE='0402LF',
 LOCATION='R269',
 CDS_LIB='pure_quanta',
 CDS_PART_NAME='Q_RES_0402LF-0,5%,1/16W,CHIP,CS00002JB13',
 PART_NUMBER='CS00002JB13',
 VALUE='0',
 PRIM_FILE='./archive_libs/logical/q_res/chips/chips.prt';

PART_NAME
 R270 'Q_RES_0402LF-33,5%,1/16W,CHIP,CS03302JB10':;

SECTION_NUMBER 1
 '@T6G_MB_LIB.T6G(SCH_1):PAGE81_I112@PURE_QUANTA.Q_RES(CHIPS)':
 C_PATH='@t6g_mb_lib.t6g(sch_1):page81_i112@pure_quanta.q_res(chips)',
 P_PATH='@t6g_mb_lib.t6g(sch_1):page82_i112@pure_quanta.q_res(chips)',
 PATH='I112',
 DRAWING='@T6G_MB_LIB.T6G(SCH_1):PAGE81',
 BOM_COST='MEM',
 WATTAGE='1/16W',
 TOLERANCE='5%',
 MATERIAL='CHIP',
 PHYS_PAGE='82',
 XY='(-3250,6075)',
 ROT='0',
 VER='1',
 PACK_TYPE='0402LF',
 LOCATION='R270',
 CDS_LIB='pure_quanta',
 CDS_PART_NAME='Q_RES_0402LF-33,5%,1/16W,CHIP,CS03302JB10',
 PART_NUMBER='CS03302JB10',
 VALUE='33',
 PRIM_FILE='./archive_libs/logical/q_res/chips/chips.prt';

PART_NAME
 R271 'Q_RES_0402LF-0,5%,1/16W,CHIP,CS00002JB13':;

SECTION_NUMBER 1
 '@T6G_MB_LIB.T6G(SCH_1):PAGE81_I104@PURE_QUANTA.Q_RES(CHIPS)':
 C_PATH='@t6g_mb_lib.t6g(sch_1):page81_i104@pure_quanta.q_res(chips)',
 P_PATH='@t6g_mb_lib.t6g(sch_1):page82_i104@pure_quanta.q_res(chips)',
 PATH='I104',
 DRAWING='@T6G_MB_LIB.T6G(SCH_1):PAGE81',
 BOM_COST='MEM',
 WATTAGE='1/16W',
 TOLERANCE='5%',
 MATERIAL='CHIP',
 PHYS_PAGE='82',
 XY='(-3200,5025)',
 ROT='0',
 VER='1',
 PACK_TYPE='0402LF',
 LOCATION='R271',
 CDS_LIB='pure_quanta',
 CDS_PART_NAME='Q_RES_0402LF-0,5%,1/16W,CHIP,CS00002JB13',
 PART_NUMBER='CS00002JB13',
 VALUE='0',
 PRIM_FILE='./archive_libs/logical/q_res/chips/chips.prt';

PART_NAME
 R272 'Q_RES_0402LF-0,5%,1/16W,EMPTY,CS00002JB13':;

SECTION_NUMBER 1
 '@T6G_MB_LIB.T6G(SCH_1):PAGE80_I115@PURE_QUANTA.Q_RES(CHIPS)':
 C_PATH='@t6g_mb_lib.t6g(sch_1):page80_i115@pure_quanta.q_res(chips)',
 P_PATH='@t6g_mb_lib.t6g(sch_1):page81_i115@pure_quanta.q_res(chips)',
 PATH='I115',
 DRAWING='@T6G_MB_LIB.T6G(SCH_1):PAGE80',
 BOM_COST='MEM',
 WATTAGE='1/16W',
 TOLERANCE='5%',
 MATERIAL='EMPTY',
 PHYS_PAGE='81',
 XY='(-6425,5375)',
 ROT='0',
 VER='1',
 PACK_TYPE='0402LF',
 LOCATION='R272',
 CDS_LIB='pure_quanta',
 CDS_PART_NAME='Q_RES_0402LF-0,5%,1/16W,EMPTY,CS00002JB13',
 PART_NUMBER='CS00002JB13',
 VALUE='0',
 PRIM_FILE='./archive_libs/logical/q_res/chips/chips.prt';

PART_NAME
 R273 'Q_RES_0402LF-33,5%,1/16W,CHIP,CS03302JB10':;

SECTION_NUMBER 1
 '@T6G_MB_LIB.T6G(SCH_1):PAGE80_I119@PURE_QUANTA.Q_RES(CHIPS)':
 C_PATH='@t6g_mb_lib.t6g(sch_1):page80_i119@pure_quanta.q_res(chips)',
 P_PATH='@t6g_mb_lib.t6g(sch_1):page81_i119@pure_quanta.q_res(chips)',
 PATH='I119',
 DRAWING='@T6G_MB_LIB.T6G(SCH_1):PAGE80',
 BOM_COST='MEM',
 WATTAGE='1/16W',
 TOLERANCE='5%',
 MATERIAL='CHIP',
 PHYS_PAGE='81',
 XY='(-6425,5575)',
 ROT='0',
 VER='1',
 PACK_TYPE='0402LF',
 LOCATION='R273',
 CDS_LIB='pure_quanta',
 CDS_PART_NAME='Q_RES_0402LF-33,5%,1/16W,CHIP,CS03302JB10',
 PART_NUMBER='CS03302JB10',
 VALUE='33',
 PRIM_FILE='./archive_libs/logical/q_res/chips/chips.prt';

PART_NAME
 R274 'Q_RES_0402LF-0,5%,1/16W,CHIP,CS00002JB13':;

SECTION_NUMBER 1
 '@T6G_MB_LIB.T6G(SCH_1):PAGE137_I71@PURE_QUANTA.Q_RES(CHIPS)':
 C_PATH='@t6g_mb_lib.t6g(sch_1):page137_i71@pure_quanta.q_res(chips)',
 P_PATH='@t6g_mb_lib.t6g(sch_1):page160_i71@pure_quanta.q_res(chips)',
 PATH='I71',
 DRAWING='@T6G_MB_LIB.T6G(SCH_1):PAGE137',
 WATTAGE='1/16W',
 TOLERANCE='5%',
 MATERIAL='CHIP',
 PHYS_PAGE='160',
 XY='(-2350,800)',
 ROT='0',
 VER='1',
 PACK_TYPE='0402LF',
 LOCATION='R274',
 CDS_LIB='pure_quanta',
 CDS_PART_NAME='Q_RES_0402LF-0,5%,1/16W,CHIP,CS00002JB13',
 PART_NUMBER='CS00002JB13',
 VALUE='0',
 PRIM_FILE='./archive_libs/logical/q_res/chips/chips.prt';

PART_NAME
 R275 'Q_RES_0402LF-33,5%,1/16W,CHIP,CS03302JB10':;

SECTION_NUMBER 1
 '@T6G_MB_LIB.T6G(SCH_1):PAGE81_I84@PURE_QUANTA.Q_RES(CHIPS)':
 C_PATH='@t6g_mb_lib.t6g(sch_1):page81_i84@pure_quanta.q_res(chips)',
 P_PATH='@t6g_mb_lib.t6g(sch_1):page82_i84@pure_quanta.q_res(chips)',
 PATH='I84',
 DRAWING='@T6G_MB_LIB.T6G(SCH_1):PAGE81',
 BOM_COST='MEM',
 WATTAGE='1/16W',
 TOLERANCE='5%',
 MATERIAL='CHIP',
 PHYS_PAGE='82',
 XY='(-3250,3725)',
 ROT='2',
 VER='1',
 PACK_TYPE='0402LF',
 LOCATION='R275',
 CDS_LIB='pure_quanta',
 CDS_PART_NAME='Q_RES_0402LF-33,5%,1/16W,CHIP,CS03302JB10',
 PART_NUMBER='CS03302JB10',
 VALUE='33',
 PRIM_FILE='./archive_libs/logical/q_res/chips/chips.prt';

PART_NAME
 R276 'Q_RES_0402LF-4.7K,5%,1/16W,CHIP,CS24702JB10':;

SECTION_NUMBER 1
 '@T6G_MB_LIB.T6G(SCH_1):PAGE28_I41@PURE_QUANTA.Q_RES(CHIPS)':
 C_PATH='@t6g_mb_lib.t6g(sch_1):page28_i41@pure_quanta.q_res(chips)',
 P_PATH='@t6g_mb_lib.t6g(sch_1):page28_i41@pure_quanta.q_res(chips)',
 PATH='I41',
 DRAWING='@T6G_MB_LIB.T6G(SCH_1):PAGE28',
 WATTAGE='1/16W',
 TOLERANCE='5%',
 MATERIAL='CHIP',
 PHYS_PAGE='28',
 XY='(-7625,7750)',
 ROT='1',
 VER='1',
 PACK_TYPE='0402LF',
 LOCATION='R276',
 CDS_LIB='pure_quanta',
 CDS_PART_NAME='Q_RES_0402LF-4.7K,5%,1/16W,CHIP,CS24702JB10',
 PART_NUMBER='CS24702JB10',
 VALUE='4.7K',
 PRIM_FILE='./archive_libs/logical/q_res/chips/chips.prt';

PART_NAME
 R277 'Q_RES_0402LF-33,5%,1/16W,CHIP,CS03302JB10':;

SECTION_NUMBER 1
 '@T6G_MB_LIB.T6G(SCH_1):PAGE80_I165@PURE_QUANTA.Q_RES(CHIPS)':
 C_PATH='@t6g_mb_lib.t6g(sch_1):page80_i165@pure_quanta.q_res(chips)',
 P_PATH='@t6g_mb_lib.t6g(sch_1):page81_i165@pure_quanta.q_res(chips)',
 PATH='I165',
 DRAWING='@T6G_MB_LIB.T6G(SCH_1):PAGE80',
 BOM_COST='MEM',
 WATTAGE='1/16W',
 TOLERANCE='5%',
 MATERIAL='CHIP',
 PHYS_PAGE='81',
 XY='(-3225,4925)',
 ROT='0',
 VER='1',
 PACK_TYPE='0402LF',
 LOCATION='R277',
 CDS_LIB='pure_quanta',
 CDS_PART_NAME='Q_RES_0402LF-33,5%,1/16W,CHIP,CS03302JB10',
 PART_NUMBER='CS03302JB10',
 VALUE='33',
 PRIM_FILE='./archive_libs/logical/q_res/chips/chips.prt';

PART_NAME
 R278 'Q_RES_0402LF-0,5%,1/16W,CHIP,CS00002JB13':;

SECTION_NUMBER 1
 '@T6G_MB_LIB.T6G(SCH_1):PAGE81_I113@PURE_QUANTA.Q_RES(CHIPS)':
 C_PATH='@t6g_mb_lib.t6g(sch_1):page81_i113@pure_quanta.q_res(chips)',
 P_PATH='@t6g_mb_lib.t6g(sch_1):page82_i113@pure_quanta.q_res(chips)',
 PATH='I113',
 DRAWING='@T6G_MB_LIB.T6G(SCH_1):PAGE81',
 BOM_COST='MEM',
 WATTAGE='1/16W',
 TOLERANCE='5%',
 MATERIAL='CHIP',
 PHYS_PAGE='82',
 XY='(-3250,6025)',
 ROT='0',
 VER='1',
 PACK_TYPE='0402LF',
 LOCATION='R278',
 CDS_LIB='pure_quanta',
 CDS_PART_NAME='Q_RES_0402LF-0,5%,1/16W,CHIP,CS00002JB13',
 PART_NUMBER='CS00002JB13',
 VALUE='0',
 PRIM_FILE='./archive_libs/logical/q_res/chips/chips.prt';

PART_NAME
 R279 'Q_RES_0402LF-33,5%,1/16W,CHIP,CS03302JB10':;

SECTION_NUMBER 1
 '@T6G_MB_LIB.T6G(SCH_1):PAGE80_I58@PURE_QUANTA.Q_RES(CHIPS)':
 C_PATH='@t6g_mb_lib.t6g(sch_1):page80_i58@pure_quanta.q_res(chips)',
 P_PATH='@t6g_mb_lib.t6g(sch_1):page81_i58@pure_quanta.q_res(chips)',
 PATH='I58',
 DRAWING='@T6G_MB_LIB.T6G(SCH_1):PAGE80',
 BOM_COST='MEM',
 WATTAGE='1/16W',
 TOLERANCE='5%',
 MATERIAL='CHIP',
 PHYS_PAGE='81',
 XY='(-6725,2175)',
 ROT='0',
 VER='1',
 PACK_TYPE='0402LF',
 LOCATION='R279',
 CDS_LIB='pure_quanta',
 CDS_PART_NAME='Q_RES_0402LF-33,5%,1/16W,CHIP,CS03302JB10',
 PART_NUMBER='CS03302JB10',
 VALUE='33',
 PRIM_FILE='./archive_libs/logical/q_res/chips/chips.prt';

PART_NAME
 R280 'Q_RES_0402LF-0,5%,1/16W,CHIP,CS00002JB13':;

SECTION_NUMBER 1
 '@T6G_MB_LIB.T6G(SCH_1):PAGE80_I59@PURE_QUANTA.Q_RES(CHIPS)':
 C_PATH='@t6g_mb_lib.t6g(sch_1):page80_i59@pure_quanta.q_res(chips)',
 P_PATH='@t6g_mb_lib.t6g(sch_1):page81_i59@pure_quanta.q_res(chips)',
 PATH='I59',
 DRAWING='@T6G_MB_LIB.T6G(SCH_1):PAGE80',
 BOM_COST='MEM',
 WATTAGE='1/16W',
 TOLERANCE='5%',
 MATERIAL='CHIP',
 PHYS_PAGE='81',
 XY='(-6725,2125)',
 ROT='0',
 VER='1',
 PACK_TYPE='0402LF',
 LOCATION='R280',
 CDS_LIB='pure_quanta',
 CDS_PART_NAME='Q_RES_0402LF-0,5%,1/16W,CHIP,CS00002JB13',
 PART_NUMBER='CS00002JB13',
 VALUE='0',
 PRIM_FILE='./archive_libs/logical/q_res/chips/chips.prt';

PART_NAME
 R281 'Q_RES_0402LF-0,5%,1/16W,CHIP,CS00002JB13':;

SECTION_NUMBER 1
 '@T6G_MB_LIB.T6G(SCH_1):PAGE137_I72@PURE_QUANTA.Q_RES(CHIPS)':
 C_PATH='@t6g_mb_lib.t6g(sch_1):page137_i72@pure_quanta.q_res(chips)',
 P_PATH='@t6g_mb_lib.t6g(sch_1):page160_i72@pure_quanta.q_res(chips)',
 PATH='I72',
 DRAWING='@T6G_MB_LIB.T6G(SCH_1):PAGE137',
 WATTAGE='1/16W',
 TOLERANCE='5%',
 MATERIAL='CHIP',
 PHYS_PAGE='160',
 XY='(-2325,700)',
 ROT='0',
 VER='1',
 PACK_TYPE='0402LF',
 LOCATION='R281',
 CDS_LIB='pure_quanta',
 CDS_PART_NAME='Q_RES_0402LF-0,5%,1/16W,CHIP,CS00002JB13',
 PART_NUMBER='CS00002JB13',
 VALUE='0',
 PRIM_FILE='./archive_libs/logical/q_res/chips/chips.prt';

PART_NAME
 R282 'Q_RES_0402LF-33,5%,1/16W,CHIP,CS03302JB10':;

SECTION_NUMBER 1
 '@T6G_MB_LIB.T6G(SCH_1):PAGE80_I31@PURE_QUANTA.Q_RES(CHIPS)':
 C_PATH='@t6g_mb_lib.t6g(sch_1):page80_i31@pure_quanta.q_res(chips)',
 P_PATH='@t6g_mb_lib.t6g(sch_1):page81_i31@pure_quanta.q_res(chips)',
 PATH='I31',
 DRAWING='@T6G_MB_LIB.T6G(SCH_1):PAGE80',
 BOM_COST='MEM',
 WATTAGE='1/16W',
 TOLERANCE='5%',
 MATERIAL='CHIP',
 PHYS_PAGE='81',
 XY='(-6725,1575)',
 ROT='0',
 VER='1',
 PACK_TYPE='0402LF',
 LOCATION='R282',
 CDS_LIB='pure_quanta',
 CDS_PART_NAME='Q_RES_0402LF-33,5%,1/16W,CHIP,CS03302JB10',
 PART_NUMBER='CS03302JB10',
 VALUE='33',
 PRIM_FILE='./archive_libs/logical/q_res/chips/chips.prt';

PART_NAME
 R283 'Q_RES_0402LF-0,5%,1/16W,CHIP,CS00002JB13':;

SECTION_NUMBER 1
 '@T6G_MB_LIB.T6G(SCH_1):PAGE80_I30@PURE_QUANTA.Q_RES(CHIPS)':
 C_PATH='@t6g_mb_lib.t6g(sch_1):page80_i30@pure_quanta.q_res(chips)',
 P_PATH='@t6g_mb_lib.t6g(sch_1):page81_i30@pure_quanta.q_res(chips)',
 PATH='I30',
 DRAWING='@T6G_MB_LIB.T6G(SCH_1):PAGE80',
 BOM_COST='MEM',
 WATTAGE='1/16W',
 TOLERANCE='5%',
 MATERIAL='CHIP',
 PHYS_PAGE='81',
 XY='(-6725,1525)',
 ROT='0',
 VER='1',
 PACK_TYPE='0402LF',
 LOCATION='R283',
 CDS_LIB='pure_quanta',
 CDS_PART_NAME='Q_RES_0402LF-0,5%,1/16W,CHIP,CS00002JB13',
 PART_NUMBER='CS00002JB13',
 VALUE='0',
 PRIM_FILE='./archive_libs/logical/q_res/chips/chips.prt';

PART_NAME
 R284 'Q_RES_0402LF-0,5%,1/16W,CHIP,CS00002JB13':;

SECTION_NUMBER 1
 '@T6G_MB_LIB.T6G(SCH_1):PAGE81_I140@PURE_QUANTA.Q_RES(CHIPS)':
 C_PATH='@t6g_mb_lib.t6g(sch_1):page81_i140@pure_quanta.q_res(chips)',
 P_PATH='@t6g_mb_lib.t6g(sch_1):page82_i140@pure_quanta.q_res(chips)',
 PATH='I140',
 DRAWING='@T6G_MB_LIB.T6G(SCH_1):PAGE81',
 BOM_COST='MEM',
 WATTAGE='1/16W',
 TOLERANCE='5%',
 MATERIAL='CHIP',
 PHYS_PAGE='82',
 XY='(-3250,6125)',
 ROT='0',
 VER='1',
 PACK_TYPE='0402LF',
 LOCATION='R284',
 CDS_LIB='pure_quanta',
 CDS_PART_NAME='Q_RES_0402LF-0,5%,1/16W,CHIP,CS00002JB13',
 PART_NUMBER='CS00002JB13',
 VALUE='0',
 PRIM_FILE='./archive_libs/logical/q_res/chips/chips.prt';

PART_NAME
 R285 'Q_RES_0402LF-33,5%,1/16W,CHIP,CS03302JB10':;

SECTION_NUMBER 1
 '@T6G_MB_LIB.T6G(SCH_1):PAGE81_I105@PURE_QUANTA.Q_RES(CHIPS)':
 C_PATH='@t6g_mb_lib.t6g(sch_1):page81_i105@pure_quanta.q_res(chips)',
 P_PATH='@t6g_mb_lib.t6g(sch_1):page82_i105@pure_quanta.q_res(chips)',
 PATH='I105',
 DRAWING='@T6G_MB_LIB.T6G(SCH_1):PAGE81',
 BOM_COST='MEM',
 WATTAGE='1/16W',
 TOLERANCE='5%',
 MATERIAL='CHIP',
 PHYS_PAGE='82',
 XY='(-3200,5075)',
 ROT='0',
 VER='1',
 PACK_TYPE='0402LF',
 LOCATION='R285',
 CDS_LIB='pure_quanta',
 CDS_PART_NAME='Q_RES_0402LF-33,5%,1/16W,CHIP,CS03302JB10',
 PART_NUMBER='CS03302JB10',
 VALUE='33',
 PRIM_FILE='./archive_libs/logical/q_res/chips/chips.prt';

PART_NAME
 R286 'Q_RES_0402LF-0,5%,1/16W,CHIP,CS00002JB13':;

SECTION_NUMBER 1
 '@T6G_MB_LIB.T6G(SCH_1):PAGE80_I62@PURE_QUANTA.Q_RES(CHIPS)':
 C_PATH='@t6g_mb_lib.t6g(sch_1):page80_i62@pure_quanta.q_res(chips)',
 P_PATH='@t6g_mb_lib.t6g(sch_1):page81_i62@pure_quanta.q_res(chips)',
 PATH='I62',
 DRAWING='@T6G_MB_LIB.T6G(SCH_1):PAGE80',
 BOM_COST='MEM',
 WATTAGE='1/16W',
 TOLERANCE='5%',
 MATERIAL='CHIP',
 PHYS_PAGE='81',
 XY='(-6725,2625)',
 ROT='0',
 VER='1',
 PACK_TYPE='0402LF',
 LOCATION='R286',
 CDS_LIB='pure_quanta',
 CDS_PART_NAME='Q_RES_0402LF-0,5%,1/16W,CHIP,CS00002JB13',
 PART_NUMBER='CS00002JB13',
 VALUE='0',
 PRIM_FILE='./archive_libs/logical/q_res/chips/chips.prt';

PART_NAME
 R287 'Q_RES_0402LF-4.7K,5%,1/16W,EMPTY,CS24702JB10':;

SECTION_NUMBER 1
 '@T6G_MB_LIB.T6G(SCH_1):PAGE28_I36@PURE_QUANTA.Q_RES(CHIPS)':
 C_PATH='@t6g_mb_lib.t6g(sch_1):page28_i36@pure_quanta.q_res(chips)',
 P_PATH='@t6g_mb_lib.t6g(sch_1):page28_i36@pure_quanta.q_res(chips)',
 PATH='I36',
 DRAWING='@T6G_MB_LIB.T6G(SCH_1):PAGE28',
 WATTAGE='1/16W',
 TOLERANCE='5%',
 MATERIAL='EMPTY',
 PHYS_PAGE='28',
 XY='(-7625,7225)',
 ROT='1',
 VER='1',
 PACK_TYPE='0402LF',
 LOCATION='R287',
 CDS_LIB='pure_quanta',
 CDS_PART_NAME='Q_RES_0402LF-4.7K,5%,1/16W,EMPTY,CS24702JB10',
 PART_NUMBER='CS24702JB10',
 VALUE='4.7K',
 PRIM_FILE='./archive_libs/logical/q_res/chips/chips.prt';

PART_NAME
 R288 'Q_RES_0402LF-4.7K,5%,1/16W,EMPTY,CS24702JB10':;

SECTION_NUMBER 1
 '@T6G_MB_LIB.T6G(SCH_1):PAGE28_I42@PURE_QUANTA.Q_RES(CHIPS)':
 C_PATH='@t6g_mb_lib.t6g(sch_1):page28_i42@pure_quanta.q_res(chips)',
 P_PATH='@t6g_mb_lib.t6g(sch_1):page28_i42@pure_quanta.q_res(chips)',
 PATH='I42',
 DRAWING='@T6G_MB_LIB.T6G(SCH_1):PAGE28',
 WATTAGE='1/16W',
 TOLERANCE='5%',
 MATERIAL='EMPTY',
 PHYS_PAGE='28',
 XY='(-7400,7750)',
 ROT='1',
 VER='1',
 PACK_TYPE='0402LF',
 LOCATION='R288',
 CDS_LIB='pure_quanta',
 CDS_PART_NAME='Q_RES_0402LF-4.7K,5%,1/16W,EMPTY,CS24702JB10',
 PART_NUMBER='CS24702JB10',
 VALUE='4.7K',
 PRIM_FILE='./archive_libs/logical/q_res/chips/chips.prt';

PART_NAME
 R289 'Q_RES_0402LF-33,5%,1/16W,CHIP,CS03302JB10':;

SECTION_NUMBER 1
 '@T6G_MB_LIB.T6G(SCH_1):PAGE80_I57@PURE_QUANTA.Q_RES(CHIPS)':
 C_PATH='@t6g_mb_lib.t6g(sch_1):page80_i57@pure_quanta.q_res(chips)',
 P_PATH='@t6g_mb_lib.t6g(sch_1):page81_i57@pure_quanta.q_res(chips)',
 PATH='I57',
 DRAWING='@T6G_MB_LIB.T6G(SCH_1):PAGE80',
 BOM_COST='MEM',
 WATTAGE='1/16W',
 TOLERANCE='5%',
 MATERIAL='CHIP',
 PHYS_PAGE='81',
 XY='(-6725,2075)',
 ROT='0',
 VER='1',
 PACK_TYPE='0402LF',
 LOCATION='R289',
 CDS_LIB='pure_quanta',
 CDS_PART_NAME='Q_RES_0402LF-33,5%,1/16W,CHIP,CS03302JB10',
 PART_NUMBER='CS03302JB10',
 VALUE='33',
 PRIM_FILE='./archive_libs/logical/q_res/chips/chips.prt';

PART_NAME
 R290 'Q_RES_0402LF-1K,1%,1/16W,EMPTY,CS21002FB06':;

SECTION_NUMBER 1
 '@T6G_MB_LIB.T6G(SCH_1):PAGE137_I78@PURE_QUANTA.Q_RES(CHIPS)':
 C_PATH='@t6g_mb_lib.t6g(sch_1):page137_i78@pure_quanta.q_res(chips)',
 P_PATH='@t6g_mb_lib.t6g(sch_1):page160_i78@pure_quanta.q_res(chips)',
 PATH='I78',
 DRAWING='@T6G_MB_LIB.T6G(SCH_1):PAGE137',
 WATTAGE='1/16W',
 TOLERANCE='1%',
 MATERIAL='EMPTY',
 PHYS_PAGE='160',
 XY='(-2000,-100)',
 ROT='0',
 VER='2',
 PACK_TYPE='0402LF',
 LOCATION='R290',
 CDS_LIB='pure_quanta',
 CDS_PART_NAME='Q_RES_0402LF-1K,1%,1/16W,EMPTY,CS21002FB06',
 PART_NUMBER='CS21002FB06',
 VALUE='1K',
 PRIM_FILE='./archive_libs/logical/q_res/chips/chips.prt';

PART_NAME
 R291 'Q_RES_0402LF-1K,1%,1/16W,CHIP,CS21002FB06':
 ROOM='';

SECTION_NUMBER 1
 '@T6G_MB_LIB.T6G(SCH_1):PAGE85_I525@PURE_QUANTA.Q_RES(CHIPS)':
 C_PATH='@t6g_mb_lib.t6g(sch_1):page85_i525@pure_quanta.q_res(chips)',
 P_PATH='@t6g_mb_lib.t6g(sch_1):page86_i525@pure_quanta.q_res(chips)',
 PATH='I525',
 DRAWING='@T6G_MB_LIB.T6G(SCH_1):PAGE85',
 BOM_COST='MEM',
 WATTAGE='1/16W',
 TOLERANCE='1%',
 MATERIAL='CHIP',
 PHYS_PAGE='86',
 XY='(-8575,2250)',
 ROT='2',
 VER='1',
 PACK_TYPE='0402LF',
 LOCATION='R291',
 CDS_LIB='pure_quanta',
 CDS_PART_NAME='Q_RES_0402LF-1K,1%,1/16W,CHIP,CS21002FB06',
 ROOM='',
 PART_NUMBER='CS21002FB06',
 VALUE='1K',
 PRIM_FILE='./archive_libs/logical/q_res/chips/chips.prt';

PART_NAME
 R292 'Q_RES_0402LF-1K,1%,1/16W,CHIP,CS21002FB06':
 ROOM='';

SECTION_NUMBER 1
 '@T6G_MB_LIB.T6G(SCH_1):PAGE86_I364@PURE_QUANTA.Q_RES(CHIPS)':
 C_PATH='@t6g_mb_lib.t6g(sch_1):page86_i364@pure_quanta.q_res(chips)',
 P_PATH='@t6g_mb_lib.t6g(sch_1):page87_i364@pure_quanta.q_res(chips)',
 PATH='I364',
 DRAWING='@T6G_MB_LIB.T6G(SCH_1):PAGE86',
 BOM_COST='MEM',
 WATTAGE='1/16W',
 TOLERANCE='1%',
 MATERIAL='CHIP',
 PHYS_PAGE='87',
 XY='(-8675,2275)',
 ROT='2',
 VER='1',
 PACK_TYPE='0402LF',
 LOCATION='R292',
 CDS_LIB='pure_quanta',
 CDS_PART_NAME='Q_RES_0402LF-1K,1%,1/16W,CHIP,CS21002FB06',
 ROOM='',
 PART_NUMBER='CS21002FB06',
 VALUE='1K',
 PRIM_FILE='./archive_libs/logical/q_res/chips/chips.prt';

PART_NAME
 R293 'Q_RES_0402LF-1K,1%,1/16W,CHIP,CS21002FB06':
 ROOM='';

SECTION_NUMBER 1
 '@T6G_MB_LIB.T6G(SCH_1):PAGE87_I364@PURE_QUANTA.Q_RES(CHIPS)':
 C_PATH='@t6g_mb_lib.t6g(sch_1):page87_i364@pure_quanta.q_res(chips)',
 P_PATH='@t6g_mb_lib.t6g(sch_1):page88_i364@pure_quanta.q_res(chips)',
 PATH='I364',
 DRAWING='@T6G_MB_LIB.T6G(SCH_1):PAGE87',
 BOM_COST='MEM',
 WATTAGE='1/16W',
 TOLERANCE='1%',
 MATERIAL='CHIP',
 PHYS_PAGE='88',
 XY='(-8675,2475)',
 ROT='2',
 VER='1',
 PACK_TYPE='0402LF',
 LOCATION='R293',
 CDS_LIB='pure_quanta',
 CDS_PART_NAME='Q_RES_0402LF-1K,1%,1/16W,CHIP,CS21002FB06',
 ROOM='',
 PART_NUMBER='CS21002FB06',
 VALUE='1K',
 PRIM_FILE='./archive_libs/logical/q_res/chips/chips.prt';

PART_NAME
 R294 'Q_RES_0402LF-1K,1%,1/16W,CHIP,CS21002FB06':
 ROOM='';

SECTION_NUMBER 1
 '@T6G_MB_LIB.T6G(SCH_1):PAGE88_I369@PURE_QUANTA.Q_RES(CHIPS)':
 C_PATH='@t6g_mb_lib.t6g(sch_1):page88_i369@pure_quanta.q_res(chips)',
 P_PATH='@t6g_mb_lib.t6g(sch_1):page89_i369@pure_quanta.q_res(chips)',
 PATH='I369',
 DRAWING='@T6G_MB_LIB.T6G(SCH_1):PAGE88',
 BOM_COST='MEM',
 WATTAGE='1/16W',
 TOLERANCE='1%',
 MATERIAL='CHIP',
 PHYS_PAGE='89',
 XY='(-8500,2300)',
 ROT='2',
 VER='1',
 PACK_TYPE='0402LF',
 LOCATION='R294',
 CDS_LIB='pure_quanta',
 CDS_PART_NAME='Q_RES_0402LF-1K,1%,1/16W,CHIP,CS21002FB06',
 ROOM='',
 PART_NUMBER='CS21002FB06',
 VALUE='1K',
 PRIM_FILE='./archive_libs/logical/q_res/chips/chips.prt';

PART_NAME
 R295 'Q_RES_0402LF-1K,1%,1/16W,CHIP,CS21002FB06':
 ROOM='';

SECTION_NUMBER 1
 '@T6G_MB_LIB.T6G(SCH_1):PAGE89_I362@PURE_QUANTA.Q_RES(CHIPS)':
 C_PATH='@t6g_mb_lib.t6g(sch_1):page89_i362@pure_quanta.q_res(chips)',
 P_PATH='@t6g_mb_lib.t6g(sch_1):page90_i362@pure_quanta.q_res(chips)',
 PATH='I362',
 DRAWING='@T6G_MB_LIB.T6G(SCH_1):PAGE89',
 BOM_COST='MEM',
 WATTAGE='1/16W',
 TOLERANCE='1%',
 MATERIAL='CHIP',
 PHYS_PAGE='90',
 XY='(-8725,2325)',
 ROT='2',
 VER='1',
 PACK_TYPE='0402LF',
 LOCATION='R295',
 CDS_LIB='pure_quanta',
 CDS_PART_NAME='Q_RES_0402LF-1K,1%,1/16W,CHIP,CS21002FB06',
 ROOM='',
 PART_NUMBER='CS21002FB06',
 VALUE='1K',
 PRIM_FILE='./archive_libs/logical/q_res/chips/chips.prt';

PART_NAME
 R296 'Q_RES_0402LF-1K,1%,1/16W,CHIP,CS21002FB06':
 ROOM='';

SECTION_NUMBER 1
 '@T6G_MB_LIB.T6G(SCH_1):PAGE90_I364@PURE_QUANTA.Q_RES(CHIPS)':
 C_PATH='@t6g_mb_lib.t6g(sch_1):page90_i364@pure_quanta.q_res(chips)',
 P_PATH='@t6g_mb_lib.t6g(sch_1):page91_i364@pure_quanta.q_res(chips)',
 PATH='I364',
 DRAWING='@T6G_MB_LIB.T6G(SCH_1):PAGE90',
 BOM_COST='MEM',
 WATTAGE='1/16W',
 TOLERANCE='1%',
 MATERIAL='CHIP',
 PHYS_PAGE='91',
 XY='(-8550,2475)',
 ROT='2',
 VER='1',
 PACK_TYPE='0402LF',
 LOCATION='R296',
 CDS_LIB='pure_quanta',
 CDS_PART_NAME='Q_RES_0402LF-1K,1%,1/16W,CHIP,CS21002FB06',
 ROOM='',
 PART_NUMBER='CS21002FB06',
 VALUE='1K',
 PRIM_FILE='./archive_libs/logical/q_res/chips/chips.prt';

PART_NAME
 R297 'Q_RES_0402LF-1K,1%,1/16W,CHIP,CS21002FB06':
 ROOM='';

SECTION_NUMBER 1
 '@T6G_MB_LIB.T6G(SCH_1):PAGE91_I186@PURE_QUANTA.Q_RES(CHIPS)':
 C_PATH='@t6g_mb_lib.t6g(sch_1):page91_i186@pure_quanta.q_res(chips)',
 P_PATH='@t6g_mb_lib.t6g(sch_1):page92_i186@pure_quanta.q_res(chips)',
 PATH='I186',
 DRAWING='@T6G_MB_LIB.T6G(SCH_1):PAGE91',
 BOM_COST='MEM',
 WATTAGE='1/16W',
 TOLERANCE='1%',
 MATERIAL='CHIP',
 PHYS_PAGE='92',
 XY='(-8350,2150)',
 ROT='2',
 VER='1',
 PACK_TYPE='0402LF',
 LOCATION='R297',
 CDS_LIB='pure_quanta',
 CDS_PART_NAME='Q_RES_0402LF-1K,1%,1/16W,CHIP,CS21002FB06',
 ROOM='',
 PART_NUMBER='CS21002FB06',
 VALUE='1K',
 PRIM_FILE='./archive_libs/logical/q_res/chips/chips.prt';

PART_NAME
 R298 'Q_RES_0402LF-1K,1%,1/16W,CHIP,CS21002FB06':
 ROOM='';

SECTION_NUMBER 1
 '@T6G_MB_LIB.T6G(SCH_1):PAGE92_I189@PURE_QUANTA.Q_RES(CHIPS)':
 C_PATH='@t6g_mb_lib.t6g(sch_1):page92_i189@pure_quanta.q_res(chips)',
 P_PATH='@t6g_mb_lib.t6g(sch_1):page93_i189@pure_quanta.q_res(chips)',
 PATH='I189',
 DRAWING='@T6G_MB_LIB.T6G(SCH_1):PAGE92',
 BOM_COST='MEM',
 WATTAGE='1/16W',
 TOLERANCE='1%',
 MATERIAL='CHIP',
 PHYS_PAGE='93',
 XY='(-8525,2100)',
 ROT='2',
 VER='1',
 PACK_TYPE='0402LF',
 LOCATION='R298',
 CDS_LIB='pure_quanta',
 CDS_PART_NAME='Q_RES_0402LF-1K,1%,1/16W,CHIP,CS21002FB06',
 ROOM='',
 PART_NUMBER='CS21002FB06',
 VALUE='1K',
 PRIM_FILE='./archive_libs/logical/q_res/chips/chips.prt';

PART_NAME
 R299 'Q_RES_0402LF-1K,1%,1/16W,CHIP,CS21002FB06':
 ROOM='';

SECTION_NUMBER 1
 '@T6G_MB_LIB.T6G(SCH_1):PAGE93_I188@PURE_QUANTA.Q_RES(CHIPS)':
 C_PATH='@t6g_mb_lib.t6g(sch_1):page93_i188@pure_quanta.q_res(chips)',
 P_PATH='@t6g_mb_lib.t6g(sch_1):page94_i188@pure_quanta.q_res(chips)',
 PATH='I188',
 DRAWING='@T6G_MB_LIB.T6G(SCH_1):PAGE93',
 BOM_COST='MEM',
 WATTAGE='1/16W',
 TOLERANCE='1%',
 MATERIAL='CHIP',
 PHYS_PAGE='94',
 XY='(-8475,2200)',
 ROT='2',
 VER='1',
 PACK_TYPE='0402LF',
 LOCATION='R299',
 CDS_LIB='pure_quanta',
 CDS_PART_NAME='Q_RES_0402LF-1K,1%,1/16W,CHIP,CS21002FB06',
 ROOM='',
 PART_NUMBER='CS21002FB06',
 VALUE='1K',
 PRIM_FILE='./archive_libs/logical/q_res/chips/chips.prt';

PART_NAME
 R300 'Q_RES_0402LF-1K,1%,1/16W,CHIP,CS21002FB06':
 ROOM='';

SECTION_NUMBER 1
 '@T6G_MB_LIB.T6G(SCH_1):PAGE94_I188@PURE_QUANTA.Q_RES(CHIPS)':
 C_PATH='@t6g_mb_lib.t6g(sch_1):page94_i188@pure_quanta.q_res(chips)',
 P_PATH='@t6g_mb_lib.t6g(sch_1):page95_i188@pure_quanta.q_res(chips)',
 PATH='I188',
 DRAWING='@T6G_MB_LIB.T6G(SCH_1):PAGE94',
 BOM_COST='MEM',
 WATTAGE='1/16W',
 TOLERANCE='1%',
 MATERIAL='CHIP',
 PHYS_PAGE='95',
 XY='(-8450,2075)',
 ROT='2',
 VER='1',
 PACK_TYPE='0402LF',
 LOCATION='R300',
 CDS_LIB='pure_quanta',
 CDS_PART_NAME='Q_RES_0402LF-1K,1%,1/16W,CHIP,CS21002FB06',
 ROOM='',
 PART_NUMBER='CS21002FB06',
 VALUE='1K',
 PRIM_FILE='./archive_libs/logical/q_res/chips/chips.prt';

PART_NAME
 R301 'Q_RES_0402LF-1K,1%,1/16W,CHIP,CS21002FB06':
 ROOM='';

SECTION_NUMBER 1
 '@T6G_MB_LIB.T6G(SCH_1):PAGE95_I188@PURE_QUANTA.Q_RES(CHIPS)':
 C_PATH='@t6g_mb_lib.t6g(sch_1):page95_i188@pure_quanta.q_res(chips)',
 P_PATH='@t6g_mb_lib.t6g(sch_1):page96_i188@pure_quanta.q_res(chips)',
 PATH='I188',
 DRAWING='@T6G_MB_LIB.T6G(SCH_1):PAGE95',
 BOM_COST='MEM',
 WATTAGE='1/16W',
 TOLERANCE='1%',
 MATERIAL='CHIP',
 PHYS_PAGE='96',
 XY='(-8475,2125)',
 ROT='2',
 VER='1',
 PACK_TYPE='0402LF',
 LOCATION='R301',
 CDS_LIB='pure_quanta',
 CDS_PART_NAME='Q_RES_0402LF-1K,1%,1/16W,CHIP,CS21002FB06',
 ROOM='',
 PART_NUMBER='CS21002FB06',
 VALUE='1K',
 PRIM_FILE='./archive_libs/logical/q_res/chips/chips.prt';

PART_NAME
 R302 'Q_RES_0402LF-1K,1%,1/16W,CHIP,CS21002FB06':
 ROOM='';

SECTION_NUMBER 1
 '@T6G_MB_LIB.T6G(SCH_1):PAGE96_I188@PURE_QUANTA.Q_RES(CHIPS)':
 C_PATH='@t6g_mb_lib.t6g(sch_1):page96_i188@pure_quanta.q_res(chips)',
 P_PATH='@t6g_mb_lib.t6g(sch_1):page97_i188@pure_quanta.q_res(chips)',
 PATH='I188',
 DRAWING='@T6G_MB_LIB.T6G(SCH_1):PAGE96',
 BOM_COST='MEM',
 WATTAGE='1/16W',
 TOLERANCE='1%',
 MATERIAL='CHIP',
 PHYS_PAGE='97',
 XY='(-8475,1825)',
 ROT='2',
 VER='1',
 PACK_TYPE='0402LF',
 LOCATION='R302',
 CDS_LIB='pure_quanta',
 CDS_PART_NAME='Q_RES_0402LF-1K,1%,1/16W,CHIP,CS21002FB06',
 ROOM='',
 PART_NUMBER='CS21002FB06',
 VALUE='1K',
 PRIM_FILE='./archive_libs/logical/q_res/chips/chips.prt';

PART_NAME
 R303 'Q_RES_0402LF-1K,1%,1/16W,CHIP,CS21002FB06':
 ROOM='';

SECTION_NUMBER 1
 '@T6G_MB_LIB.T6G(SCH_1):PAGE97_I190@PURE_QUANTA.Q_RES(CHIPS)':
 C_PATH='@t6g_mb_lib.t6g(sch_1):page97_i190@pure_quanta.q_res(chips)',
 P_PATH='@t6g_mb_lib.t6g(sch_1):page98_i190@pure_quanta.q_res(chips)',
 PATH='I190',
 DRAWING='@T6G_MB_LIB.T6G(SCH_1):PAGE97',
 BOM_COST='MEM',
 WATTAGE='1/16W',
 TOLERANCE='1%',
 MATERIAL='CHIP',
 PHYS_PAGE='98',
 XY='(-8400,2225)',
 ROT='2',
 VER='1',
 PACK_TYPE='0402LF',
 LOCATION='R303',
 CDS_LIB='pure_quanta',
 CDS_PART_NAME='Q_RES_0402LF-1K,1%,1/16W,CHIP,CS21002FB06',
 ROOM='',
 PART_NUMBER='CS21002FB06',
 VALUE='1K',
 PRIM_FILE='./archive_libs/logical/q_res/chips/chips.prt';

PART_NAME
 R304 'Q_RES_0402LF-1K,1%,1/16W,CHIP,CS21002FB06':
 ROOM='';

SECTION_NUMBER 1
 '@T6G_MB_LIB.T6G(SCH_1):PAGE98_I188@PURE_QUANTA.Q_RES(CHIPS)':
 C_PATH='@t6g_mb_lib.t6g(sch_1):page98_i188@pure_quanta.q_res(chips)',
 P_PATH='@t6g_mb_lib.t6g(sch_1):page99_i188@pure_quanta.q_res(chips)',
 PATH='I188',
 DRAWING='@T6G_MB_LIB.T6G(SCH_1):PAGE98',
 BOM_COST='MEM',
 WATTAGE='1/16W',
 TOLERANCE='1%',
 MATERIAL='CHIP',
 PHYS_PAGE='99',
 XY='(-8625,2275)',
 ROT='2',
 VER='1',
 PACK_TYPE='0402LF',
 LOCATION='R304',
 CDS_LIB='pure_quanta',
 CDS_PART_NAME='Q_RES_0402LF-1K,1%,1/16W,CHIP,CS21002FB06',
 ROOM='',
 PART_NUMBER='CS21002FB06',
 VALUE='1K',
 PRIM_FILE='./archive_libs/logical/q_res/chips/chips.prt';

PART_NAME
 R305 'Q_RES_0402LF-1K,1%,1/16W,CHIP,CS21002FB06':
 ROOM='';

SECTION_NUMBER 1
 '@T6G_MB_LIB.T6G(SCH_1):PAGE99_I188@PURE_QUANTA.Q_RES(CHIPS)':
 C_PATH='@t6g_mb_lib.t6g(sch_1):page99_i188@pure_quanta.q_res(chips)',
 P_PATH='@t6g_mb_lib.t6g(sch_1):page100_i188@pure_quanta.q_res(chips)',
 PATH='I188',
 DRAWING='@T6G_MB_LIB.T6G(SCH_1):PAGE99',
 BOM_COST='MEM',
 WATTAGE='1/16W',
 TOLERANCE='1%',
 MATERIAL='CHIP',
 PHYS_PAGE='100',
 XY='(-8700,2150)',
 ROT='2',
 VER='1',
 PACK_TYPE='0402LF',
 LOCATION='R305',
 CDS_LIB='pure_quanta',
 CDS_PART_NAME='Q_RES_0402LF-1K,1%,1/16W,CHIP,CS21002FB06',
 ROOM='',
 PART_NUMBER='CS21002FB06',
 VALUE='1K',
 PRIM_FILE='./archive_libs/logical/q_res/chips/chips.prt';

PART_NAME
 R306 'Q_RES_0402LF-1K,1%,1/16W,CHIP,CS21002FB06':
 ROOM='';

SECTION_NUMBER 1
 '@T6G_MB_LIB.T6G(SCH_1):PAGE100_I188@PURE_QUANTA.Q_RES(CHIPS)':
 C_PATH='@t6g_mb_lib.t6g(sch_1):page100_i188@pure_quanta.q_res(chips)',
 P_PATH='@t6g_mb_lib.t6g(sch_1):page101_i188@pure_quanta.q_res(chips)',
 PATH='I188',
 DRAWING='@T6G_MB_LIB.T6G(SCH_1):PAGE100',
 BOM_COST='MEM',
 WATTAGE='1/16W',
 TOLERANCE='1%',
 MATERIAL='CHIP',
 PHYS_PAGE='101',
 XY='(-8600,2325)',
 ROT='2',
 VER='1',
 PACK_TYPE='0402LF',
 LOCATION='R306',
 CDS_LIB='pure_quanta',
 CDS_PART_NAME='Q_RES_0402LF-1K,1%,1/16W,CHIP,CS21002FB06',
 ROOM='',
 PART_NUMBER='CS21002FB06',
 VALUE='1K',
 PRIM_FILE='./archive_libs/logical/q_res/chips/chips.prt';

PART_NAME
 R307 'Q_RES_0402LF-1K,1%,1/16W,CHIP,CS21002FB06':
 ROOM='';

SECTION_NUMBER 1
 '@T6G_MB_LIB.T6G(SCH_1):PAGE101_I188@PURE_QUANTA.Q_RES(CHIPS)':
 C_PATH='@t6g_mb_lib.t6g(sch_1):page101_i188@pure_quanta.q_res(chips)',
 P_PATH='@t6g_mb_lib.t6g(sch_1):page102_i188@pure_quanta.q_res(chips)',
 PATH='I188',
 DRAWING='@T6G_MB_LIB.T6G(SCH_1):PAGE101',
 BOM_COST='MEM',
 WATTAGE='1/16W',
 TOLERANCE='1%',
 MATERIAL='CHIP',
 PHYS_PAGE='102',
 XY='(-8625,2400)',
 ROT='2',
 VER='1',
 PACK_TYPE='0402LF',
 LOCATION='R307',
 CDS_LIB='pure_quanta',
 CDS_PART_NAME='Q_RES_0402LF-1K,1%,1/16W,CHIP,CS21002FB06',
 ROOM='',
 PART_NUMBER='CS21002FB06',
 VALUE='1K',
 PRIM_FILE='./archive_libs/logical/q_res/chips/chips.prt';

PART_NAME
 R308 'Q_RES_0402LF-33,5%,1/16W,CHIP,CS03302JB10':;

SECTION_NUMBER 1
 '@T6G_MB_LIB.T6G(SCH_1):PAGE349_I224@PURE_QUANTA.Q_RES(CHIPS)':
 C_PATH='@t6g_mb_lib.t6g(sch_1):page349_i224@pure_quanta.q_res(chips)',
 P_PATH='@t6g_mb_lib.t6g(sch_1):page151_i224@pure_quanta.q_res(chips)',
 PATH='I224',
 DRAWING='@T6G_MB_LIB.T6G(SCH_1):PAGE349',
 WATTAGE='1/16W',
 TOLERANCE='5%',
 MATERIAL='CHIP',
 PHYS_PAGE='151',
 XY='(-1625,2375)',
 ROT='0',
 VER='1',
 PACK_TYPE='0402LF',
 LOCATION='R308',
 CDS_LIB='pure_quanta',
 CDS_PART_NAME='Q_RES_0402LF-33,5%,1/16W,CHIP,CS03302JB10',
 PART_NUMBER='CS03302JB10',
 VALUE='33',
 PRIM_FILE='./archive_libs/logical/q_res/chips/chips.prt';

PART_NAME
 R309 'Q_RES_0402LF-33,5%,1/16W,CHIP,CS03302JB10':;

SECTION_NUMBER 1
 '@T6G_MB_LIB.T6G(SCH_1):PAGE349_I225@PURE_QUANTA.Q_RES(CHIPS)':
 C_PATH='@t6g_mb_lib.t6g(sch_1):page349_i225@pure_quanta.q_res(chips)',
 P_PATH='@t6g_mb_lib.t6g(sch_1):page151_i225@pure_quanta.q_res(chips)',
 PATH='I225',
 DRAWING='@T6G_MB_LIB.T6G(SCH_1):PAGE349',
 SEC_TYPE='0402LF',
 WATTAGE='1/16W',
 TOLERANCE='5%',
 MATERIAL='CHIP',
 PHYS_PAGE='151',
 XY='(-1625,2275)',
 ROT='0',
 VER='1',
 PACK_TYPE='0402LF',
 LOCATION='R309',
 SEC='1',
 CDS_LIB='pure_quanta',
 CDS_PART_NAME='Q_RES_0402LF-33,5%,1/16W,CHIP,CS03302JB10',
 PART_NUMBER='CS03302JB10',
 VALUE='33',
 PRIM_FILE='./archive_libs/logical/q_res/chips/chips.prt';

PART_NAME
 R310 'Q_RES_0402LF-1K,1%,1/16W,CHIP,CS21002FB06':
 ROOM='';

SECTION_NUMBER 1
 '@T6G_MB_LIB.T6G(SCH_1):PAGE104_I189@PURE_QUANTA.Q_RES(CHIPS)':
 C_PATH='@t6g_mb_lib.t6g(sch_1):page104_i189@pure_quanta.q_res(chips)',
 P_PATH='@t6g_mb_lib.t6g(sch_1):page105_i189@pure_quanta.q_res(chips)',
 PATH='I189',
 DRAWING='@T6G_MB_LIB.T6G(SCH_1):PAGE104',
 BOM_COST='MEM',
 WATTAGE='1/16W',
 TOLERANCE='1%',
 MATERIAL='CHIP',
 PHYS_PAGE='105',
 XY='(-8475,2150)',
 ROT='2',
 VER='1',
 PACK_TYPE='0402LF',
 LOCATION='R310',
 CDS_LIB='pure_quanta',
 CDS_PART_NAME='Q_RES_0402LF-1K,1%,1/16W,CHIP,CS21002FB06',
 ROOM='',
 PART_NUMBER='CS21002FB06',
 VALUE='1K',
 PRIM_FILE='./archive_libs/logical/q_res/chips/chips.prt';

PART_NAME
 R311 'Q_RES_0402LF-1K,1%,1/16W,CHIP,CS21002FB06':
 ROOM='';

SECTION_NUMBER 1
 '@T6G_MB_LIB.T6G(SCH_1):PAGE105_I188@PURE_QUANTA.Q_RES(CHIPS)':
 C_PATH='@t6g_mb_lib.t6g(sch_1):page105_i188@pure_quanta.q_res(chips)',
 P_PATH='@t6g_mb_lib.t6g(sch_1):page106_i188@pure_quanta.q_res(chips)',
 PATH='I188',
 DRAWING='@T6G_MB_LIB.T6G(SCH_1):PAGE105',
 BOM_COST='MEM',
 WATTAGE='1/16W',
 TOLERANCE='1%',
 MATERIAL='CHIP',
 PHYS_PAGE='106',
 XY='(-8475,2100)',
 ROT='2',
 VER='1',
 PACK_TYPE='0402LF',
 LOCATION='R311',
 CDS_LIB='pure_quanta',
 CDS_PART_NAME='Q_RES_0402LF-1K,1%,1/16W,CHIP,CS21002FB06',
 ROOM='',
 PART_NUMBER='CS21002FB06',
 VALUE='1K',
 PRIM_FILE='./archive_libs/logical/q_res/chips/chips.prt';

PART_NAME
 R312 'Q_RES_0402LF-1K,1%,1/16W,CHIP,CS21002FB06':
 ROOM='';

SECTION_NUMBER 1
 '@T6G_MB_LIB.T6G(SCH_1):PAGE106_I188@PURE_QUANTA.Q_RES(CHIPS)':
 C_PATH='@t6g_mb_lib.t6g(sch_1):page106_i188@pure_quanta.q_res(chips)',
 P_PATH='@t6g_mb_lib.t6g(sch_1):page107_i188@pure_quanta.q_res(chips)',
 PATH='I188',
 DRAWING='@T6G_MB_LIB.T6G(SCH_1):PAGE106',
 BOM_COST='MEM',
 WATTAGE='1/16W',
 TOLERANCE='1%',
 MATERIAL='CHIP',
 PHYS_PAGE='107',
 XY='(-8375,2075)',
 ROT='2',
 VER='1',
 PACK_TYPE='0402LF',
 LOCATION='R312',
 CDS_LIB='pure_quanta',
 CDS_PART_NAME='Q_RES_0402LF-1K,1%,1/16W,CHIP,CS21002FB06',
 ROOM='',
 PART_NUMBER='CS21002FB06',
 VALUE='1K',
 PRIM_FILE='./archive_libs/logical/q_res/chips/chips.prt';

PART_NAME
 R313 'Q_RES_0402LF-1K,1%,1/16W,CHIP,CS21002FB06':
 ROOM='';

SECTION_NUMBER 1
 '@T6G_MB_LIB.T6G(SCH_1):PAGE107_I188@PURE_QUANTA.Q_RES(CHIPS)':
 C_PATH='@t6g_mb_lib.t6g(sch_1):page107_i188@pure_quanta.q_res(chips)',
 P_PATH='@t6g_mb_lib.t6g(sch_1):page108_i188@pure_quanta.q_res(chips)',
 PATH='I188',
 DRAWING='@T6G_MB_LIB.T6G(SCH_1):PAGE107',
 BOM_COST='MEM',
 WATTAGE='1/16W',
 TOLERANCE='1%',
 MATERIAL='CHIP',
 PHYS_PAGE='108',
 XY='(-8500,2075)',
 ROT='2',
 VER='1',
 PACK_TYPE='0402LF',
 LOCATION='R313',
 CDS_LIB='pure_quanta',
 CDS_PART_NAME='Q_RES_0402LF-1K,1%,1/16W,CHIP,CS21002FB06',
 ROOM='',
 PART_NUMBER='CS21002FB06',
 VALUE='1K',
 PRIM_FILE='./archive_libs/logical/q_res/chips/chips.prt';

PART_NAME
 R314 'Q_RES_0402LF-1K,1%,1/16W,CHIP,CS21002FB06':
 ROOM='';

SECTION_NUMBER 1
 '@T6G_MB_LIB.T6G(SCH_1):PAGE108_I188@PURE_QUANTA.Q_RES(CHIPS)':
 C_PATH='@t6g_mb_lib.t6g(sch_1):page108_i188@pure_quanta.q_res(chips)',
 P_PATH='@t6g_mb_lib.t6g(sch_1):page109_i188@pure_quanta.q_res(chips)',
 PATH='I188',
 DRAWING='@T6G_MB_LIB.T6G(SCH_1):PAGE108',
 BOM_COST='MEM',
 WATTAGE='1/16W',
 TOLERANCE='1%',
 MATERIAL='CHIP',
 PHYS_PAGE='109',
 XY='(-8450,2150)',
 ROT='2',
 VER='1',
 PACK_TYPE='0402LF',
 LOCATION='R314',
 CDS_LIB='pure_quanta',
 CDS_PART_NAME='Q_RES_0402LF-1K,1%,1/16W,CHIP,CS21002FB06',
 ROOM='',
 PART_NUMBER='CS21002FB06',
 VALUE='1K',
 PRIM_FILE='./archive_libs/logical/q_res/chips/chips.prt';

PART_NAME
 R315 'Q_RES_0402LF-49.9,1%,1/16W,CHIP,CS04992FB07':;

SECTION_NUMBER 1
 '@T6G_MB_LIB.T6G(SCH_1):PAGE168_I57@PURE_QUANTA.Q_RES(CHIPS)':
 C_PATH='@t6g_mb_lib.t6g(sch_1):page168_i57@pure_quanta.q_res(chips)',
 P_PATH='@t6g_mb_lib.t6g(sch_1):page193_i57@pure_quanta.q_res(chips)',
 PATH='I57',
 DRAWING='@T6G_MB_LIB.T6G(SCH_1):PAGE168',
 WATTAGE='1/16W',
 TOLERANCE='1%',
 MATERIAL='CHIP',
 PHYS_PAGE='193',
 XY='(-5550,2650)',
 ROT='0',
 VER='1',
 PACK_TYPE='0402LF',
 LOCATION='R315',
 CDS_LIB='pure_quanta',
 CDS_PART_NAME='Q_RES_0402LF-49.9,1%,1/16W,CHIP,CS04992FB07',
 PART_NUMBER='CS04992FB07',
 VALUE='49.9',
 PRIM_FILE='./archive_libs/logical/q_res/chips/chips.prt';

PART_NAME
 R316 'Q_RES_0402LF-10K,1%,1/16W,EMPTY,CS31002FB08':;

SECTION_NUMBER 1
 '@T6G_MB_LIB.T6G(SCH_1):PAGE252_I7@PURE_QUANTA.Q_RES(CHIPS)':
 C_PATH='@t6g_mb_lib.t6g(sch_1):page252_i7@pure_quanta.q_res(chips)',
 P_PATH='@t6g_mb_lib.t6g(sch_1):page250_i7@pure_quanta.q_res(chips)',
 PATH='I7',
 DRAWING='@T6G_MB_LIB.T6G(SCH_1):PAGE252',
 WATTAGE='1/16W',
 TOLERANCE='1%',
 MATERIAL='EMPTY',
 PHYS_PAGE='250',
 XY='(-5900,2975)',
 ROT='0',
 VER='2',
 PACK_TYPE='0402LF',
 LOCATION='R316',
 CDS_LIB='pure_quanta',
 CDS_PART_NAME='Q_RES_0402LF-10K,1%,1/16W,EMPTY,CS31002FB08',
 PART_NUMBER='CS31002FB08',
 VALUE='10K',
 PRIM_FILE='./archive_libs/logical/q_res/chips/chips.prt';

PART_NAME
 R317 'Q_RES_0402LF-1K,1%,1/16W,CHIP,CS21002FB06':;

SECTION_NUMBER 1
 '@T6G_MB_LIB.T6G(SCH_1):PAGE252_I2@PURE_QUANTA.Q_RES(CHIPS)':
 C_PATH='@t6g_mb_lib.t6g(sch_1):page252_i2@pure_quanta.q_res(chips)',
 P_PATH='@t6g_mb_lib.t6g(sch_1):page250_i2@pure_quanta.q_res(chips)',
 PATH='I2',
 DRAWING='@T6G_MB_LIB.T6G(SCH_1):PAGE252',
 WATTAGE='1/16W',
 TOLERANCE='1%',
 MATERIAL='CHIP',
 PHYS_PAGE='250',
 XY='(-5900,2325)',
 ROT='0',
 VER='2',
 PACK_TYPE='0402LF',
 LOCATION='R317',
 CDS_LIB='pure_quanta',
 CDS_PART_NAME='Q_RES_0402LF-1K,1%,1/16W,CHIP,CS21002FB06',
 PART_NUMBER='CS21002FB06',
 VALUE='1K',
 PRIM_FILE='./archive_libs/logical/q_res/chips/chips.prt';

PART_NAME
 R318 'Q_RES_0402LF-10K,1%,1/16W,EMPTY,CS31002FB08':;

SECTION_NUMBER 1
 '@T6G_MB_LIB.T6G(SCH_1):PAGE252_I8@PURE_QUANTA.Q_RES(CHIPS)':
 C_PATH='@t6g_mb_lib.t6g(sch_1):page252_i8@pure_quanta.q_res(chips)',
 P_PATH='@t6g_mb_lib.t6g(sch_1):page250_i8@pure_quanta.q_res(chips)',
 PATH='I8',
 DRAWING='@T6G_MB_LIB.T6G(SCH_1):PAGE252',
 WATTAGE='1/16W',
 TOLERANCE='1%',
 MATERIAL='EMPTY',
 PHYS_PAGE='250',
 XY='(-5625,2975)',
 ROT='0',
 VER='2',
 PACK_TYPE='0402LF',
 LOCATION='R318',
 CDS_LIB='pure_quanta',
 CDS_PART_NAME='Q_RES_0402LF-10K,1%,1/16W,EMPTY,CS31002FB08',
 PART_NUMBER='CS31002FB08',
 VALUE='10K',
 PRIM_FILE='./archive_libs/logical/q_res/chips/chips.prt';

PART_NAME
 R319 'Q_RES_0402LF-1K,1%,1/16W,CHIP,CS21002FB06':;

SECTION_NUMBER 1
 '@T6G_MB_LIB.T6G(SCH_1):PAGE252_I4@PURE_QUANTA.Q_RES(CHIPS)':
 C_PATH='@t6g_mb_lib.t6g(sch_1):page252_i4@pure_quanta.q_res(chips)',
 P_PATH='@t6g_mb_lib.t6g(sch_1):page250_i4@pure_quanta.q_res(chips)',
 PATH='I4',
 DRAWING='@T6G_MB_LIB.T6G(SCH_1):PAGE252',
 WATTAGE='1/16W',
 TOLERANCE='1%',
 MATERIAL='CHIP',
 PHYS_PAGE='250',
 XY='(-5625,2325)',
 ROT='0',
 VER='2',
 PACK_TYPE='0402LF',
 LOCATION='R319',
 CDS_LIB='pure_quanta',
 CDS_PART_NAME='Q_RES_0402LF-1K,1%,1/16W,CHIP,CS21002FB06',
 PART_NUMBER='CS21002FB06',
 VALUE='1K',
 PRIM_FILE='./archive_libs/logical/q_res/chips/chips.prt';

PART_NAME
 R320 'Q_RES_0402LF-10K,1%,1/16W,EMPTY,CS31002FB08':;

SECTION_NUMBER 1
 '@T6G_MB_LIB.T6G(SCH_1):PAGE252_I10@PURE_QUANTA.Q_RES(CHIPS)':
 C_PATH='@t6g_mb_lib.t6g(sch_1):page252_i10@pure_quanta.q_res(chips)',
 P_PATH='@t6g_mb_lib.t6g(sch_1):page250_i10@pure_quanta.q_res(chips)',
 PATH='I10',
 DRAWING='@T6G_MB_LIB.T6G(SCH_1):PAGE252',
 WATTAGE='1/16W',
 TOLERANCE='1%',
 MATERIAL='EMPTY',
 PHYS_PAGE='250',
 XY='(-5350,2975)',
 ROT='0',
 VER='2',
 PACK_TYPE='0402LF',
 LOCATION='R320',
 CDS_LIB='pure_quanta',
 CDS_PART_NAME='Q_RES_0402LF-10K,1%,1/16W,EMPTY,CS31002FB08',
 PART_NUMBER='CS31002FB08',
 VALUE='10K',
 PRIM_FILE='./archive_libs/logical/q_res/chips/chips.prt';

PART_NAME
 R321 'Q_RES_0402LF-0,5%,1/16W,CHIP,CS00002JB13':;

SECTION_NUMBER 1
 '@T6G_MB_LIB.T6G(SCH_1):PAGE348_I24@PURE_QUANTA.Q_RES(CHIPS)':
 C_PATH='@t6g_mb_lib.t6g(sch_1):page348_i24@pure_quanta.q_res(chips)',
 P_PATH='@t6g_mb_lib.t6g(sch_1):page150_i24@pure_quanta.q_res(chips)',
 PATH='I24',
 DRAWING='@T6G_MB_LIB.T6G(SCH_1):PAGE348',
 WATTAGE='1/16W',
 TOLERANCE='5%',
 MATERIAL='CHIP',
 PHYS_PAGE='150',
 XY='(-14975,5725)',
 ROT='0',
 VER='1',
 PACK_TYPE='0402LF',
 LOCATION='R321',
 CDS_LIB='pure_quanta',
 CDS_PART_NAME='Q_RES_0402LF-0,5%,1/16W,CHIP,CS00002JB13',
 PART_NUMBER='CS00002JB13',
 VALUE='0',
 PRIM_FILE='./archive_libs/logical/q_res/chips/chips.prt';

PART_NAME
 R322 'Q_RES_0402LF-1K,1%,1/16W,EMPTY,CS21002FB06':;

SECTION_NUMBER 1
 '@T6G_MB_LIB.T6G(SCH_1):PAGE137_I73@PURE_QUANTA.Q_RES(CHIPS)':
 C_PATH='@t6g_mb_lib.t6g(sch_1):page137_i73@pure_quanta.q_res(chips)',
 P_PATH='@t6g_mb_lib.t6g(sch_1):page160_i73@pure_quanta.q_res(chips)',
 PATH='I73',
 DRAWING='@T6G_MB_LIB.T6G(SCH_1):PAGE137',
 WATTAGE='1/16W',
 TOLERANCE='1%',
 MATERIAL='EMPTY',
 PHYS_PAGE='160',
 XY='(-1750,-150)',
 ROT='0',
 VER='2',
 PACK_TYPE='0402LF',
 LOCATION='R322',
 CDS_LIB='pure_quanta',
 CDS_PART_NAME='Q_RES_0402LF-1K,1%,1/16W,EMPTY,CS21002FB06',
 PART_NUMBER='CS21002FB06',
 VALUE='1K',
 PRIM_FILE='./archive_libs/logical/q_res/chips/chips.prt';

PART_NAME
 R323 'Q_RES_0402LF-0,5%,1/16W,EMPTY,CS00002JB13':;

SECTION_NUMBER 1
 '@T6G_MB_LIB.T6G(SCH_1):PAGE138_I109@PURE_QUANTA.Q_RES(CHIPS)':
 C_PATH='@t6g_mb_lib.t6g(sch_1):page138_i109@pure_quanta.q_res(chips)',
 P_PATH='@t6g_mb_lib.t6g(sch_1):page161_i109@pure_quanta.q_res(chips)',
 PATH='I109',
 DRAWING='@T6G_MB_LIB.T6G(SCH_1):PAGE138',
 WATTAGE='1/16W',
 TOLERANCE='5%',
 MATERIAL='EMPTY',
 PHYS_PAGE='161',
 XY='(-575,3875)',
 ROT='0',
 VER='1',
 PACK_TYPE='0402LF',
 LOCATION='R323',
 CDS_LIB='pure_quanta',
 CDS_PART_NAME='Q_RES_0402LF-0,5%,1/16W,EMPTY,CS00002JB13',
 PART_NUMBER='CS00002JB13',
 VALUE='0',
 PRIM_FILE='./archive_libs/logical/q_res/chips/chips.prt';

PART_NAME
 R324 'Q_RES_0402LF-0,5%,1/16W,EMPTY,CS00002JB13':;

SECTION_NUMBER 1
 '@T6G_MB_LIB.T6G(SCH_1):PAGE138_I110@PURE_QUANTA.Q_RES(CHIPS)':
 C_PATH='@t6g_mb_lib.t6g(sch_1):page138_i110@pure_quanta.q_res(chips)',
 P_PATH='@t6g_mb_lib.t6g(sch_1):page161_i110@pure_quanta.q_res(chips)',
 PATH='I110',
 DRAWING='@T6G_MB_LIB.T6G(SCH_1):PAGE138',
 WATTAGE='1/16W',
 TOLERANCE='5%',
 MATERIAL='EMPTY',
 PHYS_PAGE='161',
 XY='(-575,3825)',
 ROT='0',
 VER='1',
 PACK_TYPE='0402LF',
 LOCATION='R324',
 CDS_LIB='pure_quanta',
 CDS_PART_NAME='Q_RES_0402LF-0,5%,1/16W,EMPTY,CS00002JB13',
 PART_NUMBER='CS00002JB13',
 VALUE='0',
 PRIM_FILE='./archive_libs/logical/q_res/chips/chips.prt';

PART_NAME
 R325 'Q_RES_0402LF-0,5%,1/16W,CHIP,CS00002JB13':;

SECTION_NUMBER 1
 '@T6G_MB_LIB.T6G(SCH_1):PAGE138_I99@PURE_QUANTA.Q_RES(CHIPS)':
 C_PATH='@t6g_mb_lib.t6g(sch_1):page138_i99@pure_quanta.q_res(chips)',
 P_PATH='@t6g_mb_lib.t6g(sch_1):page161_i99@pure_quanta.q_res(chips)',
 PATH='I99',
 DRAWING='@T6G_MB_LIB.T6G(SCH_1):PAGE138',
 WATTAGE='1/16W',
 TOLERANCE='5%',
 MATERIAL='CHIP',
 PHYS_PAGE='161',
 XY='(3025,5550)',
 ROT='0',
 VER='1',
 PACK_TYPE='0402LF',
 LOCATION='R325',
 CDS_LIB='pure_quanta',
 CDS_PART_NAME='Q_RES_0402LF-0,5%,1/16W,CHIP,CS00002JB13',
 PART_NUMBER='CS00002JB13',
 VALUE='0',
 PRIM_FILE='./archive_libs/logical/q_res/chips/chips.prt';

PART_NAME
 R326 'Q_RES_0402LF-0,5%,1/16W,CHIP,CS00002JB13':;

SECTION_NUMBER 1
 '@T6G_MB_LIB.T6G(SCH_1):PAGE138_I100@PURE_QUANTA.Q_RES(CHIPS)':
 C_PATH='@t6g_mb_lib.t6g(sch_1):page138_i100@pure_quanta.q_res(chips)',
 P_PATH='@t6g_mb_lib.t6g(sch_1):page161_i100@pure_quanta.q_res(chips)',
 PATH='I100',
 DRAWING='@T6G_MB_LIB.T6G(SCH_1):PAGE138',
 WATTAGE='1/16W',
 TOLERANCE='5%',
 MATERIAL='CHIP',
 PHYS_PAGE='161',
 XY='(3025,5500)',
 ROT='0',
 VER='1',
 PACK_TYPE='0402LF',
 LOCATION='R326',
 CDS_LIB='pure_quanta',
 CDS_PART_NAME='Q_RES_0402LF-0,5%,1/16W,CHIP,CS00002JB13',
 PART_NUMBER='CS00002JB13',
 VALUE='0',
 PRIM_FILE='./archive_libs/logical/q_res/chips/chips.prt';

PART_NAME
 R327 'Q_RES_0402LF-0,5%,1/16W,CHIP,CS00002JB13':;

SECTION_NUMBER 1
 '@T6G_MB_LIB.T6G(SCH_1):PAGE138_I91@PURE_QUANTA.Q_RES(CHIPS)':
 C_PATH='@t6g_mb_lib.t6g(sch_1):page138_i91@pure_quanta.q_res(chips)',
 P_PATH='@t6g_mb_lib.t6g(sch_1):page161_i91@pure_quanta.q_res(chips)',
 PATH='I91',
 DRAWING='@T6G_MB_LIB.T6G(SCH_1):PAGE138',
 WATTAGE='1/16W',
 TOLERANCE='5%',
 MATERIAL='CHIP',
 PHYS_PAGE='161',
 XY='(5825,5450)',
 ROT='0',
 VER='1',
 PACK_TYPE='0402LF',
 LOCATION='R327',
 CDS_LIB='pure_quanta',
 CDS_PART_NAME='Q_RES_0402LF-0,5%,1/16W,CHIP,CS00002JB13',
 PART_NUMBER='CS00002JB13',
 VALUE='0',
 PRIM_FILE='./archive_libs/logical/q_res/chips/chips.prt';

PART_NAME
 R328 'Q_RES_0402LF-0,5%,1/16W,CHIP,CS00002JB13':;

SECTION_NUMBER 1
 '@T6G_MB_LIB.T6G(SCH_1):PAGE138_I92@PURE_QUANTA.Q_RES(CHIPS)':
 C_PATH='@t6g_mb_lib.t6g(sch_1):page138_i92@pure_quanta.q_res(chips)',
 P_PATH='@t6g_mb_lib.t6g(sch_1):page161_i92@pure_quanta.q_res(chips)',
 PATH='I92',
 DRAWING='@T6G_MB_LIB.T6G(SCH_1):PAGE138',
 WATTAGE='1/16W',
 TOLERANCE='5%',
 MATERIAL='CHIP',
 PHYS_PAGE='161',
 XY='(5825,5400)',
 ROT='0',
 VER='1',
 PACK_TYPE='0402LF',
 LOCATION='R328',
 CDS_LIB='pure_quanta',
 CDS_PART_NAME='Q_RES_0402LF-0,5%,1/16W,CHIP,CS00002JB13',
 PART_NUMBER='CS00002JB13',
 VALUE='0',
 PRIM_FILE='./archive_libs/logical/q_res/chips/chips.prt';

PART_NAME
 R329 'Q_RES_0402LF-2K,1%,1/16W,EMPTY,CS22002FB07':;

SECTION_NUMBER 1
 '@T6G_MB_LIB.T6G(SCH_1):PAGE349_I133@PURE_QUANTA.Q_RES(CHIPS)':
 C_PATH='@t6g_mb_lib.t6g(sch_1):page349_i133@pure_quanta.q_res(chips)',
 P_PATH='@t6g_mb_lib.t6g(sch_1):page151_i133@pure_quanta.q_res(chips)',
 PATH='I133',
 DRAWING='@T6G_MB_LIB.T6G(SCH_1):PAGE349',
 WATTAGE='1/16W',
 TOLERANCE='1%',
 MATERIAL='EMPTY',
 PHYS_PAGE='151',
 XY='(4275,4725)',
 ROT='0',
 VER='1',
 PACK_TYPE='0402LF',
 LOCATION='R329',
 CDS_LIB='pure_quanta',
 CDS_PART_NAME='Q_RES_0402LF-2K,1%,1/16W,EMPTY,CS22002FB07',
 PART_NUMBER='CS22002FB07',
 VALUE='2K',
 PRIM_FILE='./archive_libs/logical/q_res/chips/chips.prt';

PART_NAME
 R330 'Q_RES_0402LF-2.2K,5%,1/16W,EMPTY,CS22202JB07':;

SECTION_NUMBER 1
 '@T6G_MB_LIB.T6G(SCH_1):PAGE349_I130@PURE_QUANTA.Q_RES(CHIPS)':
 C_PATH='@t6g_mb_lib.t6g(sch_1):page349_i130@pure_quanta.q_res(chips)',
 P_PATH='@t6g_mb_lib.t6g(sch_1):page151_i130@pure_quanta.q_res(chips)',
 PATH='I130',
 DRAWING='@T6G_MB_LIB.T6G(SCH_1):PAGE349',
 WATTAGE='1/16W',
 TOLERANCE='5%',
 MATERIAL='EMPTY',
 PHYS_PAGE='151',
 XY='(4275,4175)',
 ROT='0',
 VER='1',
 PACK_TYPE='0402LF',
 LOCATION='R330',
 CDS_LIB='pure_quanta',
 CDS_PART_NAME='Q_RES_0402LF-2.2K,5%,1/16W,EMPTY,CS22202JB07',
 PART_NUMBER='CS22202JB07',
 VALUE='2.2K',
 PRIM_FILE='./archive_libs/logical/q_res/chips/chips.prt';

PART_NAME
 R331 'Q_RES_0402LF-2.2K,5%,1/16W,EMPTY,CS22202JB07':;

SECTION_NUMBER 1
 '@T6G_MB_LIB.T6G(SCH_1):PAGE349_I129@PURE_QUANTA.Q_RES(CHIPS)':
 C_PATH='@t6g_mb_lib.t6g(sch_1):page349_i129@pure_quanta.q_res(chips)',
 P_PATH='@t6g_mb_lib.t6g(sch_1):page151_i129@pure_quanta.q_res(chips)',
 PATH='I129',
 DRAWING='@T6G_MB_LIB.T6G(SCH_1):PAGE349',
 WATTAGE='1/16W',
 TOLERANCE='5%',
 MATERIAL='EMPTY',
 PHYS_PAGE='151',
 XY='(4275,4125)',
 ROT='0',
 VER='1',
 PACK_TYPE='0402LF',
 LOCATION='R331',
 CDS_LIB='pure_quanta',
 CDS_PART_NAME='Q_RES_0402LF-2.2K,5%,1/16W,EMPTY,CS22202JB07',
 PART_NUMBER='CS22202JB07',
 VALUE='2.2K',
 PRIM_FILE='./archive_libs/logical/q_res/chips/chips.prt';

PART_NAME
 R332 'Q_RES_0402LF-2.2K,5%,1/16W,EMPTY,CS22202JB07':;

SECTION_NUMBER 1
 '@T6G_MB_LIB.T6G(SCH_1):PAGE349_I128@PURE_QUANTA.Q_RES(CHIPS)':
 C_PATH='@t6g_mb_lib.t6g(sch_1):page349_i128@pure_quanta.q_res(chips)',
 P_PATH='@t6g_mb_lib.t6g(sch_1):page151_i128@pure_quanta.q_res(chips)',
 PATH='I128',
 DRAWING='@T6G_MB_LIB.T6G(SCH_1):PAGE349',
 WATTAGE='1/16W',
 TOLERANCE='5%',
 MATERIAL='EMPTY',
 PHYS_PAGE='151',
 XY='(4275,3775)',
 ROT='0',
 VER='1',
 PACK_TYPE='0402LF',
 LOCATION='R332',
 CDS_LIB='pure_quanta',
 CDS_PART_NAME='Q_RES_0402LF-2.2K,5%,1/16W,EMPTY,CS22202JB07',
 PART_NUMBER='CS22202JB07',
 VALUE='2.2K',
 PRIM_FILE='./archive_libs/logical/q_res/chips/chips.prt';

PART_NAME
 R333 'Q_RES_0402LF-0,5%,1/16W,CHIP,CS00002JB13':;

SECTION_NUMBER 1
 '@T6G_MB_LIB.T6G(SCH_1):PAGE273_I4@PURE_QUANTA.Q_RES(CHIPS)':
 C_PATH='@t6g_mb_lib.t6g(sch_1):page273_i4@pure_quanta.q_res(chips)',
 P_PATH='@t6g_mb_lib.t6g(sch_1):page188_i4@pure_quanta.q_res(chips)',
 PATH='I4',
 DRAWING='@T6G_MB_LIB.T6G(SCH_1):PAGE273',
 BOM_COST='VR_SYSTEM ',
 WATTAGE='1/16W',
 TOLERANCE='5%',
 MATERIAL='CHIP',
 PHYS_PAGE='188',
 XY='(-6300,4950)',
 ROT='0',
 VER='1',
 PACK_TYPE='0402LF',
 LOCATION='R333',
 CDS_LIB='pure_quanta',
 CDS_PART_NAME='Q_RES_0402LF-0,5%,1/16W,CHIP,CS00002JB13',
 PART_NUMBER='CS00002JB13',
 VALUE='0',
 PRIM_FILE='./archive_libs/logical/q_res/chips/chips.prt';

PART_NAME
 R334 'Q_RES_0402LF-100K,1%,1/16W,CHIP,CS41002FB09':;

SECTION_NUMBER 1
 '@T6G_MB_LIB.T6G(SCH_1):PAGE273_I7@PURE_QUANTA.Q_RES(CHIPS)':
 C_PATH='@t6g_mb_lib.t6g(sch_1):page273_i7@pure_quanta.q_res(chips)',
 P_PATH='@t6g_mb_lib.t6g(sch_1):page188_i7@pure_quanta.q_res(chips)',
 PATH='I7',
 DRAWING='@T6G_MB_LIB.T6G(SCH_1):PAGE273',
 WATTAGE='1/16W',
 TOLERANCE='1%',
 MATERIAL='CHIP',
 PHYS_PAGE='188',
 XY='(-5775,4675)',
 ROT='0',
 VER='2',
 PACK_TYPE='0402LF',
 LOCATION='R334',
 CDS_LIB='pure_quanta',
 CDS_PART_NAME='Q_RES_0402LF-100K,1%,1/16W,CHIP,CS41002FB09',
 PART_NUMBER='CS41002FB09',
 VALUE='100K',
 PRIM_FILE='./archive_libs/logical/q_res/chips/chips.prt';

PART_NAME
 R335 'Q_RES_0402LF-10K,1%,1/16W,CHIP,CS31002FB08':
 REUSE_ID='3';

SECTION_NUMBER 1
 '@T6G_MB_LIB.T6G(SCH_1):PAGE273_I15@PURE_QUANTA.Q_RES(CHIPS)':
 C_PATH='@t6g_mb_lib.t6g(sch_1):page273_i15@pure_quanta.q_res(chips)',
 P_PATH='@t6g_mb_lib.t6g(sch_1):page188_i15@pure_quanta.q_res(chips)',
 PATH='I15',
 DRAWING='@T6G_MB_LIB.T6G(SCH_1):PAGE273',
 BOM_COST='VR_SYSTEM ',
 WATTAGE='1/16W',
 TOLERANCE='1%',
 MATERIAL='CHIP',
 PHYS_PAGE='188',
 XY='(-5575,6625)',
 ROT='0',
 VER='1',
 PACK_TYPE='0402LF',
 LOCATION='R335',
 CDS_LIB='pure_quanta',
 CDS_PART_NAME='Q_RES_0402LF-10K,1%,1/16W,CHIP,CS31002FB08',
 REUSE_ID='3',
 PART_NUMBER='CS31002FB08',
 VALUE='10K',
 PRIM_FILE='./archive_libs/logical/q_res/chips/chips.prt';

PART_NAME
 R336 'Q_RES_0402LF-100K,1%,1/16W,CHIP,CS41002FB09':
 REUSE_ID='1';

SECTION_NUMBER 1
 '@T6G_MB_LIB.T6G(SCH_1):PAGE273_I10@PURE_QUANTA.Q_RES(CHIPS)':
 C_PATH='@t6g_mb_lib.t6g(sch_1):page273_i10@pure_quanta.q_res(chips)',
 P_PATH='@t6g_mb_lib.t6g(sch_1):page188_i10@pure_quanta.q_res(chips)',
 PATH='I10',
 DRAWING='@T6G_MB_LIB.T6G(SCH_1):PAGE273',
 BOM_COST='VR_SYSTEM ',
 WATTAGE='1/16W',
 TOLERANCE='1%',
 MATERIAL='CHIP',
 PHYS_PAGE='188',
 XY='(-5125,5550)',
 ROT='0',
 VER='2',
 PACK_TYPE='0402LF',
 LOCATION='R336',
 CDS_LIB='pure_quanta',
 CDS_PART_NAME='Q_RES_0402LF-100K,1%,1/16W,CHIP,CS41002FB09',
 REUSE_ID='1',
 PART_NUMBER='CS41002FB09',
 VALUE='100K',
 PRIM_FILE='./archive_libs/logical/q_res/chips/chips.prt';

PART_NAME
 R337 'Q_RES_0402LF-0,5%,1/16W,CHIP,CS00002JB13':;

SECTION_NUMBER 1
 '@T6G_MB_LIB.T6G(SCH_1):PAGE138_I93@PURE_QUANTA.Q_RES(CHIPS)':
 C_PATH='@t6g_mb_lib.t6g(sch_1):page138_i93@pure_quanta.q_res(chips)',
 P_PATH='@t6g_mb_lib.t6g(sch_1):page161_i93@pure_quanta.q_res(chips)',
 PATH='I93',
 DRAWING='@T6G_MB_LIB.T6G(SCH_1):PAGE138',
 WATTAGE='1/16W',
 TOLERANCE='5%',
 MATERIAL='CHIP',
 PHYS_PAGE='161',
 XY='(5825,5350)',
 ROT='0',
 VER='1',
 PACK_TYPE='0402LF',
 LOCATION='R337',
 CDS_LIB='pure_quanta',
 CDS_PART_NAME='Q_RES_0402LF-0,5%,1/16W,CHIP,CS00002JB13',
 PART_NUMBER='CS00002JB13',
 VALUE='0',
 PRIM_FILE='./archive_libs/logical/q_res/chips/chips.prt';

PART_NAME
 R338 'Q_RES_0402LF-0,5%,1/16W,CHIP,CS00002JB13':;

SECTION_NUMBER 1
 '@T6G_MB_LIB.T6G(SCH_1):PAGE138_I94@PURE_QUANTA.Q_RES(CHIPS)':
 C_PATH='@t6g_mb_lib.t6g(sch_1):page138_i94@pure_quanta.q_res(chips)',
 P_PATH='@t6g_mb_lib.t6g(sch_1):page161_i94@pure_quanta.q_res(chips)',
 PATH='I94',
 DRAWING='@T6G_MB_LIB.T6G(SCH_1):PAGE138',
 WATTAGE='1/16W',
 TOLERANCE='5%',
 MATERIAL='CHIP',
 PHYS_PAGE='161',
 XY='(5825,5300)',
 ROT='0',
 VER='1',
 PACK_TYPE='0402LF',
 LOCATION='R338',
 CDS_LIB='pure_quanta',
 CDS_PART_NAME='Q_RES_0402LF-0,5%,1/16W,CHIP,CS00002JB13',
 PART_NUMBER='CS00002JB13',
 VALUE='0',
 PRIM_FILE='./archive_libs/logical/q_res/chips/chips.prt';

PART_NAME
 R339 'Q_RES_0201LF-49.9,1%,1/20W,EMPTY,CS04991FE06':;

SECTION_NUMBER 1
 '@T6G_MB_LIB.T6G(SCH_1):PAGE158_I120@PURE_QUANTA.Q_RES(CHIPS)':
 C_PATH='@t6g_mb_lib.t6g(sch_1):page158_i120@pure_quanta.q_res(chips)',
 P_PATH='@t6g_mb_lib.t6g(sch_1):page180_i120@pure_quanta.q_res(chips)',
 PATH='I120',
 DRAWING='@T6G_MB_LIB.T6G(SCH_1):PAGE158',
 WATTAGE='1/20W',
 TOLERANCE='1%',
 MATERIAL='EMPTY',
 PHYS_PAGE='180',
 XY='(-8750,5650)',
 ROT='2',
 VER='2',
 PACK_TYPE='0201LF',
 LOCATION='R339',
 CDS_LIB='pure_quanta',
 CDS_PART_NAME='Q_RES_0201LF-49.9,1%,1/20W,EMPTY,CS04991FE06',
 PART_NUMBER='CS04991FE06',
 VALUE='49.9',
 PRIM_FILE='./archive_libs/logical/q_res/chips/chips.prt';

PART_NAME
 R340 'Q_RES_0201LF-49.9,1%,1/20W,EMPTY,CS04991FE06':;

SECTION_NUMBER 1
 '@T6G_MB_LIB.T6G(SCH_1):PAGE158_I121@PURE_QUANTA.Q_RES(CHIPS)':
 C_PATH='@t6g_mb_lib.t6g(sch_1):page158_i121@pure_quanta.q_res(chips)',
 P_PATH='@t6g_mb_lib.t6g(sch_1):page180_i121@pure_quanta.q_res(chips)',
 PATH='I121',
 DRAWING='@T6G_MB_LIB.T6G(SCH_1):PAGE158',
 WATTAGE='1/20W',
 TOLERANCE='1%',
 MATERIAL='EMPTY',
 PHYS_PAGE='180',
 XY='(-8675,5650)',
 ROT='0',
 VER='2',
 PACK_TYPE='0201LF',
 LOCATION='R340',
 CDS_LIB='pure_quanta',
 CDS_PART_NAME='Q_RES_0201LF-49.9,1%,1/20W,EMPTY,CS04991FE06',
 PART_NUMBER='CS04991FE06',
 VALUE='49.9',
 PRIM_FILE='./archive_libs/logical/q_res/chips/chips.prt';

PART_NAME
 R341 'Q_RES_0402LF-51,5%,1/16W,EMPTY,CS05102JB04':;

SECTION_NUMBER 1
 '@T6G_MB_LIB.T6G(SCH_1):PAGE158_I145@PURE_QUANTA.Q_RES(CHIPS)':
 C_PATH='@t6g_mb_lib.t6g(sch_1):page158_i145@pure_quanta.q_res(chips)',
 P_PATH='@t6g_mb_lib.t6g(sch_1):page180_i145@pure_quanta.q_res(chips)',
 PATH='I145',
 DRAWING='@T6G_MB_LIB.T6G(SCH_1):PAGE158',
 WATTAGE='1/16W',
 TOLERANCE='5%',
 MATERIAL='EMPTY',
 PHYS_PAGE='180',
 XY='(-8650,4400)',
 ROT='2',
 VER='2',
 PACK_TYPE='0402LF',
 LOCATION='R341',
 CDS_LIB='pure_quanta',
 CDS_PART_NAME='Q_RES_0402LF-51,5%,1/16W,EMPTY,CS05102JB04',
 PART_NUMBER='CS05102JB04',
 VALUE='51',
 PRIM_FILE='./archive_libs/logical/q_res/chips/chips.prt';

PART_NAME
 R342 'Q_RES_0402LF-51,5%,1/16W,EMPTY,CS05102JB04':;

SECTION_NUMBER 1
 '@T6G_MB_LIB.T6G(SCH_1):PAGE158_I146@PURE_QUANTA.Q_RES(CHIPS)':
 C_PATH='@t6g_mb_lib.t6g(sch_1):page158_i146@pure_quanta.q_res(chips)',
 P_PATH='@t6g_mb_lib.t6g(sch_1):page180_i146@pure_quanta.q_res(chips)',
 PATH='I146',
 DRAWING='@T6G_MB_LIB.T6G(SCH_1):PAGE158',
 WATTAGE='1/16W',
 TOLERANCE='5%',
 MATERIAL='EMPTY',
 PHYS_PAGE='180',
 XY='(-8575,4425)',
 ROT='0',
 VER='2',
 PACK_TYPE='0402LF',
 LOCATION='R342',
 CDS_LIB='pure_quanta',
 CDS_PART_NAME='Q_RES_0402LF-51,5%,1/16W,EMPTY,CS05102JB04',
 PART_NUMBER='CS05102JB04',
 VALUE='51',
 PRIM_FILE='./archive_libs/logical/q_res/chips/chips.prt';

PART_NAME
 R343 'Q_RES_0201LF-49.9,1%,1/20W,EMPTY,CS04991FE06':;

SECTION_NUMBER 1
 '@T6G_MB_LIB.T6G(SCH_1):PAGE158_I125@PURE_QUANTA.Q_RES(CHIPS)':
 C_PATH='@t6g_mb_lib.t6g(sch_1):page158_i125@pure_quanta.q_res(chips)',
 P_PATH='@t6g_mb_lib.t6g(sch_1):page180_i125@pure_quanta.q_res(chips)',
 PATH='I125',
 DRAWING='@T6G_MB_LIB.T6G(SCH_1):PAGE158',
 WATTAGE='1/20W',
 TOLERANCE='1%',
 MATERIAL='EMPTY',
 PHYS_PAGE='180',
 XY='(-6150,5400)',
 ROT='2',
 VER='2',
 PACK_TYPE='0201LF',
 LOCATION='R343',
 CDS_LIB='pure_quanta',
 CDS_PART_NAME='Q_RES_0201LF-49.9,1%,1/20W,EMPTY,CS04991FE06',
 PART_NUMBER='CS04991FE06',
 VALUE='49.9',
 PRIM_FILE='./archive_libs/logical/q_res/chips/chips.prt';

PART_NAME
 R344 'Q_RES_0201LF-49.9,1%,1/20W,EMPTY,CS04991FE06':;

SECTION_NUMBER 1
 '@T6G_MB_LIB.T6G(SCH_1):PAGE158_I127@PURE_QUANTA.Q_RES(CHIPS)':
 C_PATH='@t6g_mb_lib.t6g(sch_1):page158_i127@pure_quanta.q_res(chips)',
 P_PATH='@t6g_mb_lib.t6g(sch_1):page180_i127@pure_quanta.q_res(chips)',
 PATH='I127',
 DRAWING='@T6G_MB_LIB.T6G(SCH_1):PAGE158',
 WATTAGE='1/20W',
 TOLERANCE='1%',
 MATERIAL='EMPTY',
 PHYS_PAGE='180',
 XY='(-6150,4050)',
 ROT='2',
 VER='2',
 PACK_TYPE='0201LF',
 LOCATION='R344',
 CDS_LIB='pure_quanta',
 CDS_PART_NAME='Q_RES_0201LF-49.9,1%,1/20W,EMPTY,CS04991FE06',
 PART_NUMBER='CS04991FE06',
 VALUE='49.9',
 PRIM_FILE='./archive_libs/logical/q_res/chips/chips.prt';

PART_NAME
 R345 'Q_RES_0201LF-49.9,1%,1/20W,EMPTY,CS04991FE06':;

SECTION_NUMBER 1
 '@T6G_MB_LIB.T6G(SCH_1):PAGE158_I124@PURE_QUANTA.Q_RES(CHIPS)':
 C_PATH='@t6g_mb_lib.t6g(sch_1):page158_i124@pure_quanta.q_res(chips)',
 P_PATH='@t6g_mb_lib.t6g(sch_1):page180_i124@pure_quanta.q_res(chips)',
 PATH='I124',
 DRAWING='@T6G_MB_LIB.T6G(SCH_1):PAGE158',
 WATTAGE='1/20W',
 TOLERANCE='1%',
 MATERIAL='EMPTY',
 PHYS_PAGE='180',
 XY='(-6075,5400)',
 ROT='0',
 VER='2',
 PACK_TYPE='0201LF',
 LOCATION='R345',
 CDS_LIB='pure_quanta',
 CDS_PART_NAME='Q_RES_0201LF-49.9,1%,1/20W,EMPTY,CS04991FE06',
 PART_NUMBER='CS04991FE06',
 VALUE='49.9',
 PRIM_FILE='./archive_libs/logical/q_res/chips/chips.prt';

PART_NAME
 R346 'Q_RES_0201LF-49.9,1%,1/20W,EMPTY,CS04991FE06':;

SECTION_NUMBER 1
 '@T6G_MB_LIB.T6G(SCH_1):PAGE158_I126@PURE_QUANTA.Q_RES(CHIPS)':
 C_PATH='@t6g_mb_lib.t6g(sch_1):page158_i126@pure_quanta.q_res(chips)',
 P_PATH='@t6g_mb_lib.t6g(sch_1):page180_i126@pure_quanta.q_res(chips)',
 PATH='I126',
 DRAWING='@T6G_MB_LIB.T6G(SCH_1):PAGE158',
 WATTAGE='1/20W',
 TOLERANCE='1%',
 MATERIAL='EMPTY',
 PHYS_PAGE='180',
 XY='(-6075,4050)',
 ROT='0',
 VER='2',
 PACK_TYPE='0201LF',
 LOCATION='R346',
 CDS_LIB='pure_quanta',
 CDS_PART_NAME='Q_RES_0201LF-49.9,1%,1/20W,EMPTY,CS04991FE06',
 PART_NUMBER='CS04991FE06',
 VALUE='49.9',
 PRIM_FILE='./archive_libs/logical/q_res/chips/chips.prt';

PART_NAME
 R347 'Q_RES_0402LF-33.2,1%,1/16W,CHIP,CS03322FB03':;

SECTION_NUMBER 1
 '@T6G_MB_LIB.T6G(SCH_1):PAGE349_I173@PURE_QUANTA.Q_RES(CHIPS)':
 C_PATH='@t6g_mb_lib.t6g(sch_1):page349_i173@pure_quanta.q_res(chips)',
 P_PATH='@t6g_mb_lib.t6g(sch_1):page151_i173@pure_quanta.q_res(chips)',
 PATH='I173',
 DRAWING='@T6G_MB_LIB.T6G(SCH_1):PAGE349',
 WATTAGE='1/16W',
 TOLERANCE='1%',
 MATERIAL='CHIP',
 PHYS_PAGE='151',
 XY='(2700,6600)',
 ROT='0',
 VER='1',
 PACK_TYPE='0402LF',
 LOCATION='R347',
 CDS_LIB='pure_quanta',
 CDS_PART_NAME='Q_RES_0402LF-33.2,1%,1/16W,CHIP,CS03322FB03',
 PART_NUMBER='CS03322FB03',
 VALUE='33.2',
 PRIM_FILE='./archive_libs/logical/q_res/chips/chips.prt';

PART_NAME
 R348 'Q_RES_0402LF-33.2,1%,1/16W,CHIP,CS03322FB03':;

SECTION_NUMBER 1
 '@T6G_MB_LIB.T6G(SCH_1):PAGE349_I172@PURE_QUANTA.Q_RES(CHIPS)':
 C_PATH='@t6g_mb_lib.t6g(sch_1):page349_i172@pure_quanta.q_res(chips)',
 P_PATH='@t6g_mb_lib.t6g(sch_1):page151_i172@pure_quanta.q_res(chips)',
 PATH='I172',
 DRAWING='@T6G_MB_LIB.T6G(SCH_1):PAGE349',
 WATTAGE='1/16W',
 TOLERANCE='1%',
 MATERIAL='CHIP',
 PHYS_PAGE='151',
 XY='(2700,6550)',
 ROT='0',
 VER='1',
 PACK_TYPE='0402LF',
 LOCATION='R348',
 CDS_LIB='pure_quanta',
 CDS_PART_NAME='Q_RES_0402LF-33.2,1%,1/16W,CHIP,CS03322FB03',
 PART_NUMBER='CS03322FB03',
 VALUE='33.2',
 PRIM_FILE='./archive_libs/logical/q_res/chips/chips.prt';

PART_NAME
 R349 'Q_RES_0402LF-33,5%,1/16W,CHIP,CS03302JB10':;

SECTION_NUMBER 1
 '@T6G_MB_LIB.T6G(SCH_1):PAGE349_I185@PURE_QUANTA.Q_RES(CHIPS)':
 C_PATH='@t6g_mb_lib.t6g(sch_1):page349_i185@pure_quanta.q_res(chips)',
 P_PATH='@t6g_mb_lib.t6g(sch_1):page151_i185@pure_quanta.q_res(chips)',
 PATH='I185',
 DRAWING='@T6G_MB_LIB.T6G(SCH_1):PAGE349',
 WATTAGE='1/16W',
 TOLERANCE='5%',
 MATERIAL='CHIP',
 PHYS_PAGE='151',
 XY='(1500,1525)',
 ROT='0',
 VER='1',
 PACK_TYPE='0402LF',
 LOCATION='R349',
 CDS_LIB='pure_quanta',
 CDS_PART_NAME='Q_RES_0402LF-33,5%,1/16W,CHIP,CS03302JB10',
 PART_NUMBER='CS03302JB10',
 VALUE='33',
 PRIM_FILE='./archive_libs/logical/q_res/chips/chips.prt';

PART_NAME
 R350 'Q_RES_0402LF-33,5%,1/16W,CHIP,CS03302JB10':;

SECTION_NUMBER 1
 '@T6G_MB_LIB.T6G(SCH_1):PAGE349_I184@PURE_QUANTA.Q_RES(CHIPS)':
 C_PATH='@t6g_mb_lib.t6g(sch_1):page349_i184@pure_quanta.q_res(chips)',
 P_PATH='@t6g_mb_lib.t6g(sch_1):page151_i184@pure_quanta.q_res(chips)',
 PATH='I184',
 DRAWING='@T6G_MB_LIB.T6G(SCH_1):PAGE349',
 WATTAGE='1/16W',
 TOLERANCE='5%',
 MATERIAL='CHIP',
 PHYS_PAGE='151',
 XY='(1500,1425)',
 ROT='0',
 VER='1',
 PACK_TYPE='0402LF',
 LOCATION='R350',
 CDS_LIB='pure_quanta',
 CDS_PART_NAME='Q_RES_0402LF-33,5%,1/16W,CHIP,CS03302JB10',
 PART_NUMBER='CS03302JB10',
 VALUE='33',
 PRIM_FILE='./archive_libs/logical/q_res/chips/chips.prt';

PART_NAME
 R351 'Q_RES_0402LF-33,5%,1/16W,CHIP,CS03302JB10':;

SECTION_NUMBER 1
 '@T6G_MB_LIB.T6G(SCH_1):PAGE349_I187@PURE_QUANTA.Q_RES(CHIPS)':
 C_PATH='@t6g_mb_lib.t6g(sch_1):page349_i187@pure_quanta.q_res(chips)',
 P_PATH='@t6g_mb_lib.t6g(sch_1):page151_i187@pure_quanta.q_res(chips)',
 PATH='I187',
 DRAWING='@T6G_MB_LIB.T6G(SCH_1):PAGE349',
 WATTAGE='1/16W',
 TOLERANCE='5%',
 MATERIAL='CHIP',
 PHYS_PAGE='151',
 XY='(2075,1125)',
 ROT='0',
 VER='1',
 PACK_TYPE='0402LF',
 LOCATION='R351',
 CDS_LIB='pure_quanta',
 CDS_PART_NAME='Q_RES_0402LF-33,5%,1/16W,CHIP,CS03302JB10',
 PART_NUMBER='CS03302JB10',
 VALUE='33',
 PRIM_FILE='./archive_libs/logical/q_res/chips/chips.prt';

PART_NAME
 R352 'Q_RES_0402LF-33,5%,1/16W,CHIP,CS03302JB10':;

SECTION_NUMBER 1
 '@T6G_MB_LIB.T6G(SCH_1):PAGE349_I186@PURE_QUANTA.Q_RES(CHIPS)':
 C_PATH='@t6g_mb_lib.t6g(sch_1):page349_i186@pure_quanta.q_res(chips)',
 P_PATH='@t6g_mb_lib.t6g(sch_1):page151_i186@pure_quanta.q_res(chips)',
 PATH='I186',
 DRAWING='@T6G_MB_LIB.T6G(SCH_1):PAGE349',
 WATTAGE='1/16W',
 TOLERANCE='5%',
 MATERIAL='CHIP',
 PHYS_PAGE='151',
 XY='(2075,1025)',
 ROT='0',
 VER='1',
 PACK_TYPE='0402LF',
 LOCATION='R352',
 CDS_LIB='pure_quanta',
 CDS_PART_NAME='Q_RES_0402LF-33,5%,1/16W,CHIP,CS03302JB10',
 PART_NUMBER='CS03302JB10',
 VALUE='33',
 PRIM_FILE='./archive_libs/logical/q_res/chips/chips.prt';

PART_NAME
 R353 'Q_RES_0402LF-0,5%,1/16W,CHIP,CS00002JB13':
 ROOM='HSC BOM2';

SECTION_NUMBER 1
 '@T6G_MB_LIB.T6G(SCH_1):PAGE371_I74@PURE_QUANTA.Q_RES(CHIPS)':
 C_PATH='@t6g_mb_lib.t6g(sch_1):page371_i74@pure_quanta.q_res(chips)',
 P_PATH='@t6g_mb_lib.t6g(sch_1):page267_i74@pure_quanta.q_res(chips)',
 PATH='I74',
 DRAWING='@T6G_MB_LIB.T6G(SCH_1):PAGE371',
 WATTAGE='1/16W',
 TOLERANCE='5%',
 MATERIAL='CHIP',
 PHYS_PAGE='267',
 XY='(-3500,1250)',
 ROT='0',
 VER='1',
 PACK_TYPE='0402LF',
 LOCATION='R353',
 CDS_LIB='pure_quanta',
 CDS_PART_NAME='Q_RES_0402LF-0,5%,1/16W,CHIP,CS00002JB13',
 ROOM='HSC BOM2',
 PART_NUMBER='CS00002JB13',
 VALUE='0',
 PRIM_FILE='./archive_libs/logical/q_res/chips/chips.prt';

PART_NAME
 R354 'Q_RES_0402LF-10.5K,1%,1/16W,CHIP,CS31052FB03':
 ROOM='HSC BOM2';

SECTION_NUMBER 1
 '@T6G_MB_LIB.T6G(SCH_1):PAGE371_I76@PURE_QUANTA.Q_RES(CHIPS)':
 C_PATH='@t6g_mb_lib.t6g(sch_1):page371_i76@pure_quanta.q_res(chips)',
 P_PATH='@t6g_mb_lib.t6g(sch_1):page267_i76@pure_quanta.q_res(chips)',
 PATH='I76',
 DRAWING='@T6G_MB_LIB.T6G(SCH_1):PAGE371',
 WATTAGE='1/16W',
 TOLERANCE='1%',
 MATERIAL='CHIP',
 PHYS_PAGE='267',
 XY='(-2275,1600)',
 ROT='0',
 VER='2',
 PACK_TYPE='0402LF',
 LOCATION='R354',
 CDS_LIB='pure_quanta',
 CDS_PART_NAME='Q_RES_0402LF-10.5K,1%,1/16W,CHIP,CS31052FB03',
 ROOM='HSC BOM2',
 PART_NUMBER='CS31052FB03',
 VALUE='10.5K',
 PRIM_FILE='./archive_libs/logical/q_res/chips/chips.prt';

PART_NAME
 R355 'Q_RES_0402LF-10.5K,1%,1/16W,CHIP,CS31052FB03':
 ROOM='HSC BOM2';

SECTION_NUMBER 1
 '@T6G_MB_LIB.T6G(SCH_1):PAGE371_I79@PURE_QUANTA.Q_RES(CHIPS)':
 C_PATH='@t6g_mb_lib.t6g(sch_1):page371_i79@pure_quanta.q_res(chips)',
 P_PATH='@t6g_mb_lib.t6g(sch_1):page267_i79@pure_quanta.q_res(chips)',
 PATH='I79',
 DRAWING='@T6G_MB_LIB.T6G(SCH_1):PAGE371',
 WATTAGE='1/16W',
 TOLERANCE='1%',
 MATERIAL='CHIP',
 PHYS_PAGE='267',
 XY='(-2125,2600)',
 ROT='2',
 VER='2',
 PACK_TYPE='0402LF',
 LOCATION='R355',
 CDS_LIB='pure_quanta',
 CDS_PART_NAME='Q_RES_0402LF-10.5K,1%,1/16W,CHIP,CS31052FB03',
 ROOM='HSC BOM2',
 PART_NUMBER='CS31052FB03',
 VALUE='10.5K',
 PRIM_FILE='./archive_libs/logical/q_res/chips/chips.prt';

PART_NAME
 R356 'Q_RES_0402LF-0,5%,1/16W,CHIP,CS00002JB13':;

SECTION_NUMBER 1
 '@T6G_MB_LIB.T6G(SCH_1):PAGE27_I349@PURE_QUANTA.Q_RES(CHIPS)':
 C_PATH='@t6g_mb_lib.t6g(sch_1):page27_i349@pure_quanta.q_res(chips)',
 P_PATH='@t6g_mb_lib.t6g(sch_1):page27_i349@pure_quanta.q_res(chips)',
 PATH='I349',
 DRAWING='@T6G_MB_LIB.T6G(SCH_1):PAGE27',
 WATTAGE='1/16W',
 TOLERANCE='5%',
 MATERIAL='CHIP',
 PHYS_PAGE='27',
 XY='(-2725,4475)',
 ROT='0',
 VER='1',
 PACK_TYPE='0402LF',
 LOCATION='R356',
 CDS_LIB='pure_quanta',
 CDS_PART_NAME='Q_RES_0402LF-0,5%,1/16W,CHIP,CS00002JB13',
 PART_NUMBER='CS00002JB13',
 VALUE='0',
 PRIM_FILE='./archive_libs/logical/q_res/chips/chips.prt';

PART_NAME
 R357 'Q_RES_0402LF-0,5%,1/16W,CHIP,CS00002JB13':;

SECTION_NUMBER 1
 '@T6G_MB_LIB.T6G(SCH_1):PAGE27_I348@PURE_QUANTA.Q_RES(CHIPS)':
 C_PATH='@t6g_mb_lib.t6g(sch_1):page27_i348@pure_quanta.q_res(chips)',
 P_PATH='@t6g_mb_lib.t6g(sch_1):page27_i348@pure_quanta.q_res(chips)',
 PATH='I348',
 DRAWING='@T6G_MB_LIB.T6G(SCH_1):PAGE27',
 WATTAGE='1/16W',
 TOLERANCE='5%',
 MATERIAL='CHIP',
 PHYS_PAGE='27',
 XY='(-2725,4425)',
 ROT='0',
 VER='1',
 PACK_TYPE='0402LF',
 LOCATION='R357',
 CDS_LIB='pure_quanta',
 CDS_PART_NAME='Q_RES_0402LF-0,5%,1/16W,CHIP,CS00002JB13',
 PART_NUMBER='CS00002JB13',
 VALUE='0',
 PRIM_FILE='./archive_libs/logical/q_res/chips/chips.prt';

PART_NAME
 R358 'Q_RES_0402LF-0,5%,1/16W,EMPTY,CS00002JB13':;

SECTION_NUMBER 1
 '@T6G_MB_LIB.T6G(SCH_1):PAGE138_I5@PURE_QUANTA.Q_RES(CHIPS)':
 C_PATH='@t6g_mb_lib.t6g(sch_1):page138_i5@pure_quanta.q_res(chips)',
 P_PATH='@t6g_mb_lib.t6g(sch_1):page161_i5@pure_quanta.q_res(chips)',
 PATH='I5',
 DRAWING='@T6G_MB_LIB.T6G(SCH_1):PAGE138',
 WATTAGE='1/16W',
 TOLERANCE='5%',
 MATERIAL='EMPTY',
 PHYS_PAGE='161',
 XY='(1725,1025)',
 ROT='0',
 VER='1',
 PACK_TYPE='0402LF',
 LOCATION='R358',
 CDS_LIB='pure_quanta',
 CDS_PART_NAME='Q_RES_0402LF-0,5%,1/16W,EMPTY,CS00002JB13',
 PART_NUMBER='CS00002JB13',
 VALUE='0',
 PRIM_FILE='./archive_libs/logical/q_res/chips/chips.prt';

PART_NAME
 R359 'Q_RES_0402LF-1K,1%,1/16W,CHIP,CS21002FB06':;

SECTION_NUMBER 1
 '@T6G_MB_LIB.T6G(SCH_1):PAGE138_I52@PURE_QUANTA.Q_RES(CHIPS)':
 C_PATH='@t6g_mb_lib.t6g(sch_1):page138_i52@pure_quanta.q_res(chips)',
 P_PATH='@t6g_mb_lib.t6g(sch_1):page161_i52@pure_quanta.q_res(chips)',
 PATH='I52',
 DRAWING='@T6G_MB_LIB.T6G(SCH_1):PAGE138',
 WATTAGE='1/16W',
 TOLERANCE='1%',
 MATERIAL='CHIP',
 PHYS_PAGE='161',
 XY='(5900,2725)',
 ROT='0',
 VER='2',
 PACK_TYPE='0402LF',
 LOCATION='R359',
 CDS_LIB='pure_quanta',
 CDS_PART_NAME='Q_RES_0402LF-1K,1%,1/16W,CHIP,CS21002FB06',
 PART_NUMBER='CS21002FB06',
 VALUE='1K',
 PRIM_FILE='./archive_libs/logical/q_res/chips/chips.prt';

PART_NAME
 R360 'Q_RES_0402LF-1K,1%,1/16W,CHIP,CS21002FB06':;

SECTION_NUMBER 1
 '@T6G_MB_LIB.T6G(SCH_1):PAGE138_I55@PURE_QUANTA.Q_RES(CHIPS)':
 C_PATH='@t6g_mb_lib.t6g(sch_1):page138_i55@pure_quanta.q_res(chips)',
 P_PATH='@t6g_mb_lib.t6g(sch_1):page161_i55@pure_quanta.q_res(chips)',
 PATH='I55',
 DRAWING='@T6G_MB_LIB.T6G(SCH_1):PAGE138',
 WATTAGE='1/16W',
 TOLERANCE='1%',
 MATERIAL='CHIP',
 PHYS_PAGE='161',
 XY='(5925,3650)',
 ROT='0',
 VER='2',
 PACK_TYPE='0402LF',
 LOCATION='R360',
 CDS_LIB='pure_quanta',
 CDS_PART_NAME='Q_RES_0402LF-1K,1%,1/16W,CHIP,CS21002FB06',
 PART_NUMBER='CS21002FB06',
 VALUE='1K',
 PRIM_FILE='./archive_libs/logical/q_res/chips/chips.prt';

PART_NAME
 R361 'Q_RES_0402LF-4.7K,5%,1/16W,EMPTY,CS24702JB10':;

SECTION_NUMBER 1
 '@T6G_MB_LIB.T6G(SCH_1):PAGE137_I40@PURE_QUANTA.Q_RES(CHIPS)':
 C_PATH='@t6g_mb_lib.t6g(sch_1):page137_i40@pure_quanta.q_res(chips)',
 P_PATH='@t6g_mb_lib.t6g(sch_1):page160_i40@pure_quanta.q_res(chips)',
 PATH='I40',
 DRAWING='@T6G_MB_LIB.T6G(SCH_1):PAGE137',
 WATTAGE='1/16W',
 TOLERANCE='5%',
 MATERIAL='EMPTY',
 PHYS_PAGE='160',
 XY='(-1550,-150)',
 ROT='0',
 VER='2',
 PACK_TYPE='0402LF',
 LOCATION='R361',
 CDS_LIB='pure_quanta',
 CDS_PART_NAME='Q_RES_0402LF-4.7K,5%,1/16W,EMPTY,CS24702JB10',
 PART_NUMBER='CS24702JB10',
 VALUE='4.7K',
 PRIM_FILE='./archive_libs/logical/q_res/chips/chips.prt';

PART_NAME
 R362 'Q_RES_0402LF-1K,1%,1/16W,CHIP,CS21002FB06':;

SECTION_NUMBER 1
 '@T6G_MB_LIB.T6G(SCH_1):PAGE138_I53@PURE_QUANTA.Q_RES(CHIPS)':
 C_PATH='@t6g_mb_lib.t6g(sch_1):page138_i53@pure_quanta.q_res(chips)',
 P_PATH='@t6g_mb_lib.t6g(sch_1):page161_i53@pure_quanta.q_res(chips)',
 PATH='I53',
 DRAWING='@T6G_MB_LIB.T6G(SCH_1):PAGE138',
 WATTAGE='1/16W',
 TOLERANCE='1%',
 MATERIAL='CHIP',
 PHYS_PAGE='161',
 XY='(6225,2725)',
 ROT='0',
 VER='2',
 PACK_TYPE='0402LF',
 LOCATION='R362',
 CDS_LIB='pure_quanta',
 CDS_PART_NAME='Q_RES_0402LF-1K,1%,1/16W,CHIP,CS21002FB06',
 PART_NUMBER='CS21002FB06',
 VALUE='1K',
 PRIM_FILE='./archive_libs/logical/q_res/chips/chips.prt';

PART_NAME
 R363 'Q_RES_0402LF-1K,1%,1/16W,CHIP,CS21002FB06':;

SECTION_NUMBER 1
 '@T6G_MB_LIB.T6G(SCH_1):PAGE138_I56@PURE_QUANTA.Q_RES(CHIPS)':
 C_PATH='@t6g_mb_lib.t6g(sch_1):page138_i56@pure_quanta.q_res(chips)',
 P_PATH='@t6g_mb_lib.t6g(sch_1):page161_i56@pure_quanta.q_res(chips)',
 PATH='I56',
 DRAWING='@T6G_MB_LIB.T6G(SCH_1):PAGE138',
 WATTAGE='1/16W',
 TOLERANCE='1%',
 MATERIAL='CHIP',
 PHYS_PAGE='161',
 XY='(6250,3650)',
 ROT='0',
 VER='2',
 PACK_TYPE='0402LF',
 LOCATION='R363',
 CDS_LIB='pure_quanta',
 CDS_PART_NAME='Q_RES_0402LF-1K,1%,1/16W,CHIP,CS21002FB06',
 PART_NUMBER='CS21002FB06',
 VALUE='1K',
 PRIM_FILE='./archive_libs/logical/q_res/chips/chips.prt';

PART_NAME
 R364 'Q_RES_0402LF-0,5%,1/16W,CHIP,CS00002JB13':;

SECTION_NUMBER 1
 '@T6G_MB_LIB.T6G(SCH_1):PAGE349_I231@PURE_QUANTA.Q_RES(CHIPS)':
 C_PATH='@t6g_mb_lib.t6g(sch_1):page349_i231@pure_quanta.q_res(chips)',
 P_PATH='@t6g_mb_lib.t6g(sch_1):page151_i231@pure_quanta.q_res(chips)',
 PATH='I231',
 DRAWING='@T6G_MB_LIB.T6G(SCH_1):PAGE349',
 SEC_TYPE='0402LF',
 WATTAGE='1/16W',
 TOLERANCE='5%',
 MATERIAL='CHIP',
 PHYS_PAGE='151',
 XY='(-1475,6375)',
 ROT='0',
 VER='1',
 PACK_TYPE='0402LF',
 LOCATION='R364',
 SEC='1',
 CDS_LIB='pure_quanta',
 CDS_PART_NAME='Q_RES_0402LF-0,5%,1/16W,CHIP,CS00002JB13',
 PART_NUMBER='CS00002JB13',
 VALUE='0',
 PRIM_FILE='./archive_libs/logical/q_res/chips/chips.prt';

PART_NAME
 R365 'Q_RES_0402LF-4.7K,5%,1/16W,EMPTY,CS24702JB10':;

SECTION_NUMBER 1
 '@T6G_MB_LIB.T6G(SCH_1):PAGE137_I41@PURE_QUANTA.Q_RES(CHIPS)':
 C_PATH='@t6g_mb_lib.t6g(sch_1):page137_i41@pure_quanta.q_res(chips)',
 P_PATH='@t6g_mb_lib.t6g(sch_1):page160_i41@pure_quanta.q_res(chips)',
 PATH='I41',
 DRAWING='@T6G_MB_LIB.T6G(SCH_1):PAGE137',
 WATTAGE='1/16W',
 TOLERANCE='5%',
 MATERIAL='EMPTY',
 PHYS_PAGE='160',
 XY='(-1225,-150)',
 ROT='0',
 VER='2',
 PACK_TYPE='0402LF',
 LOCATION='R365',
 CDS_LIB='pure_quanta',
 CDS_PART_NAME='Q_RES_0402LF-4.7K,5%,1/16W,EMPTY,CS24702JB10',
 PART_NUMBER='CS24702JB10',
 VALUE='4.7K',
 PRIM_FILE='./archive_libs/logical/q_res/chips/chips.prt';

PART_NAME
 R366 'Q_RES_0402LF-1K,1%,1/16W,CHIP,CS21002FB06':;

SECTION_NUMBER 1
 '@T6G_MB_LIB.T6G(SCH_1):PAGE138_I54@PURE_QUANTA.Q_RES(CHIPS)':
 C_PATH='@t6g_mb_lib.t6g(sch_1):page138_i54@pure_quanta.q_res(chips)',
 P_PATH='@t6g_mb_lib.t6g(sch_1):page161_i54@pure_quanta.q_res(chips)',
 PATH='I54',
 DRAWING='@T6G_MB_LIB.T6G(SCH_1):PAGE138',
 WATTAGE='1/16W',
 TOLERANCE='1%',
 MATERIAL='CHIP',
 PHYS_PAGE='161',
 XY='(6525,2725)',
 ROT='0',
 VER='2',
 PACK_TYPE='0402LF',
 LOCATION='R366',
 CDS_LIB='pure_quanta',
 CDS_PART_NAME='Q_RES_0402LF-1K,1%,1/16W,CHIP,CS21002FB06',
 PART_NUMBER='CS21002FB06',
 VALUE='1K',
 PRIM_FILE='./archive_libs/logical/q_res/chips/chips.prt';

PART_NAME
 R367 'Q_RES_0402LF-1K,1%,1/16W,CHIP,CS21002FB06':;

SECTION_NUMBER 1
 '@T6G_MB_LIB.T6G(SCH_1):PAGE138_I57@PURE_QUANTA.Q_RES(CHIPS)':
 C_PATH='@t6g_mb_lib.t6g(sch_1):page138_i57@pure_quanta.q_res(chips)',
 P_PATH='@t6g_mb_lib.t6g(sch_1):page161_i57@pure_quanta.q_res(chips)',
 PATH='I57',
 DRAWING='@T6G_MB_LIB.T6G(SCH_1):PAGE138',
 WATTAGE='1/16W',
 TOLERANCE='1%',
 MATERIAL='CHIP',
 PHYS_PAGE='161',
 XY='(6550,3650)',
 ROT='0',
 VER='2',
 PACK_TYPE='0402LF',
 LOCATION='R367',
 CDS_LIB='pure_quanta',
 CDS_PART_NAME='Q_RES_0402LF-1K,1%,1/16W,CHIP,CS21002FB06',
 PART_NUMBER='CS21002FB06',
 VALUE='1K',
 PRIM_FILE='./archive_libs/logical/q_res/chips/chips.prt';

PART_NAME
 R368 'Q_RES_0402LF-4.7K,5%,1/16W,EMPTY,CS24702JB10':;

SECTION_NUMBER 1
 '@T6G_MB_LIB.T6G(SCH_1):PAGE137_I44@PURE_QUANTA.Q_RES(CHIPS)':
 C_PATH='@t6g_mb_lib.t6g(sch_1):page137_i44@pure_quanta.q_res(chips)',
 P_PATH='@t6g_mb_lib.t6g(sch_1):page160_i44@pure_quanta.q_res(chips)',
 PATH='I44',
 DRAWING='@T6G_MB_LIB.T6G(SCH_1):PAGE137',
 WATTAGE='1/16W',
 TOLERANCE='5%',
 MATERIAL='EMPTY',
 PHYS_PAGE='160',
 XY='(-925,-150)',
 ROT='0',
 VER='2',
 PACK_TYPE='0402LF',
 LOCATION='R368',
 CDS_LIB='pure_quanta',
 CDS_PART_NAME='Q_RES_0402LF-4.7K,5%,1/16W,EMPTY,CS24702JB10',
 PART_NUMBER='CS24702JB10',
 VALUE='4.7K',
 PRIM_FILE='./archive_libs/logical/q_res/chips/chips.prt';

PART_NAME
 R369 'Q_RES_0402LF-1K,1%,1/16W,CHIP,CS21002FB06':;

SECTION_NUMBER 1
 '@T6G_MB_LIB.T6G(SCH_1):PAGE138_I58@PURE_QUANTA.Q_RES(CHIPS)':
 C_PATH='@t6g_mb_lib.t6g(sch_1):page138_i58@pure_quanta.q_res(chips)',
 P_PATH='@t6g_mb_lib.t6g(sch_1):page161_i58@pure_quanta.q_res(chips)',
 PATH='I58',
 DRAWING='@T6G_MB_LIB.T6G(SCH_1):PAGE138',
 WATTAGE='1/16W',
 TOLERANCE='1%',
 MATERIAL='CHIP',
 PHYS_PAGE='161',
 XY='(6850,2725)',
 ROT='0',
 VER='2',
 PACK_TYPE='0402LF',
 LOCATION='R369',
 CDS_LIB='pure_quanta',
 CDS_PART_NAME='Q_RES_0402LF-1K,1%,1/16W,CHIP,CS21002FB06',
 PART_NUMBER='CS21002FB06',
 VALUE='1K',
 PRIM_FILE='./archive_libs/logical/q_res/chips/chips.prt';

PART_NAME
 R370 'Q_RES_0402LF-1K,1%,1/16W,CHIP,CS21002FB06':;

SECTION_NUMBER 1
 '@T6G_MB_LIB.T6G(SCH_1):PAGE138_I60@PURE_QUANTA.Q_RES(CHIPS)':
 C_PATH='@t6g_mb_lib.t6g(sch_1):page138_i60@pure_quanta.q_res(chips)',
 P_PATH='@t6g_mb_lib.t6g(sch_1):page161_i60@pure_quanta.q_res(chips)',
 PATH='I60',
 DRAWING='@T6G_MB_LIB.T6G(SCH_1):PAGE138',
 WATTAGE='1/16W',
 TOLERANCE='1%',
 MATERIAL='CHIP',
 PHYS_PAGE='161',
 XY='(6875,3650)',
 ROT='0',
 VER='2',
 PACK_TYPE='0402LF',
 LOCATION='R370',
 CDS_LIB='pure_quanta',
 CDS_PART_NAME='Q_RES_0402LF-1K,1%,1/16W,CHIP,CS21002FB06',
 PART_NUMBER='CS21002FB06',
 VALUE='1K',
 PRIM_FILE='./archive_libs/logical/q_res/chips/chips.prt';

PART_NAME
 R371 'Q_RES_0402LF-33,5%,1/16W,CHIP,CS03302JB10':;

SECTION_NUMBER 1
 '@T6G_MB_LIB.T6G(SCH_1):PAGE80_I107@PURE_QUANTA.Q_RES(CHIPS)':
 C_PATH='@t6g_mb_lib.t6g(sch_1):page80_i107@pure_quanta.q_res(chips)',
 P_PATH='@t6g_mb_lib.t6g(sch_1):page81_i107@pure_quanta.q_res(chips)',
 PATH='I107',
 DRAWING='@T6G_MB_LIB.T6G(SCH_1):PAGE80',
 BOM_COST='MEM',
 WATTAGE='1/16W',
 TOLERANCE='5%',
 MATERIAL='CHIP',
 PHYS_PAGE='81',
 XY='(-6425,4725)',
 ROT='0',
 VER='1',
 PACK_TYPE='0402LF',
 LOCATION='R371',
 CDS_LIB='pure_quanta',
 CDS_PART_NAME='Q_RES_0402LF-33,5%,1/16W,CHIP,CS03302JB10',
 PART_NUMBER='CS03302JB10',
 VALUE='33',
 PRIM_FILE='./archive_libs/logical/q_res/chips/chips.prt';

PART_NAME
 R372 'Q_RES_0402LF-33,5%,1/16W,CHIP,CS03302JB10':;

SECTION_NUMBER 1
 '@T6G_MB_LIB.T6G(SCH_1):PAGE80_I159@PURE_QUANTA.Q_RES(CHIPS)':
 C_PATH='@t6g_mb_lib.t6g(sch_1):page80_i159@pure_quanta.q_res(chips)',
 P_PATH='@t6g_mb_lib.t6g(sch_1):page81_i159@pure_quanta.q_res(chips)',
 PATH='I159',
 DRAWING='@T6G_MB_LIB.T6G(SCH_1):PAGE80',
 BOM_COST='MEM',
 WATTAGE='1/16W',
 TOLERANCE='5%',
 MATERIAL='CHIP',
 PHYS_PAGE='81',
 XY='(-3225,4475)',
 ROT='0',
 VER='1',
 PACK_TYPE='0402LF',
 LOCATION='R372',
 CDS_LIB='pure_quanta',
 CDS_PART_NAME='Q_RES_0402LF-33,5%,1/16W,CHIP,CS03302JB10',
 PART_NUMBER='CS03302JB10',
 VALUE='33',
 PRIM_FILE='./archive_libs/logical/q_res/chips/chips.prt';

PART_NAME
 R373 'Q_RES_0402LF-0,5%,1/16W,EMPTY,CS00002JB13':;

SECTION_NUMBER 1
 '@T6G_MB_LIB.T6G(SCH_1):PAGE57_I52@PURE_QUANTA.Q_RES(CHIPS)':
 C_PATH='@t6g_mb_lib.t6g(sch_1):page57_i52@pure_quanta.q_res(chips)',
 P_PATH='@t6g_mb_lib.t6g(sch_1):page57_i52@pure_quanta.q_res(chips)',
 PATH='I52',
 DRAWING='@T6G_MB_LIB.T6G(SCH_1):PAGE57',
 BOM_COST='MEM',
 WATTAGE='1/16W',
 TOLERANCE='5%',
 MATERIAL='EMPTY',
 PHYS_PAGE='57',
 XY='(-1450,725)',
 ROT='0',
 VER='2',
 PACK_TYPE='0402LF',
 LOCATION='R373',
 CDS_LIB='pure_quanta',
 CDS_PART_NAME='Q_RES_0402LF-0,5%,1/16W,EMPTY,CS00002JB13',
 PART_NUMBER='CS00002JB13',
 VALUE='0',
 PRIM_FILE='./archive_libs/logical/q_res/chips/chips.prt';

PART_NAME
 R374 'Q_RES_0402LF-0,5%,1/16W,CHIP,CS00002JB13':;

SECTION_NUMBER 1
 '@T6G_MB_LIB.T6G(SCH_1):PAGE57_I51@PURE_QUANTA.Q_RES(CHIPS)':
 C_PATH='@t6g_mb_lib.t6g(sch_1):page57_i51@pure_quanta.q_res(chips)',
 P_PATH='@t6g_mb_lib.t6g(sch_1):page57_i51@pure_quanta.q_res(chips)',
 PATH='I51',
 DRAWING='@T6G_MB_LIB.T6G(SCH_1):PAGE57',
 BOM_COST='MEM',
 WATTAGE='1/16W',
 TOLERANCE='5%',
 MATERIAL='CHIP',
 PHYS_PAGE='57',
 XY='(-1125,725)',
 ROT='0',
 VER='2',
 PACK_TYPE='0402LF',
 LOCATION='R374',
 CDS_LIB='pure_quanta',
 CDS_PART_NAME='Q_RES_0402LF-0,5%,1/16W,CHIP,CS00002JB13',
 PART_NUMBER='CS00002JB13',
 VALUE='0',
 PRIM_FILE='./archive_libs/logical/q_res/chips/chips.prt';

PART_NAME
 R375 'Q_RES_0402LF-15,1%,1/16W,CHIP,CS01502FB03':;

SECTION_NUMBER 1
 '@T6G_MB_LIB.T6G(SCH_1):PAGE10_I837@PURE_QUANTA.Q_RES(CHIPS)':
 C_PATH='@t6g_mb_lib.t6g(sch_1):page10_i837@pure_quanta.q_res(chips)',
 P_PATH='@t6g_mb_lib.t6g(sch_1):page10_i837@pure_quanta.q_res(chips)',
 PATH='I837',
 DRAWING='@T6G_MB_LIB.T6G(SCH_1):PAGE10',
 WATTAGE='1/16W',
 TOLERANCE='1%',
 MATERIAL='CHIP',
 PHYS_PAGE='10',
 XY='(-6600,2250)',
 ROT='0',
 VER='1',
 PACK_TYPE='0402LF',
 LOCATION='R375',
 CDS_LIB='pure_quanta',
 CDS_PART_NAME='Q_RES_0402LF-15,1%,1/16W,CHIP,CS01502FB03',
 PART_NUMBER='CS01502FB03',
 VALUE='15',
 PRIM_FILE='./archive_libs/logical/q_res/chips/chips.prt';

PART_NAME
 R376 'Q_RES_0402LF-15,1%,1/16W,CHIP,CS01502FB03':;

SECTION_NUMBER 1
 '@T6G_MB_LIB.T6G(SCH_1):PAGE11_I327@PURE_QUANTA.Q_RES(CHIPS)':
 C_PATH='@t6g_mb_lib.t6g(sch_1):page11_i327@pure_quanta.q_res(chips)',
 P_PATH='@t6g_mb_lib.t6g(sch_1):page11_i327@pure_quanta.q_res(chips)',
 PATH='I327',
 DRAWING='@T6G_MB_LIB.T6G(SCH_1):PAGE11',
 WATTAGE='1/16W',
 TOLERANCE='1%',
 MATERIAL='CHIP',
 PHYS_PAGE='11',
 XY='(-6825,2025)',
 ROT='0',
 VER='1',
 PACK_TYPE='0402LF',
 LOCATION='R376',
 CDS_LIB='pure_quanta',
 CDS_PART_NAME='Q_RES_0402LF-15,1%,1/16W,CHIP,CS01502FB03',
 PART_NUMBER='CS01502FB03',
 VALUE='15',
 PRIM_FILE='./archive_libs/logical/q_res/chips/chips.prt';

PART_NAME
 R377 'Q_RES_0402LF-15,1%,1/16W,CHIP,CS01502FB03':;

SECTION_NUMBER 1
 '@T6G_MB_LIB.T6G(SCH_1):PAGE12_I314@PURE_QUANTA.Q_RES(CHIPS)':
 C_PATH='@t6g_mb_lib.t6g(sch_1):page12_i314@pure_quanta.q_res(chips)',
 P_PATH='@t6g_mb_lib.t6g(sch_1):page12_i314@pure_quanta.q_res(chips)',
 PATH='I314',
 DRAWING='@T6G_MB_LIB.T6G(SCH_1):PAGE12',
 WATTAGE='1/16W',
 TOLERANCE='1%',
 MATERIAL='CHIP',
 PHYS_PAGE='12',
 XY='(-7050,2100)',
 ROT='0',
 VER='1',
 PACK_TYPE='0402LF',
 LOCATION='R377',
 CDS_LIB='pure_quanta',
 CDS_PART_NAME='Q_RES_0402LF-15,1%,1/16W,CHIP,CS01502FB03',
 PART_NUMBER='CS01502FB03',
 VALUE='15',
 PRIM_FILE='./archive_libs/logical/q_res/chips/chips.prt';

PART_NAME
 R378 'Q_RES_0402LF-15,1%,1/16W,CHIP,CS01502FB03':;

SECTION_NUMBER 1
 '@T6G_MB_LIB.T6G(SCH_1):PAGE13_I314@PURE_QUANTA.Q_RES(CHIPS)':
 C_PATH='@t6g_mb_lib.t6g(sch_1):page13_i314@pure_quanta.q_res(chips)',
 P_PATH='@t6g_mb_lib.t6g(sch_1):page13_i314@pure_quanta.q_res(chips)',
 PATH='I314',
 DRAWING='@T6G_MB_LIB.T6G(SCH_1):PAGE13',
 WATTAGE='1/16W',
 TOLERANCE='1%',
 MATERIAL='CHIP',
 PHYS_PAGE='13',
 XY='(-6875,2175)',
 ROT='0',
 VER='1',
 PACK_TYPE='0402LF',
 LOCATION='R378',
 CDS_LIB='pure_quanta',
 CDS_PART_NAME='Q_RES_0402LF-15,1%,1/16W,CHIP,CS01502FB03',
 PART_NUMBER='CS01502FB03',
 VALUE='15',
 PRIM_FILE='./archive_libs/logical/q_res/chips/chips.prt';

PART_NAME
 R379 'Q_RES_0402LF-15,1%,1/16W,CHIP,CS01502FB03':;

SECTION_NUMBER 1
 '@T6G_MB_LIB.T6G(SCH_1):PAGE14_I315@PURE_QUANTA.Q_RES(CHIPS)':
 C_PATH='@t6g_mb_lib.t6g(sch_1):page14_i315@pure_quanta.q_res(chips)',
 P_PATH='@t6g_mb_lib.t6g(sch_1):page14_i315@pure_quanta.q_res(chips)',
 PATH='I315',
 DRAWING='@T6G_MB_LIB.T6G(SCH_1):PAGE14',
 WATTAGE='1/16W',
 TOLERANCE='1%',
 MATERIAL='CHIP',
 PHYS_PAGE='14',
 XY='(-6950,2200)',
 ROT='0',
 VER='1',
 PACK_TYPE='0402LF',
 LOCATION='R379',
 CDS_LIB='pure_quanta',
 CDS_PART_NAME='Q_RES_0402LF-15,1%,1/16W,CHIP,CS01502FB03',
 PART_NUMBER='CS01502FB03',
 VALUE='15',
 PRIM_FILE='./archive_libs/logical/q_res/chips/chips.prt';

PART_NAME
 R380 'Q_RES_0402LF-15,1%,1/16W,CHIP,CS01502FB03':;

SECTION_NUMBER 1
 '@T6G_MB_LIB.T6G(SCH_1):PAGE15_I314@PURE_QUANTA.Q_RES(CHIPS)':
 C_PATH='@t6g_mb_lib.t6g(sch_1):page15_i314@pure_quanta.q_res(chips)',
 P_PATH='@t6g_mb_lib.t6g(sch_1):page15_i314@pure_quanta.q_res(chips)',
 PATH='I314',
 DRAWING='@T6G_MB_LIB.T6G(SCH_1):PAGE15',
 WATTAGE='1/16W',
 TOLERANCE='1%',
 MATERIAL='CHIP',
 PHYS_PAGE='15',
 XY='(-6925,2125)',
 ROT='0',
 VER='1',
 PACK_TYPE='0402LF',
 LOCATION='R380',
 CDS_LIB='pure_quanta',
 CDS_PART_NAME='Q_RES_0402LF-15,1%,1/16W,CHIP,CS01502FB03',
 PART_NUMBER='CS01502FB03',
 VALUE='15',
 PRIM_FILE='./archive_libs/logical/q_res/chips/chips.prt';

PART_NAME
 R381 'Q_RES_0402LF-15,1%,1/16W,CHIP,CS01502FB03':;

SECTION_NUMBER 1
 '@T6G_MB_LIB.T6G(SCH_1):PAGE16_I323@PURE_QUANTA.Q_RES(CHIPS)':
 C_PATH='@t6g_mb_lib.t6g(sch_1):page16_i323@pure_quanta.q_res(chips)',
 P_PATH='@t6g_mb_lib.t6g(sch_1):page16_i323@pure_quanta.q_res(chips)',
 PATH='I323',
 DRAWING='@T6G_MB_LIB.T6G(SCH_1):PAGE16',
 WATTAGE='1/16W',
 TOLERANCE='1%',
 MATERIAL='CHIP',
 PHYS_PAGE='16',
 XY='(-6975,2200)',
 ROT='0',
 VER='1',
 PACK_TYPE='0402LF',
 LOCATION='R381',
 CDS_LIB='pure_quanta',
 CDS_PART_NAME='Q_RES_0402LF-15,1%,1/16W,CHIP,CS01502FB03',
 PART_NUMBER='CS01502FB03',
 VALUE='15',
 PRIM_FILE='./archive_libs/logical/q_res/chips/chips.prt';

PART_NAME
 R382 'Q_RES_0402LF-15,1%,1/16W,CHIP,CS01502FB03':;

SECTION_NUMBER 1
 '@T6G_MB_LIB.T6G(SCH_1):PAGE17_I314@PURE_QUANTA.Q_RES(CHIPS)':
 C_PATH='@t6g_mb_lib.t6g(sch_1):page17_i314@pure_quanta.q_res(chips)',
 P_PATH='@t6g_mb_lib.t6g(sch_1):page17_i314@pure_quanta.q_res(chips)',
 PATH='I314',
 DRAWING='@T6G_MB_LIB.T6G(SCH_1):PAGE17',
 WATTAGE='1/16W',
 TOLERANCE='1%',
 MATERIAL='CHIP',
 PHYS_PAGE='17',
 XY='(-6875,2125)',
 ROT='0',
 VER='1',
 PACK_TYPE='0402LF',
 LOCATION='R382',
 CDS_LIB='pure_quanta',
 CDS_PART_NAME='Q_RES_0402LF-15,1%,1/16W,CHIP,CS01502FB03',
 PART_NUMBER='CS01502FB03',
 VALUE='15',
 PRIM_FILE='./archive_libs/logical/q_res/chips/chips.prt';

PART_NAME
 R383 'Q_RES_0402LF-15,1%,1/16W,CHIP,CS01502FB03':;

SECTION_NUMBER 1
 '@T6G_MB_LIB.T6G(SCH_1):PAGE18_I314@PURE_QUANTA.Q_RES(CHIPS)':
 C_PATH='@t6g_mb_lib.t6g(sch_1):page18_i314@pure_quanta.q_res(chips)',
 P_PATH='@t6g_mb_lib.t6g(sch_1):page18_i314@pure_quanta.q_res(chips)',
 PATH='I314',
 DRAWING='@T6G_MB_LIB.T6G(SCH_1):PAGE18',
 WATTAGE='1/16W',
 TOLERANCE='1%',
 MATERIAL='CHIP',
 PHYS_PAGE='18',
 XY='(-6800,2125)',
 ROT='0',
 VER='1',
 PACK_TYPE='0402LF',
 LOCATION='R383',
 CDS_LIB='pure_quanta',
 CDS_PART_NAME='Q_RES_0402LF-15,1%,1/16W,CHIP,CS01502FB03',
 PART_NUMBER='CS01502FB03',
 VALUE='15',
 PRIM_FILE='./archive_libs/logical/q_res/chips/chips.prt';

PART_NAME
 R384 'Q_RES_0402LF-15,1%,1/16W,CHIP,CS01502FB03':;

SECTION_NUMBER 1
 '@T6G_MB_LIB.T6G(SCH_1):PAGE19_I314@PURE_QUANTA.Q_RES(CHIPS)':
 C_PATH='@t6g_mb_lib.t6g(sch_1):page19_i314@pure_quanta.q_res(chips)',
 P_PATH='@t6g_mb_lib.t6g(sch_1):page19_i314@pure_quanta.q_res(chips)',
 PATH='I314',
 DRAWING='@T6G_MB_LIB.T6G(SCH_1):PAGE19',
 WATTAGE='1/16W',
 TOLERANCE='1%',
 MATERIAL='CHIP',
 PHYS_PAGE='19',
 XY='(-6800,2150)',
 ROT='0',
 VER='1',
 PACK_TYPE='0402LF',
 LOCATION='R384',
 CDS_LIB='pure_quanta',
 CDS_PART_NAME='Q_RES_0402LF-15,1%,1/16W,CHIP,CS01502FB03',
 PART_NUMBER='CS01502FB03',
 VALUE='15',
 PRIM_FILE='./archive_libs/logical/q_res/chips/chips.prt';

PART_NAME
 R385 'Q_RES_0402LF-15,1%,1/16W,CHIP,CS01502FB03':;

SECTION_NUMBER 1
 '@T6G_MB_LIB.T6G(SCH_1):PAGE20_I314@PURE_QUANTA.Q_RES(CHIPS)':
 C_PATH='@t6g_mb_lib.t6g(sch_1):page20_i314@pure_quanta.q_res(chips)',
 P_PATH='@t6g_mb_lib.t6g(sch_1):page20_i314@pure_quanta.q_res(chips)',
 PATH='I314',
 DRAWING='@T6G_MB_LIB.T6G(SCH_1):PAGE20',
 WATTAGE='1/16W',
 TOLERANCE='1%',
 MATERIAL='CHIP',
 PHYS_PAGE='20',
 XY='(-6700,2100)',
 ROT='0',
 VER='1',
 PACK_TYPE='0402LF',
 LOCATION='R385',
 CDS_LIB='pure_quanta',
 CDS_PART_NAME='Q_RES_0402LF-15,1%,1/16W,CHIP,CS01502FB03',
 PART_NUMBER='CS01502FB03',
 VALUE='15',
 PRIM_FILE='./archive_libs/logical/q_res/chips/chips.prt';

PART_NAME
 R386 'Q_RES_0402LF-15,1%,1/16W,CHIP,CS01502FB03':;

SECTION_NUMBER 1
 '@T6G_MB_LIB.T6G(SCH_1):PAGE21_I314@PURE_QUANTA.Q_RES(CHIPS)':
 C_PATH='@t6g_mb_lib.t6g(sch_1):page21_i314@pure_quanta.q_res(chips)',
 P_PATH='@t6g_mb_lib.t6g(sch_1):page21_i314@pure_quanta.q_res(chips)',
 PATH='I314',
 DRAWING='@T6G_MB_LIB.T6G(SCH_1):PAGE21',
 WATTAGE='1/16W',
 TOLERANCE='1%',
 MATERIAL='CHIP',
 PHYS_PAGE='21',
 XY='(-6775,2150)',
 ROT='0',
 VER='1',
 PACK_TYPE='0402LF',
 LOCATION='R386',
 CDS_LIB='pure_quanta',
 CDS_PART_NAME='Q_RES_0402LF-15,1%,1/16W,CHIP,CS01502FB03',
 PART_NUMBER='CS01502FB03',
 VALUE='15',
 PRIM_FILE='./archive_libs/logical/q_res/chips/chips.prt';

PART_NAME
 R387 'Q_RES_0402LF-2.2K,5%,1/16W,CHIP,CS22202JB07':;

SECTION_NUMBER 1
 '@T6G_MB_LIB.T6G(SCH_1):PAGE27_I388@PURE_QUANTA.Q_RES(CHIPS)':
 C_PATH='@t6g_mb_lib.t6g(sch_1):page27_i388@pure_quanta.q_res(chips)',
 P_PATH='@t6g_mb_lib.t6g(sch_1):page27_i388@pure_quanta.q_res(chips)',
 PATH='I388',
 DRAWING='@T6G_MB_LIB.T6G(SCH_1):PAGE27',
 WATTAGE='1/16W',
 TOLERANCE='5%',
 MATERIAL='CHIP',
 PHYS_PAGE='27',
 XY='(-8700,2850)',
 ROT='0',
 VER='1',
 PACK_TYPE='0402LF',
 LOCATION='R387',
 CDS_LIB='pure_quanta',
 CDS_PART_NAME='Q_RES_0402LF-2.2K,5%,1/16W,CHIP,CS22202JB07',
 PART_NUMBER='CS22202JB07',
 VALUE='2.2K',
 PRIM_FILE='./archive_libs/logical/q_res/chips/chips.prt';

PART_NAME
 R388 'Q_RES_0402LF-2.2K,5%,1/16W,CHIP,CS22202JB07':;

SECTION_NUMBER 1
 '@T6G_MB_LIB.T6G(SCH_1):PAGE27_I389@PURE_QUANTA.Q_RES(CHIPS)':
 C_PATH='@t6g_mb_lib.t6g(sch_1):page27_i389@pure_quanta.q_res(chips)',
 P_PATH='@t6g_mb_lib.t6g(sch_1):page27_i389@pure_quanta.q_res(chips)',
 PATH='I389',
 DRAWING='@T6G_MB_LIB.T6G(SCH_1):PAGE27',
 WATTAGE='1/16W',
 TOLERANCE='5%',
 MATERIAL='CHIP',
 PHYS_PAGE='27',
 XY='(-8700,2900)',
 ROT='0',
 VER='1',
 PACK_TYPE='0402LF',
 LOCATION='R388',
 CDS_LIB='pure_quanta',
 CDS_PART_NAME='Q_RES_0402LF-2.2K,5%,1/16W,CHIP,CS22202JB07',
 PART_NUMBER='CS22202JB07',
 VALUE='2.2K',
 PRIM_FILE='./archive_libs/logical/q_res/chips/chips.prt';

PART_NAME
 R389 'Q_RES_0402LF-2.2K,5%,1/16W,CHIP,CS22202JB07':;

SECTION_NUMBER 1
 '@T6G_MB_LIB.T6G(SCH_1):PAGE27_I391@PURE_QUANTA.Q_RES(CHIPS)':
 C_PATH='@t6g_mb_lib.t6g(sch_1):page27_i391@pure_quanta.q_res(chips)',
 P_PATH='@t6g_mb_lib.t6g(sch_1):page27_i391@pure_quanta.q_res(chips)',
 PATH='I391',
 DRAWING='@T6G_MB_LIB.T6G(SCH_1):PAGE27',
 WATTAGE='1/16W',
 TOLERANCE='5%',
 MATERIAL='CHIP',
 PHYS_PAGE='27',
 XY='(-8700,3000)',
 ROT='0',
 VER='1',
 PACK_TYPE='0402LF',
 LOCATION='R389',
 CDS_LIB='pure_quanta',
 CDS_PART_NAME='Q_RES_0402LF-2.2K,5%,1/16W,CHIP,CS22202JB07',
 PART_NUMBER='CS22202JB07',
 VALUE='2.2K',
 PRIM_FILE='./archive_libs/logical/q_res/chips/chips.prt';

PART_NAME
 R390 'Q_RES_0402LF-2.2K,5%,1/16W,CHIP,CS22202JB07':;

SECTION_NUMBER 1
 '@T6G_MB_LIB.T6G(SCH_1):PAGE27_I390@PURE_QUANTA.Q_RES(CHIPS)':
 C_PATH='@t6g_mb_lib.t6g(sch_1):page27_i390@pure_quanta.q_res(chips)',
 P_PATH='@t6g_mb_lib.t6g(sch_1):page27_i390@pure_quanta.q_res(chips)',
 PATH='I390',
 DRAWING='@T6G_MB_LIB.T6G(SCH_1):PAGE27',
 WATTAGE='1/16W',
 TOLERANCE='5%',
 MATERIAL='CHIP',
 PHYS_PAGE='27',
 XY='(-8700,2950)',
 ROT='0',
 VER='1',
 PACK_TYPE='0402LF',
 LOCATION='R390',
 CDS_LIB='pure_quanta',
 CDS_PART_NAME='Q_RES_0402LF-2.2K,5%,1/16W,CHIP,CS22202JB07',
 PART_NUMBER='CS22202JB07',
 VALUE='2.2K',
 PRIM_FILE='./archive_libs/logical/q_res/chips/chips.prt';

PART_NAME
 R391 'Q_RES_0402LF-2.2K,5%,1/16W,CHIP,CS22202JB07':;

SECTION_NUMBER 1
 '@T6G_MB_LIB.T6G(SCH_1):PAGE27_I392@PURE_QUANTA.Q_RES(CHIPS)':
 C_PATH='@t6g_mb_lib.t6g(sch_1):page27_i392@pure_quanta.q_res(chips)',
 P_PATH='@t6g_mb_lib.t6g(sch_1):page27_i392@pure_quanta.q_res(chips)',
 PATH='I392',
 DRAWING='@T6G_MB_LIB.T6G(SCH_1):PAGE27',
 WATTAGE='1/16W',
 TOLERANCE='5%',
 MATERIAL='CHIP',
 PHYS_PAGE='27',
 XY='(-8700,3050)',
 ROT='0',
 VER='1',
 PACK_TYPE='0402LF',
 LOCATION='R391',
 CDS_LIB='pure_quanta',
 CDS_PART_NAME='Q_RES_0402LF-2.2K,5%,1/16W,CHIP,CS22202JB07',
 PART_NUMBER='CS22202JB07',
 VALUE='2.2K',
 PRIM_FILE='./archive_libs/logical/q_res/chips/chips.prt';

PART_NAME
 R392 'Q_RES_0402LF-2.2K,5%,1/16W,EMPTY,CS22202JB07':;

SECTION_NUMBER 1
 '@T6G_MB_LIB.T6G(SCH_1):PAGE27_I395@PURE_QUANTA.Q_RES(CHIPS)':
 C_PATH='@t6g_mb_lib.t6g(sch_1):page27_i395@pure_quanta.q_res(chips)',
 P_PATH='@t6g_mb_lib.t6g(sch_1):page27_i395@pure_quanta.q_res(chips)',
 PATH='I395',
 DRAWING='@T6G_MB_LIB.T6G(SCH_1):PAGE27',
 WATTAGE='1/16W',
 TOLERANCE='5%',
 MATERIAL='EMPTY',
 PHYS_PAGE='27',
 XY='(-8675,4650)',
 ROT='2',
 VER='2',
 PACK_TYPE='0402LF',
 LOCATION='R392',
 CDS_LIB='pure_quanta',
 CDS_PART_NAME='Q_RES_0402LF-2.2K,5%,1/16W,EMPTY,CS22202JB07',
 PART_NUMBER='CS22202JB07',
 VALUE='2.2K',
 PRIM_FILE='./archive_libs/logical/q_res/chips/chips.prt';

PART_NAME
 R393 'Q_RES_0402LF-2.2K,5%,1/16W,CHIP,CS22202JB07':;

SECTION_NUMBER 1
 '@T6G_MB_LIB.T6G(SCH_1):PAGE27_I396@PURE_QUANTA.Q_RES(CHIPS)':
 C_PATH='@t6g_mb_lib.t6g(sch_1):page27_i396@pure_quanta.q_res(chips)',
 P_PATH='@t6g_mb_lib.t6g(sch_1):page27_i396@pure_quanta.q_res(chips)',
 PATH='I396',
 DRAWING='@T6G_MB_LIB.T6G(SCH_1):PAGE27',
 WATTAGE='1/16W',
 TOLERANCE='5%',
 MATERIAL='CHIP',
 PHYS_PAGE='27',
 XY='(-8675,4350)',
 ROT='2',
 VER='2',
 PACK_TYPE='0402LF',
 LOCATION='R393',
 CDS_LIB='pure_quanta',
 CDS_PART_NAME='Q_RES_0402LF-2.2K,5%,1/16W,CHIP,CS22202JB07',
 PART_NUMBER='CS22202JB07',
 VALUE='2.2K',
 PRIM_FILE='./archive_libs/logical/q_res/chips/chips.prt';

PART_NAME
 R394 'Q_RES_0402LF-2.2K,5%,1/16W,CHIP,CS22202JB07':;

SECTION_NUMBER 1
 '@T6G_MB_LIB.T6G(SCH_1):PAGE27_I397@PURE_QUANTA.Q_RES(CHIPS)':
 C_PATH='@t6g_mb_lib.t6g(sch_1):page27_i397@pure_quanta.q_res(chips)',
 P_PATH='@t6g_mb_lib.t6g(sch_1):page27_i397@pure_quanta.q_res(chips)',
 PATH='I397',
 DRAWING='@T6G_MB_LIB.T6G(SCH_1):PAGE27',
 WATTAGE='1/16W',
 TOLERANCE='5%',
 MATERIAL='CHIP',
 PHYS_PAGE='27',
 XY='(-8550,4350)',
 ROT='0',
 VER='2',
 PACK_TYPE='0402LF',
 LOCATION='R394',
 CDS_LIB='pure_quanta',
 CDS_PART_NAME='Q_RES_0402LF-2.2K,5%,1/16W,CHIP,CS22202JB07',
 PART_NUMBER='CS22202JB07',
 VALUE='2.2K',
 PRIM_FILE='./archive_libs/logical/q_res/chips/chips.prt';

PART_NAME
 R395 'Q_RES_0402LF-0,5%,1/16W,CHIP,CS00002JB13':;

SECTION_NUMBER 1
 '@T6G_MB_LIB.T6G(SCH_1):PAGE80_I155@PURE_QUANTA.Q_RES(CHIPS)':
 C_PATH='@t6g_mb_lib.t6g(sch_1):page80_i155@pure_quanta.q_res(chips)',
 P_PATH='@t6g_mb_lib.t6g(sch_1):page81_i155@pure_quanta.q_res(chips)',
 PATH='I155',
 DRAWING='@T6G_MB_LIB.T6G(SCH_1):PAGE80',
 BOM_COST='MEM',
 WATTAGE='1/16W',
 TOLERANCE='5%',
 MATERIAL='CHIP',
 PHYS_PAGE='81',
 XY='(-3225,4225)',
 ROT='0',
 VER='1',
 PACK_TYPE='0402LF',
 LOCATION='R395',
 CDS_LIB='pure_quanta',
 CDS_PART_NAME='Q_RES_0402LF-0,5%,1/16W,CHIP,CS00002JB13',
 PART_NUMBER='CS00002JB13',
 VALUE='0',
 PRIM_FILE='./archive_libs/logical/q_res/chips/chips.prt';

PART_NAME
 R396 'Q_RES_0402LF-2.2K,5%,1/16W,CHIP,CS22202JB07':;

SECTION_NUMBER 1
 '@T6G_MB_LIB.T6G(SCH_1):PAGE27_I393@PURE_QUANTA.Q_RES(CHIPS)':
 C_PATH='@t6g_mb_lib.t6g(sch_1):page27_i393@pure_quanta.q_res(chips)',
 P_PATH='@t6g_mb_lib.t6g(sch_1):page27_i393@pure_quanta.q_res(chips)',
 PATH='I393',
 DRAWING='@T6G_MB_LIB.T6G(SCH_1):PAGE27',
 WATTAGE='1/16W',
 TOLERANCE='5%',
 MATERIAL='CHIP',
 PHYS_PAGE='27',
 XY='(-8700,3100)',
 ROT='0',
 VER='1',
 PACK_TYPE='0402LF',
 LOCATION='R396',
 CDS_LIB='pure_quanta',
 CDS_PART_NAME='Q_RES_0402LF-2.2K,5%,1/16W,CHIP,CS22202JB07',
 PART_NUMBER='CS22202JB07',
 VALUE='2.2K',
 PRIM_FILE='./archive_libs/logical/q_res/chips/chips.prt';

PART_NAME
 R397 'Q_RES_0402LF-2.2K,5%,1/16W,CHIP,CS22202JB07':;

SECTION_NUMBER 1
 '@T6G_MB_LIB.T6G(SCH_1):PAGE27_I394@PURE_QUANTA.Q_RES(CHIPS)':
 C_PATH='@t6g_mb_lib.t6g(sch_1):page27_i394@pure_quanta.q_res(chips)',
 P_PATH='@t6g_mb_lib.t6g(sch_1):page27_i394@pure_quanta.q_res(chips)',
 PATH='I394',
 DRAWING='@T6G_MB_LIB.T6G(SCH_1):PAGE27',
 WATTAGE='1/16W',
 TOLERANCE='5%',
 MATERIAL='CHIP',
 PHYS_PAGE='27',
 XY='(-8700,3150)',
 ROT='0',
 VER='1',
 PACK_TYPE='0402LF',
 LOCATION='R397',
 CDS_LIB='pure_quanta',
 CDS_PART_NAME='Q_RES_0402LF-2.2K,5%,1/16W,CHIP,CS22202JB07',
 PART_NUMBER='CS22202JB07',
 VALUE='2.2K',
 PRIM_FILE='./archive_libs/logical/q_res/chips/chips.prt';

PART_NAME
 R398 'Q_RES_0402LF-1K,1%,1/16W,CHIP,CS21002FB06':;

SECTION_NUMBER 1
 '@T6G_MB_LIB.T6G(SCH_1):PAGE27_I305@PURE_QUANTA.Q_RES(CHIPS)':
 C_PATH='@t6g_mb_lib.t6g(sch_1):page27_i305@pure_quanta.q_res(chips)',
 P_PATH='@t6g_mb_lib.t6g(sch_1):page27_i305@pure_quanta.q_res(chips)',
 PATH='I305',
 DRAWING='@T6G_MB_LIB.T6G(SCH_1):PAGE27',
 WATTAGE='1/16W',
 TOLERANCE='1%',
 MATERIAL='CHIP',
 PHYS_PAGE='27',
 XY='(-8000,1300)',
 ROT='0',
 VER='2',
 PACK_TYPE='0402LF',
 LOCATION='R398',
 CDS_LIB='pure_quanta',
 CDS_PART_NAME='Q_RES_0402LF-1K,1%,1/16W,CHIP,CS21002FB06',
 PART_NUMBER='CS21002FB06',
 VALUE='1K',
 PRIM_FILE='./archive_libs/logical/q_res/chips/chips.prt';

PART_NAME
 R399 'Q_RES_0402LF-1K,1%,1/16W,CHIP,CS21002FB06':;

SECTION_NUMBER 1
 '@T6G_MB_LIB.T6G(SCH_1):PAGE27_I304@PURE_QUANTA.Q_RES(CHIPS)':
 C_PATH='@t6g_mb_lib.t6g(sch_1):page27_i304@pure_quanta.q_res(chips)',
 P_PATH='@t6g_mb_lib.t6g(sch_1):page27_i304@pure_quanta.q_res(chips)',
 PATH='I304',
 DRAWING='@T6G_MB_LIB.T6G(SCH_1):PAGE27',
 WATTAGE='1/16W',
 TOLERANCE='1%',
 MATERIAL='CHIP',
 PHYS_PAGE='27',
 XY='(-7675,1300)',
 ROT='0',
 VER='2',
 PACK_TYPE='0402LF',
 LOCATION='R399',
 CDS_LIB='pure_quanta',
 CDS_PART_NAME='Q_RES_0402LF-1K,1%,1/16W,CHIP,CS21002FB06',
 PART_NUMBER='CS21002FB06',
 VALUE='1K',
 PRIM_FILE='./archive_libs/logical/q_res/chips/chips.prt';

PART_NAME
 R400 'Q_RES_0402LF-1K,1%,1/16W,CHIP,CS21002FB06':;

SECTION_NUMBER 1
 '@T6G_MB_LIB.T6G(SCH_1):PAGE27_I301@PURE_QUANTA.Q_RES(CHIPS)':
 C_PATH='@t6g_mb_lib.t6g(sch_1):page27_i301@pure_quanta.q_res(chips)',
 P_PATH='@t6g_mb_lib.t6g(sch_1):page27_i301@pure_quanta.q_res(chips)',
 PATH='I301',
 DRAWING='@T6G_MB_LIB.T6G(SCH_1):PAGE27',
 WATTAGE='1/16W',
 TOLERANCE='1%',
 MATERIAL='CHIP',
 PHYS_PAGE='27',
 XY='(-7350,1300)',
 ROT='0',
 VER='2',
 PACK_TYPE='0402LF',
 LOCATION='R400',
 CDS_LIB='pure_quanta',
 CDS_PART_NAME='Q_RES_0402LF-1K,1%,1/16W,CHIP,CS21002FB06',
 PART_NUMBER='CS21002FB06',
 VALUE='1K',
 PRIM_FILE='./archive_libs/logical/q_res/chips/chips.prt';

PART_NAME
 R401 'Q_RES_0402LF-1K,1%,1/16W,CHIP,CS21002FB06':;

SECTION_NUMBER 1
 '@T6G_MB_LIB.T6G(SCH_1):PAGE27_I300@PURE_QUANTA.Q_RES(CHIPS)':
 C_PATH='@t6g_mb_lib.t6g(sch_1):page27_i300@pure_quanta.q_res(chips)',
 P_PATH='@t6g_mb_lib.t6g(sch_1):page27_i300@pure_quanta.q_res(chips)',
 PATH='I300',
 DRAWING='@T6G_MB_LIB.T6G(SCH_1):PAGE27',
 WATTAGE='1/16W',
 TOLERANCE='1%',
 MATERIAL='CHIP',
 PHYS_PAGE='27',
 XY='(-7025,1300)',
 ROT='0',
 VER='2',
 PACK_TYPE='0402LF',
 LOCATION='R401',
 CDS_LIB='pure_quanta',
 CDS_PART_NAME='Q_RES_0402LF-1K,1%,1/16W,CHIP,CS21002FB06',
 PART_NUMBER='CS21002FB06',
 VALUE='1K',
 PRIM_FILE='./archive_libs/logical/q_res/chips/chips.prt';

PART_NAME
 R402 'Q_RES_0402LF-1K,1%,1/16W,CHIP,CS21002FB06':;

SECTION_NUMBER 1
 '@T6G_MB_LIB.T6G(SCH_1):PAGE27_I296@PURE_QUANTA.Q_RES(CHIPS)':
 C_PATH='@t6g_mb_lib.t6g(sch_1):page27_i296@pure_quanta.q_res(chips)',
 P_PATH='@t6g_mb_lib.t6g(sch_1):page27_i296@pure_quanta.q_res(chips)',
 PATH='I296',
 DRAWING='@T6G_MB_LIB.T6G(SCH_1):PAGE27',
 WATTAGE='1/16W',
 TOLERANCE='1%',
 MATERIAL='CHIP',
 PHYS_PAGE='27',
 XY='(-6675,1300)',
 ROT='0',
 VER='2',
 PACK_TYPE='0402LF',
 LOCATION='R402',
 CDS_LIB='pure_quanta',
 CDS_PART_NAME='Q_RES_0402LF-1K,1%,1/16W,CHIP,CS21002FB06',
 PART_NUMBER='CS21002FB06',
 VALUE='1K',
 PRIM_FILE='./archive_libs/logical/q_res/chips/chips.prt';

PART_NAME
 R403 'Q_RES_0402LF-1K,1%,1/16W,CHIP,CS21002FB06':;

SECTION_NUMBER 1
 '@T6G_MB_LIB.T6G(SCH_1):PAGE27_I294@PURE_QUANTA.Q_RES(CHIPS)':
 C_PATH='@t6g_mb_lib.t6g(sch_1):page27_i294@pure_quanta.q_res(chips)',
 P_PATH='@t6g_mb_lib.t6g(sch_1):page27_i294@pure_quanta.q_res(chips)',
 PATH='I294',
 DRAWING='@T6G_MB_LIB.T6G(SCH_1):PAGE27',
 WATTAGE='1/16W',
 TOLERANCE='1%',
 MATERIAL='CHIP',
 PHYS_PAGE='27',
 XY='(-6375,1300)',
 ROT='0',
 VER='2',
 PACK_TYPE='0402LF',
 LOCATION='R403',
 CDS_LIB='pure_quanta',
 CDS_PART_NAME='Q_RES_0402LF-1K,1%,1/16W,CHIP,CS21002FB06',
 PART_NUMBER='CS21002FB06',
 VALUE='1K',
 PRIM_FILE='./archive_libs/logical/q_res/chips/chips.prt';

PART_NAME
 R404 'Q_RES_0402LF-0,5%,1/16W,CHIP,CS00002JB13':;

SECTION_NUMBER 1
 '@T6G_MB_LIB.T6G(SCH_1):PAGE27_I170@PURE_QUANTA.Q_RES(CHIPS)':
 C_PATH='@t6g_mb_lib.t6g(sch_1):page27_i170@pure_quanta.q_res(chips)',
 P_PATH='@t6g_mb_lib.t6g(sch_1):page27_i170@pure_quanta.q_res(chips)',
 PATH='I170',
 DRAWING='@T6G_MB_LIB.T6G(SCH_1):PAGE27',
 WATTAGE='1/16W',
 TOLERANCE='5%',
 MATERIAL='CHIP',
 PHYS_PAGE='27',
 XY='(-5725,4575)',
 ROT='2',
 VER='1',
 PACK_TYPE='0402LF',
 LOCATION='R404',
 CDS_LIB='pure_quanta',
 CDS_PART_NAME='Q_RES_0402LF-0,5%,1/16W,CHIP,CS00002JB13',
 PART_NUMBER='CS00002JB13',
 VALUE='0',
 PRIM_FILE='./archive_libs/logical/q_res/chips/chips.prt';

PART_NAME
 R405 'Q_RES_0402LF-0,5%,1/16W,CHIP,CS00002JB13':;

SECTION_NUMBER 1
 '@T6G_MB_LIB.T6G(SCH_1):PAGE27_I279@PURE_QUANTA.Q_RES(CHIPS)':
 C_PATH='@t6g_mb_lib.t6g(sch_1):page27_i279@pure_quanta.q_res(chips)',
 P_PATH='@t6g_mb_lib.t6g(sch_1):page27_i279@pure_quanta.q_res(chips)',
 PATH='I279',
 DRAWING='@T6G_MB_LIB.T6G(SCH_1):PAGE27',
 WATTAGE='1/16W',
 TOLERANCE='5%',
 MATERIAL='CHIP',
 PHYS_PAGE='27',
 XY='(-2375,1475)',
 ROT='2',
 VER='1',
 PACK_TYPE='0402LF',
 LOCATION='R405',
 CDS_LIB='pure_quanta',
 CDS_PART_NAME='Q_RES_0402LF-0,5%,1/16W,CHIP,CS00002JB13',
 PART_NUMBER='CS00002JB13',
 VALUE='0',
 PRIM_FILE='./archive_libs/logical/q_res/chips/chips.prt';

PART_NAME
 R406 'Q_RES_0402LF-4.7K,5%,1/16W,EMPTY,CS24702JB10':;

SECTION_NUMBER 1
 '@T6G_MB_LIB.T6G(SCH_1):PAGE137_I46@PURE_QUANTA.Q_RES(CHIPS)':
 C_PATH='@t6g_mb_lib.t6g(sch_1):page137_i46@pure_quanta.q_res(chips)',
 P_PATH='@t6g_mb_lib.t6g(sch_1):page160_i46@pure_quanta.q_res(chips)',
 PATH='I46',
 DRAWING='@T6G_MB_LIB.T6G(SCH_1):PAGE137',
 WATTAGE='1/16W',
 TOLERANCE='5%',
 MATERIAL='EMPTY',
 PHYS_PAGE='160',
 XY='(-650,-150)',
 ROT='0',
 VER='2',
 PACK_TYPE='0402LF',
 LOCATION='R406',
 CDS_LIB='pure_quanta',
 CDS_PART_NAME='Q_RES_0402LF-4.7K,5%,1/16W,EMPTY,CS24702JB10',
 PART_NUMBER='CS24702JB10',
 VALUE='4.7K',
 PRIM_FILE='./archive_libs/logical/q_res/chips/chips.prt';

PART_NAME
 R407 'Q_RES_0402LF-0,5%,1/16W,CHIP,CS00002JB13':;

SECTION_NUMBER 1
 '@T6G_MB_LIB.T6G(SCH_1):PAGE79_I139@PURE_QUANTA.Q_RES(CHIPS)':
 C_PATH='@t6g_mb_lib.t6g(sch_1):page79_i139@pure_quanta.q_res(chips)',
 P_PATH='@t6g_mb_lib.t6g(sch_1):page80_i139@pure_quanta.q_res(chips)',
 PATH='I139',
 DRAWING='@T6G_MB_LIB.T6G(SCH_1):PAGE79',
 BOM_COST='MEM',
 WATTAGE='1/16W',
 TOLERANCE='5%',
 MATERIAL='CHIP',
 PHYS_PAGE='80',
 XY='(-2775,4750)',
 ROT='2',
 VER='1',
 PACK_TYPE='0402LF',
 LOCATION='R407',
 CDS_LIB='pure_quanta',
 CDS_PART_NAME='Q_RES_0402LF-0,5%,1/16W,CHIP,CS00002JB13',
 PART_NUMBER='CS00002JB13',
 VALUE='0',
 PRIM_FILE='./archive_libs/logical/q_res/chips/chips.prt';

PART_NAME
 R408 'Q_RES_0402LF-2.2K,5%,1/16W,CHIP,CS22202JB07':;

SECTION_NUMBER 1
 '@T6G_MB_LIB.T6G(SCH_1):PAGE27_I380@PURE_QUANTA.Q_RES(CHIPS)':
 C_PATH='@t6g_mb_lib.t6g(sch_1):page27_i380@pure_quanta.q_res(chips)',
 P_PATH='@t6g_mb_lib.t6g(sch_1):page27_i380@pure_quanta.q_res(chips)',
 PATH='I380',
 DRAWING='@T6G_MB_LIB.T6G(SCH_1):PAGE27',
 WATTAGE='1/16W',
 TOLERANCE='5%',
 MATERIAL='CHIP',
 PHYS_PAGE='27',
 XY='(-575,5600)',
 ROT='0',
 VER='1',
 PACK_TYPE='0402LF',
 LOCATION='R408',
 CDS_LIB='pure_quanta',
 CDS_PART_NAME='Q_RES_0402LF-2.2K,5%,1/16W,CHIP,CS22202JB07',
 PART_NUMBER='CS22202JB07',
 VALUE='2.2K',
 PRIM_FILE='./archive_libs/logical/q_res/chips/chips.prt';

PART_NAME
 R409 'Q_RES_0402LF-2.2K,5%,1/16W,CHIP,CS22202JB07':;

SECTION_NUMBER 1
 '@T6G_MB_LIB.T6G(SCH_1):PAGE27_I381@PURE_QUANTA.Q_RES(CHIPS)':
 C_PATH='@t6g_mb_lib.t6g(sch_1):page27_i381@pure_quanta.q_res(chips)',
 P_PATH='@t6g_mb_lib.t6g(sch_1):page27_i381@pure_quanta.q_res(chips)',
 PATH='I381',
 DRAWING='@T6G_MB_LIB.T6G(SCH_1):PAGE27',
 WATTAGE='1/16W',
 TOLERANCE='5%',
 MATERIAL='CHIP',
 PHYS_PAGE='27',
 XY='(-575,5550)',
 ROT='0',
 VER='1',
 PACK_TYPE='0402LF',
 LOCATION='R409',
 CDS_LIB='pure_quanta',
 CDS_PART_NAME='Q_RES_0402LF-2.2K,5%,1/16W,CHIP,CS22202JB07',
 PART_NUMBER='CS22202JB07',
 VALUE='2.2K',
 PRIM_FILE='./archive_libs/logical/q_res/chips/chips.prt';

PART_NAME
 R410 'Q_RES_0402LF-2.2K,5%,1/16W,CHIP,CS22202JB07':;

SECTION_NUMBER 1
 '@T6G_MB_LIB.T6G(SCH_1):PAGE27_I382@PURE_QUANTA.Q_RES(CHIPS)':
 C_PATH='@t6g_mb_lib.t6g(sch_1):page27_i382@pure_quanta.q_res(chips)',
 P_PATH='@t6g_mb_lib.t6g(sch_1):page27_i382@pure_quanta.q_res(chips)',
 PATH='I382',
 DRAWING='@T6G_MB_LIB.T6G(SCH_1):PAGE27',
 WATTAGE='1/16W',
 TOLERANCE='5%',
 MATERIAL='CHIP',
 PHYS_PAGE='27',
 XY='(-575,5500)',
 ROT='0',
 VER='1',
 PACK_TYPE='0402LF',
 LOCATION='R410',
 CDS_LIB='pure_quanta',
 CDS_PART_NAME='Q_RES_0402LF-2.2K,5%,1/16W,CHIP,CS22202JB07',
 PART_NUMBER='CS22202JB07',
 VALUE='2.2K',
 PRIM_FILE='./archive_libs/logical/q_res/chips/chips.prt';

PART_NAME
 R411 'Q_RES_0402LF-2.2K,5%,1/16W,CHIP,CS22202JB07':;

SECTION_NUMBER 1
 '@T6G_MB_LIB.T6G(SCH_1):PAGE27_I383@PURE_QUANTA.Q_RES(CHIPS)':
 C_PATH='@t6g_mb_lib.t6g(sch_1):page27_i383@pure_quanta.q_res(chips)',
 P_PATH='@t6g_mb_lib.t6g(sch_1):page27_i383@pure_quanta.q_res(chips)',
 PATH='I383',
 DRAWING='@T6G_MB_LIB.T6G(SCH_1):PAGE27',
 WATTAGE='1/16W',
 TOLERANCE='5%',
 MATERIAL='CHIP',
 PHYS_PAGE='27',
 XY='(-575,5450)',
 ROT='0',
 VER='1',
 PACK_TYPE='0402LF',
 LOCATION='R411',
 CDS_LIB='pure_quanta',
 CDS_PART_NAME='Q_RES_0402LF-2.2K,5%,1/16W,CHIP,CS22202JB07',
 PART_NUMBER='CS22202JB07',
 VALUE='2.2K',
 PRIM_FILE='./archive_libs/logical/q_res/chips/chips.prt';

PART_NAME
 R412 'Q_RES_0402LF-2.2K,5%,1/16W,CHIP,CS22202JB07':;

SECTION_NUMBER 1
 '@T6G_MB_LIB.T6G(SCH_1):PAGE27_I377@PURE_QUANTA.Q_RES(CHIPS)':
 C_PATH='@t6g_mb_lib.t6g(sch_1):page27_i377@pure_quanta.q_res(chips)',
 P_PATH='@t6g_mb_lib.t6g(sch_1):page27_i377@pure_quanta.q_res(chips)',
 PATH='I377',
 DRAWING='@T6G_MB_LIB.T6G(SCH_1):PAGE27',
 WATTAGE='1/16W',
 TOLERANCE='5%',
 MATERIAL='CHIP',
 PHYS_PAGE='27',
 XY='(-575,5400)',
 ROT='0',
 VER='1',
 PACK_TYPE='0402LF',
 LOCATION='R412',
 CDS_LIB='pure_quanta',
 CDS_PART_NAME='Q_RES_0402LF-2.2K,5%,1/16W,CHIP,CS22202JB07',
 PART_NUMBER='CS22202JB07',
 VALUE='2.2K',
 PRIM_FILE='./archive_libs/logical/q_res/chips/chips.prt';

PART_NAME
 R413 'Q_RES_0402LF-2.2K,5%,1/16W,CHIP,CS22202JB07':;

SECTION_NUMBER 1
 '@T6G_MB_LIB.T6G(SCH_1):PAGE27_I384@PURE_QUANTA.Q_RES(CHIPS)':
 C_PATH='@t6g_mb_lib.t6g(sch_1):page27_i384@pure_quanta.q_res(chips)',
 P_PATH='@t6g_mb_lib.t6g(sch_1):page27_i384@pure_quanta.q_res(chips)',
 PATH='I384',
 DRAWING='@T6G_MB_LIB.T6G(SCH_1):PAGE27',
 WATTAGE='1/16W',
 TOLERANCE='5%',
 MATERIAL='CHIP',
 PHYS_PAGE='27',
 XY='(-575,5350)',
 ROT='0',
 VER='1',
 PACK_TYPE='0402LF',
 LOCATION='R413',
 CDS_LIB='pure_quanta',
 CDS_PART_NAME='Q_RES_0402LF-2.2K,5%,1/16W,CHIP,CS22202JB07',
 PART_NUMBER='CS22202JB07',
 VALUE='2.2K',
 PRIM_FILE='./archive_libs/logical/q_res/chips/chips.prt';

PART_NAME
 R414 'Q_RES_0402LF-2.2K,5%,1/16W,CHIP,CS22202JB07':;

SECTION_NUMBER 1
 '@T6G_MB_LIB.T6G(SCH_1):PAGE27_I385@PURE_QUANTA.Q_RES(CHIPS)':
 C_PATH='@t6g_mb_lib.t6g(sch_1):page27_i385@pure_quanta.q_res(chips)',
 P_PATH='@t6g_mb_lib.t6g(sch_1):page27_i385@pure_quanta.q_res(chips)',
 PATH='I385',
 DRAWING='@T6G_MB_LIB.T6G(SCH_1):PAGE27',
 WATTAGE='1/16W',
 TOLERANCE='5%',
 MATERIAL='CHIP',
 PHYS_PAGE='27',
 XY='(-575,5300)',
 ROT='0',
 VER='1',
 PACK_TYPE='0402LF',
 LOCATION='R414',
 CDS_LIB='pure_quanta',
 CDS_PART_NAME='Q_RES_0402LF-2.2K,5%,1/16W,CHIP,CS22202JB07',
 PART_NUMBER='CS22202JB07',
 VALUE='2.2K',
 PRIM_FILE='./archive_libs/logical/q_res/chips/chips.prt';

PART_NAME
 R415 'Q_RES_0402LF-2.2K,5%,1/16W,CHIP,CS22202JB07':;

SECTION_NUMBER 1
 '@T6G_MB_LIB.T6G(SCH_1):PAGE27_I386@PURE_QUANTA.Q_RES(CHIPS)':
 C_PATH='@t6g_mb_lib.t6g(sch_1):page27_i386@pure_quanta.q_res(chips)',
 P_PATH='@t6g_mb_lib.t6g(sch_1):page27_i386@pure_quanta.q_res(chips)',
 PATH='I386',
 DRAWING='@T6G_MB_LIB.T6G(SCH_1):PAGE27',
 WATTAGE='1/16W',
 TOLERANCE='5%',
 MATERIAL='CHIP',
 PHYS_PAGE='27',
 XY='(-575,5250)',
 ROT='0',
 VER='1',
 PACK_TYPE='0402LF',
 LOCATION='R415',
 CDS_LIB='pure_quanta',
 CDS_PART_NAME='Q_RES_0402LF-2.2K,5%,1/16W,CHIP,CS22202JB07',
 PART_NUMBER='CS22202JB07',
 VALUE='2.2K',
 PRIM_FILE='./archive_libs/logical/q_res/chips/chips.prt';

PART_NAME
 R416 'Q_RES_0402LF-2.2K,5%,1/16W,CHIP,CS22202JB07':;

SECTION_NUMBER 1
 '@T6G_MB_LIB.T6G(SCH_1):PAGE27_I387@PURE_QUANTA.Q_RES(CHIPS)':
 C_PATH='@t6g_mb_lib.t6g(sch_1):page27_i387@pure_quanta.q_res(chips)',
 P_PATH='@t6g_mb_lib.t6g(sch_1):page27_i387@pure_quanta.q_res(chips)',
 PATH='I387',
 DRAWING='@T6G_MB_LIB.T6G(SCH_1):PAGE27',
 WATTAGE='1/16W',
 TOLERANCE='5%',
 MATERIAL='CHIP',
 PHYS_PAGE='27',
 XY='(-575,5200)',
 ROT='0',
 VER='1',
 PACK_TYPE='0402LF',
 LOCATION='R416',
 CDS_LIB='pure_quanta',
 CDS_PART_NAME='Q_RES_0402LF-2.2K,5%,1/16W,CHIP,CS22202JB07',
 PART_NUMBER='CS22202JB07',
 VALUE='2.2K',
 PRIM_FILE='./archive_libs/logical/q_res/chips/chips.prt';

PART_NAME
 R417 'Q_RES_0402LF-2.2K,5%,1/16W,CHIP,CS22202JB07':;

SECTION_NUMBER 1
 '@T6G_MB_LIB.T6G(SCH_1):PAGE27_I379@PURE_QUANTA.Q_RES(CHIPS)':
 C_PATH='@t6g_mb_lib.t6g(sch_1):page27_i379@pure_quanta.q_res(chips)',
 P_PATH='@t6g_mb_lib.t6g(sch_1):page27_i379@pure_quanta.q_res(chips)',
 PATH='I379',
 DRAWING='@T6G_MB_LIB.T6G(SCH_1):PAGE27',
 WATTAGE='1/16W',
 TOLERANCE='5%',
 MATERIAL='CHIP',
 PHYS_PAGE='27',
 XY='(-575,5150)',
 ROT='0',
 VER='1',
 PACK_TYPE='0402LF',
 LOCATION='R417',
 CDS_LIB='pure_quanta',
 CDS_PART_NAME='Q_RES_0402LF-2.2K,5%,1/16W,CHIP,CS22202JB07',
 PART_NUMBER='CS22202JB07',
 VALUE='2.2K',
 PRIM_FILE='./archive_libs/logical/q_res/chips/chips.prt';

PART_NAME
 R418 'Q_RES_0402LF-2.2K,5%,1/16W,CHIP,CS22202JB07':;

SECTION_NUMBER 1
 '@T6G_MB_LIB.T6G(SCH_1):PAGE27_I378@PURE_QUANTA.Q_RES(CHIPS)':
 C_PATH='@t6g_mb_lib.t6g(sch_1):page27_i378@pure_quanta.q_res(chips)',
 P_PATH='@t6g_mb_lib.t6g(sch_1):page27_i378@pure_quanta.q_res(chips)',
 PATH='I378',
 DRAWING='@T6G_MB_LIB.T6G(SCH_1):PAGE27',
 WATTAGE='1/16W',
 TOLERANCE='5%',
 MATERIAL='CHIP',
 PHYS_PAGE='27',
 XY='(-575,5100)',
 ROT='0',
 VER='1',
 PACK_TYPE='0402LF',
 LOCATION='R418',
 CDS_LIB='pure_quanta',
 CDS_PART_NAME='Q_RES_0402LF-2.2K,5%,1/16W,CHIP,CS22202JB07',
 PART_NUMBER='CS22202JB07',
 VALUE='2.2K',
 PRIM_FILE='./archive_libs/logical/q_res/chips/chips.prt';

PART_NAME
 R419 'Q_RES_0402LF-0,5%,1/16W,CHIP,CS00002JB13':;

SECTION_NUMBER 1
 '@T6G_MB_LIB.T6G(SCH_1):PAGE79_I141@PURE_QUANTA.Q_RES(CHIPS)':
 C_PATH='@t6g_mb_lib.t6g(sch_1):page79_i141@pure_quanta.q_res(chips)',
 P_PATH='@t6g_mb_lib.t6g(sch_1):page80_i141@pure_quanta.q_res(chips)',
 PATH='I141',
 DRAWING='@T6G_MB_LIB.T6G(SCH_1):PAGE79',
 BOM_COST='MEM',
 WATTAGE='1/16W',
 TOLERANCE='5%',
 MATERIAL='CHIP',
 PHYS_PAGE='80',
 XY='(-2775,3800)',
 ROT='2',
 VER='1',
 PACK_TYPE='0402LF',
 LOCATION='R419',
 CDS_LIB='pure_quanta',
 CDS_PART_NAME='Q_RES_0402LF-0,5%,1/16W,CHIP,CS00002JB13',
 PART_NUMBER='CS00002JB13',
 VALUE='0',
 PRIM_FILE='./archive_libs/logical/q_res/chips/chips.prt';

PART_NAME
 R420 'Q_RES_0402LF-1K,1%,1/16W,EMPTY,CS21002FB06':;

SECTION_NUMBER 1
 '@T6G_MB_LIB.T6G(SCH_1):PAGE28_I22@PURE_QUANTA.Q_RES(CHIPS)':
 C_PATH='@t6g_mb_lib.t6g(sch_1):page28_i22@pure_quanta.q_res(chips)',
 P_PATH='@t6g_mb_lib.t6g(sch_1):page28_i22@pure_quanta.q_res(chips)',
 PATH='I22',
 DRAWING='@T6G_MB_LIB.T6G(SCH_1):PAGE28',
 WATTAGE='1/16W',
 TOLERANCE='1%',
 MATERIAL='EMPTY',
 PHYS_PAGE='28',
 XY='(-9100,9650)',
 ROT='0',
 VER='2',
 PACK_TYPE='0402LF',
 LOCATION='R420',
 CDS_LIB='pure_quanta',
 CDS_PART_NAME='Q_RES_0402LF-1K,1%,1/16W,EMPTY,CS21002FB06',
 PART_NUMBER='CS21002FB06',
 VALUE='1K',
 PRIM_FILE='./archive_libs/logical/q_res/chips/chips.prt';

PART_NAME
 R421 'Q_RES_0402LF-1K,1%,1/16W,EMPTY,CS21002FB06':;

SECTION_NUMBER 1
 '@T6G_MB_LIB.T6G(SCH_1):PAGE28_I23@PURE_QUANTA.Q_RES(CHIPS)':
 C_PATH='@t6g_mb_lib.t6g(sch_1):page28_i23@pure_quanta.q_res(chips)',
 P_PATH='@t6g_mb_lib.t6g(sch_1):page28_i23@pure_quanta.q_res(chips)',
 PATH='I23',
 DRAWING='@T6G_MB_LIB.T6G(SCH_1):PAGE28',
 WATTAGE='1/16W',
 TOLERANCE='1%',
 MATERIAL='EMPTY',
 PHYS_PAGE='28',
 XY='(-8925,9650)',
 ROT='0',
 VER='2',
 PACK_TYPE='0402LF',
 LOCATION='R421',
 CDS_LIB='pure_quanta',
 CDS_PART_NAME='Q_RES_0402LF-1K,1%,1/16W,EMPTY,CS21002FB06',
 PART_NUMBER='CS21002FB06',
 VALUE='1K',
 PRIM_FILE='./archive_libs/logical/q_res/chips/chips.prt';

PART_NAME
 R422 'Q_RES_0402LF-2.2K,5%,1/16W,CHIP,CS22202JB07':;

SECTION_NUMBER 1
 '@T6G_MB_LIB.T6G(SCH_1):PAGE28_I29@PURE_QUANTA.Q_RES(CHIPS)':
 C_PATH='@t6g_mb_lib.t6g(sch_1):page28_i29@pure_quanta.q_res(chips)',
 P_PATH='@t6g_mb_lib.t6g(sch_1):page28_i29@pure_quanta.q_res(chips)',
 PATH='I29',
 DRAWING='@T6G_MB_LIB.T6G(SCH_1):PAGE28',
 WATTAGE='1/16W',
 TOLERANCE='5%',
 MATERIAL='CHIP',
 PHYS_PAGE='28',
 XY='(-8775,13050)',
 ROT='0',
 VER='2',
 PACK_TYPE='0402LF',
 LOCATION='R422',
 CDS_LIB='pure_quanta',
 CDS_PART_NAME='Q_RES_0402LF-2.2K,5%,1/16W,CHIP,CS22202JB07',
 PART_NUMBER='CS22202JB07',
 VALUE='2.2K',
 PRIM_FILE='./archive_libs/logical/q_res/chips/chips.prt';

PART_NAME
 R423 'Q_RES_0402LF-1K,1%,1/16W,EMPTY,CS21002FB06':;

SECTION_NUMBER 1
 '@T6G_MB_LIB.T6G(SCH_1):PAGE28_I24@PURE_QUANTA.Q_RES(CHIPS)':
 C_PATH='@t6g_mb_lib.t6g(sch_1):page28_i24@pure_quanta.q_res(chips)',
 P_PATH='@t6g_mb_lib.t6g(sch_1):page28_i24@pure_quanta.q_res(chips)',
 PATH='I24',
 DRAWING='@T6G_MB_LIB.T6G(SCH_1):PAGE28',
 WATTAGE='1/16W',
 TOLERANCE='1%',
 MATERIAL='EMPTY',
 PHYS_PAGE='28',
 XY='(-8750,9650)',
 ROT='0',
 VER='2',
 PACK_TYPE='0402LF',
 LOCATION='R423',
 CDS_LIB='pure_quanta',
 CDS_PART_NAME='Q_RES_0402LF-1K,1%,1/16W,EMPTY,CS21002FB06',
 PART_NUMBER='CS21002FB06',
 VALUE='1K',
 PRIM_FILE='./archive_libs/logical/q_res/chips/chips.prt';

PART_NAME
 R424 'Q_RES_0402LF-2.2K,5%,1/16W,CHIP,CS22202JB07':;

SECTION_NUMBER 1
 '@T6G_MB_LIB.T6G(SCH_1):PAGE28_I30@PURE_QUANTA.Q_RES(CHIPS)':
 C_PATH='@t6g_mb_lib.t6g(sch_1):page28_i30@pure_quanta.q_res(chips)',
 P_PATH='@t6g_mb_lib.t6g(sch_1):page28_i30@pure_quanta.q_res(chips)',
 PATH='I30',
 DRAWING='@T6G_MB_LIB.T6G(SCH_1):PAGE28',
 WATTAGE='1/16W',
 TOLERANCE='5%',
 MATERIAL='CHIP',
 PHYS_PAGE='28',
 XY='(-8600,13050)',
 ROT='0',
 VER='2',
 PACK_TYPE='0402LF',
 LOCATION='R424',
 CDS_LIB='pure_quanta',
 CDS_PART_NAME='Q_RES_0402LF-2.2K,5%,1/16W,CHIP,CS22202JB07',
 PART_NUMBER='CS22202JB07',
 VALUE='2.2K',
 PRIM_FILE='./archive_libs/logical/q_res/chips/chips.prt';

PART_NAME
 R425 'Q_RES_0402LF-1K,1%,1/16W,EMPTY,CS21002FB06':;

SECTION_NUMBER 1
 '@T6G_MB_LIB.T6G(SCH_1):PAGE28_I25@PURE_QUANTA.Q_RES(CHIPS)':
 C_PATH='@t6g_mb_lib.t6g(sch_1):page28_i25@pure_quanta.q_res(chips)',
 P_PATH='@t6g_mb_lib.t6g(sch_1):page28_i25@pure_quanta.q_res(chips)',
 PATH='I25',
 DRAWING='@T6G_MB_LIB.T6G(SCH_1):PAGE28',
 WATTAGE='1/16W',
 TOLERANCE='1%',
 MATERIAL='EMPTY',
 PHYS_PAGE='28',
 XY='(-8575,9650)',
 ROT='0',
 VER='2',
 PACK_TYPE='0402LF',
 LOCATION='R425',
 CDS_LIB='pure_quanta',
 CDS_PART_NAME='Q_RES_0402LF-1K,1%,1/16W,EMPTY,CS21002FB06',
 PART_NUMBER='CS21002FB06',
 VALUE='1K',
 PRIM_FILE='./archive_libs/logical/q_res/chips/chips.prt';

PART_NAME
 R426 'Q_RES_0402LF-0,5%,1/16W,CHIP,CS00002JB13':;

SECTION_NUMBER 1
 '@T6G_MB_LIB.T6G(SCH_1):PAGE136_I99@PURE_QUANTA.Q_RES(CHIPS)':
 C_PATH='@t6g_mb_lib.t6g(sch_1):page136_i99@pure_quanta.q_res(chips)',
 P_PATH='@t6g_mb_lib.t6g(sch_1):page159_i99@pure_quanta.q_res(chips)',
 PATH='I99',
 DRAWING='@T6G_MB_LIB.T6G(SCH_1):PAGE136',
 WATTAGE='1/16W',
 TOLERANCE='5%',
 MATERIAL='CHIP',
 PHYS_PAGE='159',
 XY='(-6075,5775)',
 ROT='2',
 VER='1',
 PACK_TYPE='0402LF',
 LOCATION='R426',
 CDS_LIB='pure_quanta',
 CDS_PART_NAME='Q_RES_0402LF-0,5%,1/16W,CHIP,CS00002JB13',
 PART_NUMBER='CS00002JB13',
 VALUE='0',
 PRIM_FILE='./archive_libs/logical/q_res/chips/chips.prt';

PART_NAME
 R427 'Q_RES_0402LF-0,5%,1/16W,CHIP,CS00002JB13':;

SECTION_NUMBER 1
 '@T6G_MB_LIB.T6G(SCH_1):PAGE136_I100@PURE_QUANTA.Q_RES(CHIPS)':
 C_PATH='@t6g_mb_lib.t6g(sch_1):page136_i100@pure_quanta.q_res(chips)',
 P_PATH='@t6g_mb_lib.t6g(sch_1):page159_i100@pure_quanta.q_res(chips)',
 PATH='I100',
 DRAWING='@T6G_MB_LIB.T6G(SCH_1):PAGE136',
 WATTAGE='1/16W',
 TOLERANCE='5%',
 MATERIAL='CHIP',
 PHYS_PAGE='159',
 XY='(-6075,5725)',
 ROT='2',
 VER='1',
 PACK_TYPE='0402LF',
 LOCATION='R427',
 CDS_LIB='pure_quanta',
 CDS_PART_NAME='Q_RES_0402LF-0,5%,1/16W,CHIP,CS00002JB13',
 PART_NUMBER='CS00002JB13',
 VALUE='0',
 PRIM_FILE='./archive_libs/logical/q_res/chips/chips.prt';

PART_NAME
 R428 'Q_RES_0402LF-0,5%,1/16W,CHIP,CS00002JB13':;

SECTION_NUMBER 1
 '@T6G_MB_LIB.T6G(SCH_1):PAGE136_I103@PURE_QUANTA.Q_RES(CHIPS)':
 C_PATH='@t6g_mb_lib.t6g(sch_1):page136_i103@pure_quanta.q_res(chips)',
 P_PATH='@t6g_mb_lib.t6g(sch_1):page159_i103@pure_quanta.q_res(chips)',
 PATH='I103',
 DRAWING='@T6G_MB_LIB.T6G(SCH_1):PAGE136',
 WATTAGE='1/16W',
 TOLERANCE='5%',
 MATERIAL='CHIP',
 PHYS_PAGE='159',
 XY='(-6050,4375)',
 ROT='2',
 VER='1',
 PACK_TYPE='0402LF',
 LOCATION='R428',
 CDS_LIB='pure_quanta',
 CDS_PART_NAME='Q_RES_0402LF-0,5%,1/16W,CHIP,CS00002JB13',
 PART_NUMBER='CS00002JB13',
 VALUE='0',
 PRIM_FILE='./archive_libs/logical/q_res/chips/chips.prt';

PART_NAME
 R429 'Q_RES_0402LF-0,5%,1/16W,CHIP,CS00002JB13':;

SECTION_NUMBER 1
 '@T6G_MB_LIB.T6G(SCH_1):PAGE136_I104@PURE_QUANTA.Q_RES(CHIPS)':
 C_PATH='@t6g_mb_lib.t6g(sch_1):page136_i104@pure_quanta.q_res(chips)',
 P_PATH='@t6g_mb_lib.t6g(sch_1):page159_i104@pure_quanta.q_res(chips)',
 PATH='I104',
 DRAWING='@T6G_MB_LIB.T6G(SCH_1):PAGE136',
 WATTAGE='1/16W',
 TOLERANCE='5%',
 MATERIAL='CHIP',
 PHYS_PAGE='159',
 XY='(-6050,4325)',
 ROT='2',
 VER='1',
 PACK_TYPE='0402LF',
 LOCATION='R429',
 CDS_LIB='pure_quanta',
 CDS_PART_NAME='Q_RES_0402LF-0,5%,1/16W,CHIP,CS00002JB13',
 PART_NUMBER='CS00002JB13',
 VALUE='0',
 PRIM_FILE='./archive_libs/logical/q_res/chips/chips.prt';

PART_NAME
 R430 'Q_RES_0402LF-0,5%,1/16W,CHIP,CS00002JB13':;

SECTION_NUMBER 1
 '@T6G_MB_LIB.T6G(SCH_1):PAGE28_I98@PURE_QUANTA.Q_RES(CHIPS)':
 C_PATH='@t6g_mb_lib.t6g(sch_1):page28_i98@pure_quanta.q_res(chips)',
 P_PATH='@t6g_mb_lib.t6g(sch_1):page28_i98@pure_quanta.q_res(chips)',
 PATH='I98',
 DRAWING='@T6G_MB_LIB.T6G(SCH_1):PAGE28',
 WATTAGE='1/16W',
 TOLERANCE='5%',
 MATERIAL='CHIP',
 PHYS_PAGE='28',
 XY='(-6850,10925)',
 ROT='2',
 VER='1',
 PACK_TYPE='0402LF',
 LOCATION='R430',
 CDS_LIB='pure_quanta',
 CDS_PART_NAME='Q_RES_0402LF-0,5%,1/16W,CHIP,CS00002JB13',
 PART_NUMBER='CS00002JB13',
 VALUE='0',
 PRIM_FILE='./archive_libs/logical/q_res/chips/chips.prt';

PART_NAME
 R431 'Q_RES_0402LF-0,5%,1/16W,CHIP,CS00002JB13':;

SECTION_NUMBER 1
 '@T6G_MB_LIB.T6G(SCH_1):PAGE28_I97@PURE_QUANTA.Q_RES(CHIPS)':
 C_PATH='@t6g_mb_lib.t6g(sch_1):page28_i97@pure_quanta.q_res(chips)',
 P_PATH='@t6g_mb_lib.t6g(sch_1):page28_i97@pure_quanta.q_res(chips)',
 PATH='I97',
 DRAWING='@T6G_MB_LIB.T6G(SCH_1):PAGE28',
 WATTAGE='1/16W',
 TOLERANCE='5%',
 MATERIAL='CHIP',
 PHYS_PAGE='28',
 XY='(-6850,10875)',
 ROT='2',
 VER='1',
 PACK_TYPE='0402LF',
 LOCATION='R431',
 CDS_LIB='pure_quanta',
 CDS_PART_NAME='Q_RES_0402LF-0,5%,1/16W,CHIP,CS00002JB13',
 PART_NUMBER='CS00002JB13',
 VALUE='0',
 PRIM_FILE='./archive_libs/logical/q_res/chips/chips.prt';

PART_NAME
 R432 'Q_RES_0402LF-10M,1%,1/16W,CHIP,CS61002FB02':;

SECTION_NUMBER 1
 '@T6G_MB_LIB.T6G(SCH_1):PAGE28_I104@PURE_QUANTA.Q_RES(CHIPS)':
 C_PATH='@t6g_mb_lib.t6g(sch_1):page28_i104@pure_quanta.q_res(chips)',
 P_PATH='@t6g_mb_lib.t6g(sch_1):page28_i104@pure_quanta.q_res(chips)',
 PATH='I104',
 DRAWING='@T6G_MB_LIB.T6G(SCH_1):PAGE28',
 WATTAGE='1/16W',
 TOLERANCE='1%',
 MATERIAL='CHIP',
 PHYS_PAGE='28',
 XY='(-5575,8125)',
 ROT='0',
 VER='1',
 PACK_TYPE='0402LF',
 LOCATION='R432',
 CDS_LIB='pure_quanta',
 CDS_PART_NAME='Q_RES_0402LF-10M,1%,1/16W,CHIP,CS61002FB02',
 PART_NUMBER='CS61002FB02',
 VALUE='10M',
 PRIM_FILE='./archive_libs/logical/q_res/chips/chips.prt';

PART_NAME
 R433 'Q_RES_0402LF-20M,1%,1/16W,CHIP,CS62002FB01':;

SECTION_NUMBER 1
 '@T6G_MB_LIB.T6G(SCH_1):PAGE28_I221@PURE_QUANTA.Q_RES(CHIPS)':
 C_PATH='@t6g_mb_lib.t6g(sch_1):page28_i221@pure_quanta.q_res(chips)',
 P_PATH='@t6g_mb_lib.t6g(sch_1):page28_i221@pure_quanta.q_res(chips)',
 PATH='I221',
 DRAWING='@T6G_MB_LIB.T6G(SCH_1):PAGE28',
 SEC_TYPE='0402LF',
 WATTAGE='1/16W',
 TOLERANCE='1%',
 MATERIAL='CHIP',
 PHYS_PAGE='28',
 XY='(-3350,8450)',
 ROT='0',
 VER='1',
 PACK_TYPE='0402LF',
 LOCATION='R433',
 SEC='1',
 CDS_LIB='pure_quanta',
 CDS_PART_NAME='Q_RES_0402LF-20M,1%,1/16W,CHIP,CS62002FB01',
 PART_NUMBER='CS62002FB01',
 VALUE='20M',
 PRIM_FILE='./archive_libs/logical/q_res/chips/chips.prt';

PART_NAME
 R434 'Q_RES_0402LF-33,5%,1/16W,CHIP,CS03302JB10':;

SECTION_NUMBER 1
 '@T6G_MB_LIB.T6G(SCH_1):PAGE28_I165@PURE_QUANTA.Q_RES(CHIPS)':
 C_PATH='@t6g_mb_lib.t6g(sch_1):page28_i165@pure_quanta.q_res(chips)',
 P_PATH='@t6g_mb_lib.t6g(sch_1):page28_i165@pure_quanta.q_res(chips)',
 PATH='I165',
 DRAWING='@T6G_MB_LIB.T6G(SCH_1):PAGE28',
 WATTAGE='1/16W',
 TOLERANCE='5%',
 MATERIAL='CHIP',
 PHYS_PAGE='28',
 XY='(-2175,12525)',
 ROT='0',
 VER='1',
 PACK_TYPE='0402LF',
 LOCATION='R434',
 CDS_LIB='pure_quanta',
 CDS_PART_NAME='Q_RES_0402LF-33,5%,1/16W,CHIP,CS03302JB10',
 PART_NUMBER='CS03302JB10',
 VALUE='33',
 PRIM_FILE='./archive_libs/logical/q_res/chips/chips.prt';

PART_NAME
 R435 'Q_RES_0402LF-0,5%,1/16W,CHIP,CS00002JB13':;

SECTION_NUMBER 1
 '@T6G_MB_LIB.T6G(SCH_1):PAGE28_I171@PURE_QUANTA.Q_RES(CHIPS)':
 C_PATH='@t6g_mb_lib.t6g(sch_1):page28_i171@pure_quanta.q_res(chips)',
 P_PATH='@t6g_mb_lib.t6g(sch_1):page28_i171@pure_quanta.q_res(chips)',
 PATH='I171',
 DRAWING='@T6G_MB_LIB.T6G(SCH_1):PAGE28',
 WATTAGE='1/16W',
 TOLERANCE='5%',
 MATERIAL='CHIP',
 PHYS_PAGE='28',
 XY='(-1800,13025)',
 ROT='0',
 VER='1',
 PACK_TYPE='0402LF',
 LOCATION='R435',
 CDS_LIB='pure_quanta',
 CDS_PART_NAME='Q_RES_0402LF-0,5%,1/16W,CHIP,CS00002JB13',
 PART_NUMBER='CS00002JB13',
 VALUE='0',
 PRIM_FILE='./archive_libs/logical/q_res/chips/chips.prt';

PART_NAME
 R436 'Q_RES_0402LF-0,5%,1/16W,CHIP,CS00002JB13':;

SECTION_NUMBER 1
 '@T6G_MB_LIB.T6G(SCH_1):PAGE28_I172@PURE_QUANTA.Q_RES(CHIPS)':
 C_PATH='@t6g_mb_lib.t6g(sch_1):page28_i172@pure_quanta.q_res(chips)',
 P_PATH='@t6g_mb_lib.t6g(sch_1):page28_i172@pure_quanta.q_res(chips)',
 PATH='I172',
 DRAWING='@T6G_MB_LIB.T6G(SCH_1):PAGE28',
 WATTAGE='1/16W',
 TOLERANCE='5%',
 MATERIAL='CHIP',
 PHYS_PAGE='28',
 XY='(-1800,12975)',
 ROT='0',
 VER='1',
 PACK_TYPE='0402LF',
 LOCATION='R436',
 CDS_LIB='pure_quanta',
 CDS_PART_NAME='Q_RES_0402LF-0,5%,1/16W,CHIP,CS00002JB13',
 PART_NUMBER='CS00002JB13',
 VALUE='0',
 PRIM_FILE='./archive_libs/logical/q_res/chips/chips.prt';

PART_NAME
 R437 'Q_RES_0402LF-2.2K,5%,1/16W,CHIP,CS22202JB07':;

SECTION_NUMBER 1
 '@T6G_MB_LIB.T6G(SCH_1):PAGE132_I18@PURE_QUANTA.Q_RES(CHIPS)':
 C_PATH='@t6g_mb_lib.t6g(sch_1):page132_i18@pure_quanta.q_res(chips)',
 P_PATH='@t6g_mb_lib.t6g(sch_1):page155_i18@pure_quanta.q_res(chips)',
 PATH='I18',
 DRAWING='@T6G_MB_LIB.T6G(SCH_1):PAGE132',
 WATTAGE='1/16W',
 TOLERANCE='5%',
 MATERIAL='CHIP',
 PHYS_PAGE='155',
 XY='(-1175,4650)',
 ROT='0',
 VER='2',
 PACK_TYPE='0402LF',
 LOCATION='R437',
 CDS_LIB='pure_quanta',
 CDS_PART_NAME='Q_RES_0402LF-2.2K,5%,1/16W,CHIP,CS22202JB07',
 PART_NUMBER='CS22202JB07',
 VALUE='2.2K',
 PRIM_FILE='./archive_libs/logical/q_res/chips/chips.prt';

PART_NAME
 R438 'Q_RES_0402LF-4.7K,5%,1/16W,EMPTY,CS24702JB10':;

SECTION_NUMBER 1
 '@T6G_MB_LIB.T6G(SCH_1):PAGE28_I222@PURE_QUANTA.Q_RES(CHIPS)':
 C_PATH='@t6g_mb_lib.t6g(sch_1):page28_i222@pure_quanta.q_res(chips)',
 P_PATH='@t6g_mb_lib.t6g(sch_1):page28_i222@pure_quanta.q_res(chips)',
 PATH='I222',
 DRAWING='@T6G_MB_LIB.T6G(SCH_1):PAGE28',
 SEC_TYPE='0402LF',
 WATTAGE='1/16W',
 TOLERANCE='5%',
 MATERIAL='EMPTY',
 PHYS_PAGE='28',
 XY='(-7775,8925)',
 ROT='0',
 VER='1',
 PACK_TYPE='0402LF',
 LOCATION='R438',
 SEC='1',
 CDS_LIB='pure_quanta',
 CDS_PART_NAME='Q_RES_0402LF-4.7K,5%,1/16W,EMPTY,CS24702JB10',
 PART_NUMBER='CS24702JB10',
 VALUE='4.7K',
 PRIM_FILE='./archive_libs/logical/q_res/chips/chips.prt';

PART_NAME
 R439 'Q_RES_0402LF-0,5%,1/16W,CHIP,CS00002JB13':;

SECTION_NUMBER 1
 '@T6G_MB_LIB.T6G(SCH_1):PAGE79_I144@PURE_QUANTA.Q_RES(CHIPS)':
 C_PATH='@t6g_mb_lib.t6g(sch_1):page79_i144@pure_quanta.q_res(chips)',
 P_PATH='@t6g_mb_lib.t6g(sch_1):page80_i144@pure_quanta.q_res(chips)',
 PATH='I144',
 DRAWING='@T6G_MB_LIB.T6G(SCH_1):PAGE79',
 SEC_TYPE='0402LF',
 WATTAGE='1/16W',
 TOLERANCE='5%',
 MATERIAL='CHIP',
 PHYS_PAGE='80',
 XY='(-2775,3900)',
 ROT='0',
 VER='1',
 PACK_TYPE='0402LF',
 LOCATION='R439',
 SEC='1',
 CDS_LIB='pure_quanta',
 CDS_PART_NAME='Q_RES_0402LF-0,5%,1/16W,CHIP,CS00002JB13',
 PART_NUMBER='CS00002JB13',
 VALUE='0',
 PRIM_FILE='./archive_libs/logical/q_res/chips/chips.prt';

PART_NAME
 R440 'Q_RES_0402LF-4.7K,5%,1/16W,EMPTY,CS24702JB10':;

SECTION_NUMBER 1
 '@T6G_MB_LIB.T6G(SCH_1):PAGE28_I37@PURE_QUANTA.Q_RES(CHIPS)':
 C_PATH='@t6g_mb_lib.t6g(sch_1):page28_i37@pure_quanta.q_res(chips)',
 P_PATH='@t6g_mb_lib.t6g(sch_1):page28_i37@pure_quanta.q_res(chips)',
 PATH='I37',
 DRAWING='@T6G_MB_LIB.T6G(SCH_1):PAGE28',
 WATTAGE='1/16W',
 TOLERANCE='5%',
 MATERIAL='EMPTY',
 PHYS_PAGE='28',
 XY='(-7400,7225)',
 ROT='1',
 VER='1',
 PACK_TYPE='0402LF',
 LOCATION='R440',
 CDS_LIB='pure_quanta',
 CDS_PART_NAME='Q_RES_0402LF-4.7K,5%,1/16W,EMPTY,CS24702JB10',
 PART_NUMBER='CS24702JB10',
 VALUE='4.7K',
 PRIM_FILE='./archive_libs/logical/q_res/chips/chips.prt';

PART_NAME
 R441 'Q_RES_0402LF-2.2K,5%,1/16W,CHIP,CS22202JB07':;

SECTION_NUMBER 1
 '@T6G_MB_LIB.T6G(SCH_1):PAGE28_I55@PURE_QUANTA.Q_RES(CHIPS)':
 C_PATH='@t6g_mb_lib.t6g(sch_1):page28_i55@pure_quanta.q_res(chips)',
 P_PATH='@t6g_mb_lib.t6g(sch_1):page28_i55@pure_quanta.q_res(chips)',
 PATH='I55',
 DRAWING='@T6G_MB_LIB.T6G(SCH_1):PAGE28',
 WATTAGE='1/16W',
 TOLERANCE='5%',
 MATERIAL='CHIP',
 PHYS_PAGE='28',
 XY='(-7775,8775)',
 ROT='0',
 VER='1',
 PACK_TYPE='0402LF',
 LOCATION='R441',
 CDS_LIB='pure_quanta',
 CDS_PART_NAME='Q_RES_0402LF-2.2K,5%,1/16W,CHIP,CS22202JB07',
 PART_NUMBER='CS22202JB07',
 VALUE='2.2K',
 PRIM_FILE='./archive_libs/logical/q_res/chips/chips.prt';

PART_NAME
 R442 'Q_RES_0402LF-1K,1%,1/16W,CHIP,CS21002FB06':;

SECTION_NUMBER 1
 '@T6G_MB_LIB.T6G(SCH_1):PAGE28_I56@PURE_QUANTA.Q_RES(CHIPS)':
 C_PATH='@t6g_mb_lib.t6g(sch_1):page28_i56@pure_quanta.q_res(chips)',
 P_PATH='@t6g_mb_lib.t6g(sch_1):page28_i56@pure_quanta.q_res(chips)',
 PATH='I56',
 DRAWING='@T6G_MB_LIB.T6G(SCH_1):PAGE28',
 WATTAGE='1/16W',
 TOLERANCE='1%',
 MATERIAL='CHIP',
 PHYS_PAGE='28',
 XY='(-7775,8725)',
 ROT='0',
 VER='1',
 PACK_TYPE='0402LF',
 LOCATION='R442',
 CDS_LIB='pure_quanta',
 CDS_PART_NAME='Q_RES_0402LF-1K,1%,1/16W,CHIP,CS21002FB06',
 PART_NUMBER='CS21002FB06',
 VALUE='1K',
 PRIM_FILE='./archive_libs/logical/q_res/chips/chips.prt';

PART_NAME
 R443 'Q_RES_0402LF-1K,1%,1/16W,CHIP,CS21002FB06':;

SECTION_NUMBER 1
 '@T6G_MB_LIB.T6G(SCH_1):PAGE28_I53@PURE_QUANTA.Q_RES(CHIPS)':
 C_PATH='@t6g_mb_lib.t6g(sch_1):page28_i53@pure_quanta.q_res(chips)',
 P_PATH='@t6g_mb_lib.t6g(sch_1):page28_i53@pure_quanta.q_res(chips)',
 PATH='I53',
 DRAWING='@T6G_MB_LIB.T6G(SCH_1):PAGE28',
 WATTAGE='1/16W',
 TOLERANCE='1%',
 MATERIAL='CHIP',
 PHYS_PAGE='28',
 XY='(-7775,8675)',
 ROT='0',
 VER='1',
 PACK_TYPE='0402LF',
 LOCATION='R443',
 CDS_LIB='pure_quanta',
 CDS_PART_NAME='Q_RES_0402LF-1K,1%,1/16W,CHIP,CS21002FB06',
 PART_NUMBER='CS21002FB06',
 VALUE='1K',
 PRIM_FILE='./archive_libs/logical/q_res/chips/chips.prt';

PART_NAME
 R444 'Q_RES_0402LF-4.7K,5%,1/16W,CHIP,CS24702JB10':;

SECTION_NUMBER 1
 '@T6G_MB_LIB.T6G(SCH_1):PAGE28_I43@PURE_QUANTA.Q_RES(CHIPS)':
 C_PATH='@t6g_mb_lib.t6g(sch_1):page28_i43@pure_quanta.q_res(chips)',
 P_PATH='@t6g_mb_lib.t6g(sch_1):page28_i43@pure_quanta.q_res(chips)',
 PATH='I43',
 DRAWING='@T6G_MB_LIB.T6G(SCH_1):PAGE28',
 WATTAGE='1/16W',
 TOLERANCE='5%',
 MATERIAL='CHIP',
 PHYS_PAGE='28',
 XY='(-7225,7750)',
 ROT='1',
 VER='1',
 PACK_TYPE='0402LF',
 LOCATION='R444',
 CDS_LIB='pure_quanta',
 CDS_PART_NAME='Q_RES_0402LF-4.7K,5%,1/16W,CHIP,CS24702JB10',
 PART_NUMBER='CS24702JB10',
 VALUE='4.7K',
 PRIM_FILE='./archive_libs/logical/q_res/chips/chips.prt';

PART_NAME
 R445 'Q_RES_0402LF-4.7K,5%,1/16W,CHIP,CS24702JB10':;

SECTION_NUMBER 1
 '@T6G_MB_LIB.T6G(SCH_1):PAGE28_I66@PURE_QUANTA.Q_RES(CHIPS)':
 C_PATH='@t6g_mb_lib.t6g(sch_1):page28_i66@pure_quanta.q_res(chips)',
 P_PATH='@t6g_mb_lib.t6g(sch_1):page28_i66@pure_quanta.q_res(chips)',
 PATH='I66',
 DRAWING='@T6G_MB_LIB.T6G(SCH_1):PAGE28',
 WATTAGE='1/16W',
 TOLERANCE='5%',
 MATERIAL='CHIP',
 PHYS_PAGE='28',
 XY='(-6925,7750)',
 ROT='1',
 VER='1',
 PACK_TYPE='0402LF',
 LOCATION='R445',
 CDS_LIB='pure_quanta',
 CDS_PART_NAME='Q_RES_0402LF-4.7K,5%,1/16W,CHIP,CS24702JB10',
 PART_NUMBER='CS24702JB10',
 VALUE='4.7K',
 PRIM_FILE='./archive_libs/logical/q_res/chips/chips.prt';

PART_NAME
 R446 'Q_RES_0402LF-4.7K,5%,1/16W,CHIP,CS24702JB10':;

SECTION_NUMBER 1
 '@T6G_MB_LIB.T6G(SCH_1):PAGE28_I64@PURE_QUANTA.Q_RES(CHIPS)':
 C_PATH='@t6g_mb_lib.t6g(sch_1):page28_i64@pure_quanta.q_res(chips)',
 P_PATH='@t6g_mb_lib.t6g(sch_1):page28_i64@pure_quanta.q_res(chips)',
 PATH='I64',
 DRAWING='@T6G_MB_LIB.T6G(SCH_1):PAGE28',
 WATTAGE='1/16W',
 TOLERANCE='5%',
 MATERIAL='CHIP',
 PHYS_PAGE='28',
 XY='(-7075,7750)',
 ROT='1',
 VER='1',
 PACK_TYPE='0402LF',
 LOCATION='R446',
 CDS_LIB='pure_quanta',
 CDS_PART_NAME='Q_RES_0402LF-4.7K,5%,1/16W,CHIP,CS24702JB10',
 PART_NUMBER='CS24702JB10',
 VALUE='4.7K',
 PRIM_FILE='./archive_libs/logical/q_res/chips/chips.prt';

PART_NAME
 R447 'Q_RES_0402LF-4.7K,5%,1/16W,CHIP,CS24702JB10':;

SECTION_NUMBER 1
 '@T6G_MB_LIB.T6G(SCH_1):PAGE28_I65@PURE_QUANTA.Q_RES(CHIPS)':
 C_PATH='@t6g_mb_lib.t6g(sch_1):page28_i65@pure_quanta.q_res(chips)',
 P_PATH='@t6g_mb_lib.t6g(sch_1):page28_i65@pure_quanta.q_res(chips)',
 PATH='I65',
 DRAWING='@T6G_MB_LIB.T6G(SCH_1):PAGE28',
 WATTAGE='1/16W',
 TOLERANCE='5%',
 MATERIAL='CHIP',
 PHYS_PAGE='28',
 XY='(-6775,7750)',
 ROT='1',
 VER='1',
 PACK_TYPE='0402LF',
 LOCATION='R447',
 CDS_LIB='pure_quanta',
 CDS_PART_NAME='Q_RES_0402LF-4.7K,5%,1/16W,CHIP,CS24702JB10',
 PART_NUMBER='CS24702JB10',
 VALUE='4.7K',
 PRIM_FILE='./archive_libs/logical/q_res/chips/chips.prt';

PART_NAME
 R448 'Q_RES_0402LF-4.7K,5%,1/16W,EMPTY,CS24702JB10':;

SECTION_NUMBER 1
 '@T6G_MB_LIB.T6G(SCH_1):PAGE28_I49@PURE_QUANTA.Q_RES(CHIPS)':
 C_PATH='@t6g_mb_lib.t6g(sch_1):page28_i49@pure_quanta.q_res(chips)',
 P_PATH='@t6g_mb_lib.t6g(sch_1):page28_i49@pure_quanta.q_res(chips)',
 PATH='I49',
 DRAWING='@T6G_MB_LIB.T6G(SCH_1):PAGE28',
 WATTAGE='1/16W',
 TOLERANCE='5%',
 MATERIAL='EMPTY',
 PHYS_PAGE='28',
 XY='(-7775,8425)',
 ROT='0',
 VER='1',
 PACK_TYPE='0402LF',
 LOCATION='R448',
 CDS_LIB='pure_quanta',
 CDS_PART_NAME='Q_RES_0402LF-4.7K,5%,1/16W,EMPTY,CS24702JB10',
 PART_NUMBER='CS24702JB10',
 VALUE='4.7K',
 PRIM_FILE='./archive_libs/logical/q_res/chips/chips.prt';

PART_NAME
 R449 'Q_RES_0402LF-4.7K,5%,1/16W,EMPTY,CS24702JB10':;

SECTION_NUMBER 1
 '@T6G_MB_LIB.T6G(SCH_1):PAGE28_I48@PURE_QUANTA.Q_RES(CHIPS)':
 C_PATH='@t6g_mb_lib.t6g(sch_1):page28_i48@pure_quanta.q_res(chips)',
 P_PATH='@t6g_mb_lib.t6g(sch_1):page28_i48@pure_quanta.q_res(chips)',
 PATH='I48',
 DRAWING='@T6G_MB_LIB.T6G(SCH_1):PAGE28',
 WATTAGE='1/16W',
 TOLERANCE='5%',
 MATERIAL='EMPTY',
 PHYS_PAGE='28',
 XY='(-7775,8375)',
 ROT='0',
 VER='1',
 PACK_TYPE='0402LF',
 LOCATION='R449',
 CDS_LIB='pure_quanta',
 CDS_PART_NAME='Q_RES_0402LF-4.7K,5%,1/16W,EMPTY,CS24702JB10',
 PART_NUMBER='CS24702JB10',
 VALUE='4.7K',
 PRIM_FILE='./archive_libs/logical/q_res/chips/chips.prt';

PART_NAME
 R450 'Q_RES_0402LF-4.7K,5%,1/16W,CHIP,CS24702JB10':;

SECTION_NUMBER 1
 '@T6G_MB_LIB.T6G(SCH_1):PAGE28_I47@PURE_QUANTA.Q_RES(CHIPS)':
 C_PATH='@t6g_mb_lib.t6g(sch_1):page28_i47@pure_quanta.q_res(chips)',
 P_PATH='@t6g_mb_lib.t6g(sch_1):page28_i47@pure_quanta.q_res(chips)',
 PATH='I47',
 DRAWING='@T6G_MB_LIB.T6G(SCH_1):PAGE28',
 WATTAGE='1/16W',
 TOLERANCE='5%',
 MATERIAL='CHIP',
 PHYS_PAGE='28',
 XY='(-7775,8325)',
 ROT='0',
 VER='1',
 PACK_TYPE='0402LF',
 LOCATION='R450',
 CDS_LIB='pure_quanta',
 CDS_PART_NAME='Q_RES_0402LF-4.7K,5%,1/16W,CHIP,CS24702JB10',
 PART_NUMBER='CS24702JB10',
 VALUE='4.7K',
 PRIM_FILE='./archive_libs/logical/q_res/chips/chips.prt';

PART_NAME
 R451 'Q_RES_0402LF-4.7K,5%,1/16W,CHIP,CS24702JB10':;

SECTION_NUMBER 1
 '@T6G_MB_LIB.T6G(SCH_1):PAGE28_I46@PURE_QUANTA.Q_RES(CHIPS)':
 C_PATH='@t6g_mb_lib.t6g(sch_1):page28_i46@pure_quanta.q_res(chips)',
 P_PATH='@t6g_mb_lib.t6g(sch_1):page28_i46@pure_quanta.q_res(chips)',
 PATH='I46',
 DRAWING='@T6G_MB_LIB.T6G(SCH_1):PAGE28',
 WATTAGE='1/16W',
 TOLERANCE='5%',
 MATERIAL='CHIP',
 PHYS_PAGE='28',
 XY='(-7775,8275)',
 ROT='0',
 VER='1',
 PACK_TYPE='0402LF',
 LOCATION='R451',
 CDS_LIB='pure_quanta',
 CDS_PART_NAME='Q_RES_0402LF-4.7K,5%,1/16W,CHIP,CS24702JB10',
 PART_NUMBER='CS24702JB10',
 VALUE='4.7K',
 PRIM_FILE='./archive_libs/logical/q_res/chips/chips.prt';

PART_NAME
 R452 'Q_RES_0402LF-4.7K,5%,1/16W,CHIP,CS24702JB10':;

SECTION_NUMBER 1
 '@T6G_MB_LIB.T6G(SCH_1):PAGE28_I45@PURE_QUANTA.Q_RES(CHIPS)':
 C_PATH='@t6g_mb_lib.t6g(sch_1):page28_i45@pure_quanta.q_res(chips)',
 P_PATH='@t6g_mb_lib.t6g(sch_1):page28_i45@pure_quanta.q_res(chips)',
 PATH='I45',
 DRAWING='@T6G_MB_LIB.T6G(SCH_1):PAGE28',
 WATTAGE='1/16W',
 TOLERANCE='5%',
 MATERIAL='CHIP',
 PHYS_PAGE='28',
 XY='(-7775,8225)',
 ROT='0',
 VER='1',
 PACK_TYPE='0402LF',
 LOCATION='R452',
 CDS_LIB='pure_quanta',
 CDS_PART_NAME='Q_RES_0402LF-4.7K,5%,1/16W,CHIP,CS24702JB10',
 PART_NUMBER='CS24702JB10',
 VALUE='4.7K',
 PRIM_FILE='./archive_libs/logical/q_res/chips/chips.prt';

PART_NAME
 R453 'Q_RES_0402LF-10K,5%,1/16W,CHIP,CS31002JB08':;

SECTION_NUMBER 1
 '@T6G_MB_LIB.T6G(SCH_1):PAGE167_I31@PURE_QUANTA.Q_RES(CHIPS)':
 C_PATH='@t6g_mb_lib.t6g(sch_1):page167_i31@pure_quanta.q_res(chips)',
 P_PATH='@t6g_mb_lib.t6g(sch_1):page192_i31@pure_quanta.q_res(chips)',
 PATH='I31',
 DRAWING='@T6G_MB_LIB.T6G(SCH_1):PAGE167',
 SEC_TYPE='0402LF',
 WATTAGE='1/16W',
 TOLERANCE='5%',
 MATERIAL='CHIP',
 PHYS_PAGE='192',
 XY='(-6375,4450)',
 ROT='0',
 VER='2',
 PACK_TYPE='0402LF',
 LOCATION='R453',
 SEC='1',
 CDS_LIB='pure_quanta',
 CDS_PART_NAME='Q_RES_0402LF-10K,5%,1/16W,CHIP,CS31002JB08',
 PART_NUMBER='CS31002JB08',
 VALUE='10K',
 PRIM_FILE='./archive_libs/logical/q_res/chips/chips.prt';

PART_NAME
 R454 'Q_RES_0402LF-10K,5%,1/16W,CHIP,CS31002JB08':;

SECTION_NUMBER 1
 '@T6G_MB_LIB.T6G(SCH_1):PAGE29_I383@PURE_QUANTA.Q_RES(CHIPS)':
 C_PATH='@t6g_mb_lib.t6g(sch_1):page29_i383@pure_quanta.q_res(chips)',
 P_PATH='@t6g_mb_lib.t6g(sch_1):page29_i383@pure_quanta.q_res(chips)',
 PATH='I383',
 DRAWING='@T6G_MB_LIB.T6G(SCH_1):PAGE29',
 BOM_COST='I/O CONNECTOR',
 WATTAGE='1/16W',
 TOLERANCE='5%',
 MATERIAL='CHIP',
 PHYS_PAGE='29',
 XY='(-2350,2575)',
 ROT='0',
 VER='2',
 PACK_TYPE='0402LF',
 LOCATION='R454',
 CDS_LIB='pure_quanta',
 CDS_PART_NAME='Q_RES_0402LF-10K,5%,1/16W,CHIP,CS31002JB08',
 PART_NUMBER='CS31002JB08',
 VALUE='10K',
 PRIM_FILE='./archive_libs/logical/q_res/chips/chips.prt';

PART_NAME
 R455 'Q_RES_0402LF-4.7K,5%,1/16W,EMPTY,CS24702JB10':;

SECTION_NUMBER 1
 '@T6G_MB_LIB.T6G(SCH_1):PAGE29_I284@PURE_QUANTA.Q_RES(CHIPS)':
 C_PATH='@t6g_mb_lib.t6g(sch_1):page29_i284@pure_quanta.q_res(chips)',
 P_PATH='@t6g_mb_lib.t6g(sch_1):page29_i284@pure_quanta.q_res(chips)',
 PATH='I284',
 DRAWING='@T6G_MB_LIB.T6G(SCH_1):PAGE29',
 WATTAGE='1/16W',
 TOLERANCE='5%',
 MATERIAL='EMPTY',
 PHYS_PAGE='29',
 XY='(-8150,3250)',
 ROT='0',
 VER='2',
 PACK_TYPE='0402LF',
 LOCATION='R455',
 CDS_LIB='pure_quanta',
 CDS_PART_NAME='Q_RES_0402LF-4.7K,5%,1/16W,EMPTY,CS24702JB10',
 PART_NUMBER='CS24702JB10',
 VALUE='4.7K',
 PRIM_FILE='./archive_libs/logical/q_res/chips/chips.prt';

PART_NAME
 R456 'Q_RES_0402LF-4.7K,5%,1/16W,EMPTY,CS24702JB10':;

SECTION_NUMBER 1
 '@T6G_MB_LIB.T6G(SCH_1):PAGE55_I339@PURE_QUANTA.Q_RES(CHIPS)':
 C_PATH='@t6g_mb_lib.t6g(sch_1):page55_i339@pure_quanta.q_res(chips)',
 P_PATH='@t6g_mb_lib.t6g(sch_1):page55_i339@pure_quanta.q_res(chips)',
 PATH='I339',
 DRAWING='@T6G_MB_LIB.T6G(SCH_1):PAGE55',
 WATTAGE='1/16W',
 TOLERANCE='5%',
 MATERIAL='EMPTY',
 PHYS_PAGE='55',
 XY='(-8700,1150)',
 ROT='1',
 VER='1',
 PACK_TYPE='0402LF',
 LOCATION='R456',
 CDS_LIB='pure_quanta',
 CDS_PART_NAME='Q_RES_0402LF-4.7K,5%,1/16W,EMPTY,CS24702JB10',
 PART_NUMBER='CS24702JB10',
 VALUE='4.7K',
 PRIM_FILE='./archive_libs/logical/q_res/chips/chips.prt';

PART_NAME
 R457 'Q_RES_0402LF-4.7K,5%,1/16W,EMPTY,CS24702JB10':;

SECTION_NUMBER 1
 '@T6G_MB_LIB.T6G(SCH_1):PAGE29_I282@PURE_QUANTA.Q_RES(CHIPS)':
 C_PATH='@t6g_mb_lib.t6g(sch_1):page29_i282@pure_quanta.q_res(chips)',
 P_PATH='@t6g_mb_lib.t6g(sch_1):page29_i282@pure_quanta.q_res(chips)',
 PATH='I282',
 DRAWING='@T6G_MB_LIB.T6G(SCH_1):PAGE29',
 WATTAGE='1/16W',
 TOLERANCE='5%',
 MATERIAL='EMPTY',
 PHYS_PAGE='29',
 XY='(-7925,3225)',
 ROT='0',
 VER='2',
 PACK_TYPE='0402LF',
 LOCATION='R457',
 CDS_LIB='pure_quanta',
 CDS_PART_NAME='Q_RES_0402LF-4.7K,5%,1/16W,EMPTY,CS24702JB10',
 PART_NUMBER='CS24702JB10',
 VALUE='4.7K',
 PRIM_FILE='./archive_libs/logical/q_res/chips/chips.prt';

PART_NAME
 R458 'Q_RES_0402LF-30K,1%,1/16W,EMPTY,CS33002FB02':;

SECTION_NUMBER 1
 '@T6G_MB_LIB.T6G(SCH_1):PAGE29_I405@PURE_QUANTA.Q_RES(CHIPS)':
 C_PATH='@t6g_mb_lib.t6g(sch_1):page29_i405@pure_quanta.q_res(chips)',
 P_PATH='@t6g_mb_lib.t6g(sch_1):page29_i405@pure_quanta.q_res(chips)',
 PATH='I405',
 DRAWING='@T6G_MB_LIB.T6G(SCH_1):PAGE29',
 WATTAGE='1/16W',
 TOLERANCE='1%',
 MATERIAL='EMPTY',
 PHYS_PAGE='29',
 XY='(-7750,2150)',
 ROT='0',
 VER='1',
 PACK_TYPE='0402LF',
 LOCATION='R458',
 CDS_LIB='pure_quanta',
 CDS_PART_NAME='Q_RES_0402LF-30K,1%,1/16W,EMPTY,CS33002FB02',
 PART_NUMBER='CS33002FB02',
 VALUE='30K',
 PRIM_FILE='./archive_libs/logical/q_res/chips/chips.prt';

PART_NAME
 R459 'Q_RES_0402LF-33,5%,1/16W,CHIP,CS03302JB10':;

SECTION_NUMBER 1
 '@T6G_MB_LIB.T6G(SCH_1):PAGE29_I407@PURE_QUANTA.Q_RES(CHIPS)':
 C_PATH='@t6g_mb_lib.t6g(sch_1):page29_i407@pure_quanta.q_res(chips)',
 P_PATH='@t6g_mb_lib.t6g(sch_1):page29_i407@pure_quanta.q_res(chips)',
 PATH='I407',
 DRAWING='@T6G_MB_LIB.T6G(SCH_1):PAGE29',
 WATTAGE='1/16W',
 TOLERANCE='5%',
 MATERIAL='CHIP',
 PHYS_PAGE='29',
 XY='(-6950,5900)',
 ROT='0',
 VER='1',
 PACK_TYPE='0402LF',
 LOCATION='R459',
 CDS_LIB='pure_quanta',
 CDS_PART_NAME='Q_RES_0402LF-33,5%,1/16W,CHIP,CS03302JB10',
 PART_NUMBER='CS03302JB10',
 VALUE='33',
 PRIM_FILE='./archive_libs/logical/q_res/chips/chips.prt';

PART_NAME
 R460 'Q_RES_0402LF-33,5%,1/16W,CHIP,CS03302JB10':;

SECTION_NUMBER 1
 '@T6G_MB_LIB.T6G(SCH_1):PAGE29_I408@PURE_QUANTA.Q_RES(CHIPS)':
 C_PATH='@t6g_mb_lib.t6g(sch_1):page29_i408@pure_quanta.q_res(chips)',
 P_PATH='@t6g_mb_lib.t6g(sch_1):page29_i408@pure_quanta.q_res(chips)',
 PATH='I408',
 DRAWING='@T6G_MB_LIB.T6G(SCH_1):PAGE29',
 WATTAGE='1/16W',
 TOLERANCE='5%',
 MATERIAL='CHIP',
 PHYS_PAGE='29',
 XY='(-6950,5850)',
 ROT='0',
 VER='1',
 PACK_TYPE='0402LF',
 LOCATION='R460',
 CDS_LIB='pure_quanta',
 CDS_PART_NAME='Q_RES_0402LF-33,5%,1/16W,CHIP,CS03302JB10',
 PART_NUMBER='CS03302JB10',
 VALUE='33',
 PRIM_FILE='./archive_libs/logical/q_res/chips/chips.prt';

PART_NAME
 R461 'Q_RES_0402LF-33,5%,1/16W,CHIP,CS03302JB10':;

SECTION_NUMBER 1
 '@T6G_MB_LIB.T6G(SCH_1):PAGE29_I409@PURE_QUANTA.Q_RES(CHIPS)':
 C_PATH='@t6g_mb_lib.t6g(sch_1):page29_i409@pure_quanta.q_res(chips)',
 P_PATH='@t6g_mb_lib.t6g(sch_1):page29_i409@pure_quanta.q_res(chips)',
 PATH='I409',
 DRAWING='@T6G_MB_LIB.T6G(SCH_1):PAGE29',
 WATTAGE='1/16W',
 TOLERANCE='5%',
 MATERIAL='CHIP',
 PHYS_PAGE='29',
 XY='(-6950,5650)',
 ROT='0',
 VER='1',
 PACK_TYPE='0402LF',
 LOCATION='R461',
 CDS_LIB='pure_quanta',
 CDS_PART_NAME='Q_RES_0402LF-33,5%,1/16W,CHIP,CS03302JB10',
 PART_NUMBER='CS03302JB10',
 VALUE='33',
 PRIM_FILE='./archive_libs/logical/q_res/chips/chips.prt';

PART_NAME
 R462 'Q_RES_0402LF-33,5%,1/16W,EMPTY,CS03302JB10':;

SECTION_NUMBER 1
 '@T6G_MB_LIB.T6G(SCH_1):PAGE29_I425@PURE_QUANTA.Q_RES(CHIPS)':
 C_PATH='@t6g_mb_lib.t6g(sch_1):page29_i425@pure_quanta.q_res(chips)',
 P_PATH='@t6g_mb_lib.t6g(sch_1):page29_i425@pure_quanta.q_res(chips)',
 PATH='I425',
 DRAWING='@T6G_MB_LIB.T6G(SCH_1):PAGE29',
 WATTAGE='1/16W',
 TOLERANCE='5%',
 MATERIAL='EMPTY',
 PHYS_PAGE='29',
 XY='(-6950,5550)',
 ROT='0',
 VER='1',
 PACK_TYPE='0402LF',
 LOCATION='R462',
 CDS_LIB='pure_quanta',
 CDS_PART_NAME='Q_RES_0402LF-33,5%,1/16W,EMPTY,CS03302JB10',
 PART_NUMBER='CS03302JB10',
 VALUE='33',
 PRIM_FILE='./archive_libs/logical/q_res/chips/chips.prt';

PART_NAME
 R463 'Q_RES_0402LF-33,5%,1/16W,CHIP,CS03302JB10':;

SECTION_NUMBER 1
 '@T6G_MB_LIB.T6G(SCH_1):PAGE80_I112@PURE_QUANTA.Q_RES(CHIPS)':
 C_PATH='@t6g_mb_lib.t6g(sch_1):page80_i112@pure_quanta.q_res(chips)',
 P_PATH='@t6g_mb_lib.t6g(sch_1):page81_i112@pure_quanta.q_res(chips)',
 PATH='I112',
 DRAWING='@T6G_MB_LIB.T6G(SCH_1):PAGE80',
 WATTAGE='1/16W',
 TOLERANCE='5%',
 MATERIAL='CHIP',
 PHYS_PAGE='81',
 XY='(-6425,5075)',
 ROT='0',
 VER='1',
 PACK_TYPE='0402LF',
 LOCATION='R463',
 CDS_LIB='pure_quanta',
 CDS_PART_NAME='Q_RES_0402LF-33,5%,1/16W,CHIP,CS03302JB10',
 PART_NUMBER='CS03302JB10',
 VALUE='33',
 PRIM_FILE='./archive_libs/logical/q_res/chips/chips.prt';

PART_NAME
 R464 'Q_RES_0402LF-33,5%,1/16W,CHIP,CS03302JB10':;

SECTION_NUMBER 1
 '@T6G_MB_LIB.T6G(SCH_1):PAGE29_I410@PURE_QUANTA.Q_RES(CHIPS)':
 C_PATH='@t6g_mb_lib.t6g(sch_1):page29_i410@pure_quanta.q_res(chips)',
 P_PATH='@t6g_mb_lib.t6g(sch_1):page29_i410@pure_quanta.q_res(chips)',
 PATH='I410',
 DRAWING='@T6G_MB_LIB.T6G(SCH_1):PAGE29',
 WATTAGE='1/16W',
 TOLERANCE='5%',
 MATERIAL='CHIP',
 PHYS_PAGE='29',
 XY='(-6950,5250)',
 ROT='0',
 VER='1',
 PACK_TYPE='0402LF',
 LOCATION='R464',
 CDS_LIB='pure_quanta',
 CDS_PART_NAME='Q_RES_0402LF-33,5%,1/16W,CHIP,CS03302JB10',
 PART_NUMBER='CS03302JB10',
 VALUE='33',
 PRIM_FILE='./archive_libs/logical/q_res/chips/chips.prt';

PART_NAME
 R465 'Q_RES_0402LF-49.9,1%,1/16W,CHIP,CS04992FB07':;

SECTION_NUMBER 1
 '@T6G_MB_LIB.T6G(SCH_1):PAGE29_I411@PURE_QUANTA.Q_RES(CHIPS)':
 C_PATH='@t6g_mb_lib.t6g(sch_1):page29_i411@pure_quanta.q_res(chips)',
 P_PATH='@t6g_mb_lib.t6g(sch_1):page29_i411@pure_quanta.q_res(chips)',
 PATH='I411',
 DRAWING='@T6G_MB_LIB.T6G(SCH_1):PAGE29',
 WATTAGE='1/16W',
 TOLERANCE='1%',
 MATERIAL='CHIP',
 PHYS_PAGE='29',
 XY='(-6950,5200)',
 ROT='0',
 VER='1',
 PACK_TYPE='0402LF',
 LOCATION='R465',
 CDS_LIB='pure_quanta',
 CDS_PART_NAME='Q_RES_0402LF-49.9,1%,1/16W,CHIP,CS04992FB07',
 PART_NUMBER='CS04992FB07',
 VALUE='49.9',
 PRIM_FILE='./archive_libs/logical/q_res/chips/chips.prt';

PART_NAME
 R466 'Q_RES_0402LF-33,5%,1/16W,CHIP,CS03302JB10':;

SECTION_NUMBER 1
 '@T6G_MB_LIB.T6G(SCH_1):PAGE29_I412@PURE_QUANTA.Q_RES(CHIPS)':
 C_PATH='@t6g_mb_lib.t6g(sch_1):page29_i412@pure_quanta.q_res(chips)',
 P_PATH='@t6g_mb_lib.t6g(sch_1):page29_i412@pure_quanta.q_res(chips)',
 PATH='I412',
 DRAWING='@T6G_MB_LIB.T6G(SCH_1):PAGE29',
 WATTAGE='1/16W',
 TOLERANCE='5%',
 MATERIAL='CHIP',
 PHYS_PAGE='29',
 XY='(-6950,5150)',
 ROT='0',
 VER='1',
 PACK_TYPE='0402LF',
 LOCATION='R466',
 CDS_LIB='pure_quanta',
 CDS_PART_NAME='Q_RES_0402LF-33,5%,1/16W,CHIP,CS03302JB10',
 PART_NUMBER='CS03302JB10',
 VALUE='33',
 PRIM_FILE='./archive_libs/logical/q_res/chips/chips.prt';

PART_NAME
 R467 'Q_RES_0402LF-33,5%,1/16W,CHIP,CS03302JB10':;

SECTION_NUMBER 1
 '@T6G_MB_LIB.T6G(SCH_1):PAGE29_I413@PURE_QUANTA.Q_RES(CHIPS)':
 C_PATH='@t6g_mb_lib.t6g(sch_1):page29_i413@pure_quanta.q_res(chips)',
 P_PATH='@t6g_mb_lib.t6g(sch_1):page29_i413@pure_quanta.q_res(chips)',
 PATH='I413',
 DRAWING='@T6G_MB_LIB.T6G(SCH_1):PAGE29',
 WATTAGE='1/16W',
 TOLERANCE='5%',
 MATERIAL='CHIP',
 PHYS_PAGE='29',
 XY='(-6950,5100)',
 ROT='0',
 VER='1',
 PACK_TYPE='0402LF',
 LOCATION='R467',
 CDS_LIB='pure_quanta',
 CDS_PART_NAME='Q_RES_0402LF-33,5%,1/16W,CHIP,CS03302JB10',
 PART_NUMBER='CS03302JB10',
 VALUE='33',
 PRIM_FILE='./archive_libs/logical/q_res/chips/chips.prt';

PART_NAME
 R468 'Q_RES_0402LF-33,5%,1/16W,CHIP,CS03302JB10':;

SECTION_NUMBER 1
 '@T6G_MB_LIB.T6G(SCH_1):PAGE29_I329@PURE_QUANTA.Q_RES(CHIPS)':
 C_PATH='@t6g_mb_lib.t6g(sch_1):page29_i329@pure_quanta.q_res(chips)',
 P_PATH='@t6g_mb_lib.t6g(sch_1):page29_i329@pure_quanta.q_res(chips)',
 PATH='I329',
 DRAWING='@T6G_MB_LIB.T6G(SCH_1):PAGE29',
 WATTAGE='1/16W',
 TOLERANCE='5%',
 MATERIAL='CHIP',
 PHYS_PAGE='29',
 XY='(-6950,4950)',
 ROT='0',
 VER='1',
 PACK_TYPE='0402LF',
 LOCATION='R468',
 CDS_LIB='pure_quanta',
 CDS_PART_NAME='Q_RES_0402LF-33,5%,1/16W,CHIP,CS03302JB10',
 PART_NUMBER='CS03302JB10',
 VALUE='33',
 PRIM_FILE='./archive_libs/logical/q_res/chips/chips.prt';

PART_NAME
 R469 'Q_RES_0402LF-33,5%,1/16W,CHIP,CS03302JB10':;

SECTION_NUMBER 1
 '@T6G_MB_LIB.T6G(SCH_1):PAGE29_I328@PURE_QUANTA.Q_RES(CHIPS)':
 C_PATH='@t6g_mb_lib.t6g(sch_1):page29_i328@pure_quanta.q_res(chips)',
 P_PATH='@t6g_mb_lib.t6g(sch_1):page29_i328@pure_quanta.q_res(chips)',
 PATH='I328',
 DRAWING='@T6G_MB_LIB.T6G(SCH_1):PAGE29',
 WATTAGE='1/16W',
 TOLERANCE='5%',
 MATERIAL='CHIP',
 PHYS_PAGE='29',
 XY='(-6950,4900)',
 ROT='0',
 VER='1',
 PACK_TYPE='0402LF',
 LOCATION='R469',
 CDS_LIB='pure_quanta',
 CDS_PART_NAME='Q_RES_0402LF-33,5%,1/16W,CHIP,CS03302JB10',
 PART_NUMBER='CS03302JB10',
 VALUE='33',
 PRIM_FILE='./archive_libs/logical/q_res/chips/chips.prt';

PART_NAME
 R470 'Q_RES_0402LF-33,5%,1/16W,CHIP,CS03302JB10':;

SECTION_NUMBER 1
 '@T6G_MB_LIB.T6G(SCH_1):PAGE29_I327@PURE_QUANTA.Q_RES(CHIPS)':
 C_PATH='@t6g_mb_lib.t6g(sch_1):page29_i327@pure_quanta.q_res(chips)',
 P_PATH='@t6g_mb_lib.t6g(sch_1):page29_i327@pure_quanta.q_res(chips)',
 PATH='I327',
 DRAWING='@T6G_MB_LIB.T6G(SCH_1):PAGE29',
 WATTAGE='1/16W',
 TOLERANCE='5%',
 MATERIAL='CHIP',
 PHYS_PAGE='29',
 XY='(-6950,4850)',
 ROT='0',
 VER='1',
 PACK_TYPE='0402LF',
 LOCATION='R470',
 CDS_LIB='pure_quanta',
 CDS_PART_NAME='Q_RES_0402LF-33,5%,1/16W,CHIP,CS03302JB10',
 PART_NUMBER='CS03302JB10',
 VALUE='33',
 PRIM_FILE='./archive_libs/logical/q_res/chips/chips.prt';

PART_NAME
 R471 'Q_RES_0402LF-33,5%,1/16W,CHIP,CS03302JB10':;

SECTION_NUMBER 1
 '@T6G_MB_LIB.T6G(SCH_1):PAGE29_I330@PURE_QUANTA.Q_RES(CHIPS)':
 C_PATH='@t6g_mb_lib.t6g(sch_1):page29_i330@pure_quanta.q_res(chips)',
 P_PATH='@t6g_mb_lib.t6g(sch_1):page29_i330@pure_quanta.q_res(chips)',
 PATH='I330',
 DRAWING='@T6G_MB_LIB.T6G(SCH_1):PAGE29',
 WATTAGE='1/16W',
 TOLERANCE='5%',
 MATERIAL='CHIP',
 PHYS_PAGE='29',
 XY='(-6950,4800)',
 ROT='0',
 VER='1',
 PACK_TYPE='0402LF',
 LOCATION='R471',
 CDS_LIB='pure_quanta',
 CDS_PART_NAME='Q_RES_0402LF-33,5%,1/16W,CHIP,CS03302JB10',
 PART_NUMBER='CS03302JB10',
 VALUE='33',
 PRIM_FILE='./archive_libs/logical/q_res/chips/chips.prt';

PART_NAME
 R472 'Q_RES_0402LF-33,5%,1/16W,EMPTY,CS03302JB10':;

SECTION_NUMBER 1
 '@T6G_MB_LIB.T6G(SCH_1):PAGE29_I428@PURE_QUANTA.Q_RES(CHIPS)':
 C_PATH='@t6g_mb_lib.t6g(sch_1):page29_i428@pure_quanta.q_res(chips)',
 P_PATH='@t6g_mb_lib.t6g(sch_1):page29_i428@pure_quanta.q_res(chips)',
 PATH='I428',
 DRAWING='@T6G_MB_LIB.T6G(SCH_1):PAGE29',
 WATTAGE='1/16W',
 TOLERANCE='5%',
 MATERIAL='EMPTY',
 PHYS_PAGE='29',
 XY='(-6950,4650)',
 ROT='0',
 VER='1',
 PACK_TYPE='0402LF',
 LOCATION='R472',
 CDS_LIB='pure_quanta',
 CDS_PART_NAME='Q_RES_0402LF-33,5%,1/16W,EMPTY,CS03302JB10',
 PART_NUMBER='CS03302JB10',
 VALUE='33',
 PRIM_FILE='./archive_libs/logical/q_res/chips/chips.prt';

PART_NAME
 R473 'Q_RES_0402LF-0,5%,1/16W,CHIP,CS00002JB13':;

SECTION_NUMBER 1
 '@T6G_MB_LIB.T6G(SCH_1):PAGE29_I430@PURE_QUANTA.Q_RES(CHIPS)':
 C_PATH='@t6g_mb_lib.t6g(sch_1):page29_i430@pure_quanta.q_res(chips)',
 P_PATH='@t6g_mb_lib.t6g(sch_1):page29_i430@pure_quanta.q_res(chips)',
 PATH='I430',
 DRAWING='@T6G_MB_LIB.T6G(SCH_1):PAGE29',
 WATTAGE='1/16W',
 TOLERANCE='5%',
 MATERIAL='CHIP',
 PHYS_PAGE='29',
 XY='(-6950,4450)',
 ROT='0',
 VER='1',
 PACK_TYPE='0402LF',
 LOCATION='R473',
 CDS_LIB='pure_quanta',
 CDS_PART_NAME='Q_RES_0402LF-0,5%,1/16W,CHIP,CS00002JB13',
 PART_NUMBER='CS00002JB13',
 VALUE='0',
 PRIM_FILE='./archive_libs/logical/q_res/chips/chips.prt';

PART_NAME
 R474 'Q_RES_0402LF-0,5%,1/16W,CHIP,CS00002JB13':;

SECTION_NUMBER 1
 '@T6G_MB_LIB.T6G(SCH_1):PAGE29_I332@PURE_QUANTA.Q_RES(CHIPS)':
 C_PATH='@t6g_mb_lib.t6g(sch_1):page29_i332@pure_quanta.q_res(chips)',
 P_PATH='@t6g_mb_lib.t6g(sch_1):page29_i332@pure_quanta.q_res(chips)',
 PATH='I332',
 DRAWING='@T6G_MB_LIB.T6G(SCH_1):PAGE29',
 WATTAGE='1/16W',
 TOLERANCE='5%',
 MATERIAL='CHIP',
 PHYS_PAGE='29',
 XY='(-6950,4350)',
 ROT='0',
 VER='1',
 PACK_TYPE='0402LF',
 LOCATION='R474',
 CDS_LIB='pure_quanta',
 CDS_PART_NAME='Q_RES_0402LF-0,5%,1/16W,CHIP,CS00002JB13',
 PART_NUMBER='CS00002JB13',
 VALUE='0',
 PRIM_FILE='./archive_libs/logical/q_res/chips/chips.prt';

PART_NAME
 R475 'Q_RES_0402LF-33,5%,1/16W,CHIP,CS03302JB10':;

SECTION_NUMBER 1
 '@T6G_MB_LIB.T6G(SCH_1):PAGE29_I414@PURE_QUANTA.Q_RES(CHIPS)':
 C_PATH='@t6g_mb_lib.t6g(sch_1):page29_i414@pure_quanta.q_res(chips)',
 P_PATH='@t6g_mb_lib.t6g(sch_1):page29_i414@pure_quanta.q_res(chips)',
 PATH='I414',
 DRAWING='@T6G_MB_LIB.T6G(SCH_1):PAGE29',
 WATTAGE='1/16W',
 TOLERANCE='5%',
 MATERIAL='CHIP',
 PHYS_PAGE='29',
 XY='(-6950,4250)',
 ROT='0',
 VER='1',
 PACK_TYPE='0402LF',
 LOCATION='R475',
 CDS_LIB='pure_quanta',
 CDS_PART_NAME='Q_RES_0402LF-33,5%,1/16W,CHIP,CS03302JB10',
 PART_NUMBER='CS03302JB10',
 VALUE='33',
 PRIM_FILE='./archive_libs/logical/q_res/chips/chips.prt';

PART_NAME
 R476 'Q_RES_0402LF-33,5%,1/16W,CHIP,CS03302JB10':;

SECTION_NUMBER 1
 '@T6G_MB_LIB.T6G(SCH_1):PAGE149_I148@PURE_QUANTA.Q_RES(CHIPS)':
 C_PATH='@t6g_mb_lib.t6g(sch_1):page149_i148@pure_quanta.q_res(chips)',
 P_PATH='@t6g_mb_lib.t6g(sch_1):page172_i148@pure_quanta.q_res(chips)',
 PATH='I148',
 DRAWING='@T6G_MB_LIB.T6G(SCH_1):PAGE149',
 WATTAGE='1/16W',
 TOLERANCE='5%',
 MATERIAL='CHIP',
 PHYS_PAGE='172',
 XY='(-6300,5700)',
 ROT='0',
 VER='1',
 PACK_TYPE='0402LF',
 LOCATION='R476',
 CDS_LIB='pure_quanta',
 CDS_PART_NAME='Q_RES_0402LF-33,5%,1/16W,CHIP,CS03302JB10',
 PART_NUMBER='CS03302JB10',
 VALUE='33',
 PRIM_FILE='./archive_libs/logical/q_res/chips/chips.prt';

PART_NAME
 R477 'Q_RES_0402LF-33,5%,1/16W,CHIP,CS03302JB10':;

SECTION_NUMBER 1
 '@T6G_MB_LIB.T6G(SCH_1):PAGE149_I147@PURE_QUANTA.Q_RES(CHIPS)':
 C_PATH='@t6g_mb_lib.t6g(sch_1):page149_i147@pure_quanta.q_res(chips)',
 P_PATH='@t6g_mb_lib.t6g(sch_1):page172_i147@pure_quanta.q_res(chips)',
 PATH='I147',
 DRAWING='@T6G_MB_LIB.T6G(SCH_1):PAGE149',
 WATTAGE='1/16W',
 TOLERANCE='5%',
 MATERIAL='CHIP',
 PHYS_PAGE='172',
 XY='(-6300,5650)',
 ROT='0',
 VER='1',
 PACK_TYPE='0402LF',
 LOCATION='R477',
 CDS_LIB='pure_quanta',
 CDS_PART_NAME='Q_RES_0402LF-33,5%,1/16W,CHIP,CS03302JB10',
 PART_NUMBER='CS03302JB10',
 VALUE='33',
 PRIM_FILE='./archive_libs/logical/q_res/chips/chips.prt';

PART_NAME
 R478 'Q_RES_0402LF-33,5%,1/16W,CHIP,CS03302JB10':;

SECTION_NUMBER 1
 '@T6G_MB_LIB.T6G(SCH_1):PAGE149_I150@PURE_QUANTA.Q_RES(CHIPS)':
 C_PATH='@t6g_mb_lib.t6g(sch_1):page149_i150@pure_quanta.q_res(chips)',
 P_PATH='@t6g_mb_lib.t6g(sch_1):page172_i150@pure_quanta.q_res(chips)',
 PATH='I150',
 DRAWING='@T6G_MB_LIB.T6G(SCH_1):PAGE149',
 WATTAGE='1/16W',
 TOLERANCE='5%',
 MATERIAL='CHIP',
 PHYS_PAGE='172',
 XY='(-6300,5600)',
 ROT='0',
 VER='1',
 PACK_TYPE='0402LF',
 LOCATION='R478',
 CDS_LIB='pure_quanta',
 CDS_PART_NAME='Q_RES_0402LF-33,5%,1/16W,CHIP,CS03302JB10',
 PART_NUMBER='CS03302JB10',
 VALUE='33',
 PRIM_FILE='./archive_libs/logical/q_res/chips/chips.prt';

PART_NAME
 R479 'Q_RES_0402LF-10K,1%,1/16W,CHIP,CS31002FB08':;

SECTION_NUMBER 1
 '@T6G_MB_LIB.T6G(SCH_1):PAGE273_I83@PURE_QUANTA.Q_RES(CHIPS)':
 C_PATH='@t6g_mb_lib.t6g(sch_1):page273_i83@pure_quanta.q_res(chips)',
 P_PATH='@t6g_mb_lib.t6g(sch_1):page188_i83@pure_quanta.q_res(chips)',
 PATH='I83',
 DRAWING='@T6G_MB_LIB.T6G(SCH_1):PAGE273',
 SEC_TYPE='0402LF',
 WATTAGE='1/16W',
 TOLERANCE='1%',
 MATERIAL='CHIP',
 PHYS_PAGE='188',
 XY='(-2875,4250)',
 ROT='0',
 VER='2',
 PACK_TYPE='0402LF',
 LOCATION='R479',
 SEC='1',
 CDS_LIB='pure_quanta',
 CDS_PART_NAME='Q_RES_0402LF-10K,1%,1/16W,CHIP,CS31002FB08',
 PART_NUMBER='CS31002FB08',
 VALUE='10K',
 PRIM_FILE='./archive_libs/logical/q_res/chips/chips.prt';

PART_NAME
 R480 'Q_RES_0402LF-100K,1%,1/16W,CHIP,CS41002FB09':;

SECTION_NUMBER 1
 '@T6G_MB_LIB.T6G(SCH_1):PAGE273_I84@PURE_QUANTA.Q_RES(CHIPS)':
 C_PATH='@t6g_mb_lib.t6g(sch_1):page273_i84@pure_quanta.q_res(chips)',
 P_PATH='@t6g_mb_lib.t6g(sch_1):page188_i84@pure_quanta.q_res(chips)',
 PATH='I84',
 DRAWING='@T6G_MB_LIB.T6G(SCH_1):PAGE273',
 SEC_TYPE='0402LF',
 WATTAGE='1/16W',
 TOLERANCE='1%',
 MATERIAL='CHIP',
 PHYS_PAGE='188',
 XY='(-2800,3725)',
 ROT='2',
 VER='2',
 PACK_TYPE='0402LF',
 LOCATION='R480',
 SEC='1',
 CDS_LIB='pure_quanta',
 CDS_PART_NAME='Q_RES_0402LF-100K,1%,1/16W,CHIP,CS41002FB09',
 PART_NUMBER='CS41002FB09',
 VALUE='100K',
 PRIM_FILE='./archive_libs/logical/q_res/chips/chips.prt';

PART_NAME
 R481 'Q_RES_0402LF-0,5%,1/16W,CHIP,CS00002JB13':;

SECTION_NUMBER 1
 '@T6G_MB_LIB.T6G(SCH_1):PAGE27_I335@PURE_QUANTA.Q_RES(CHIPS)':
 C_PATH='@t6g_mb_lib.t6g(sch_1):page27_i335@pure_quanta.q_res(chips)',
 P_PATH='@t6g_mb_lib.t6g(sch_1):page27_i335@pure_quanta.q_res(chips)',
 PATH='I335',
 DRAWING='@T6G_MB_LIB.T6G(SCH_1):PAGE27',
 WATTAGE='1/16W',
 TOLERANCE='5%',
 MATERIAL='CHIP',
 PHYS_PAGE='27',
 XY='(-1475,2950)',
 ROT='0',
 VER='1',
 PACK_TYPE='0402LF',
 LOCATION='R481',
 CDS_LIB='pure_quanta',
 CDS_PART_NAME='Q_RES_0402LF-0,5%,1/16W,CHIP,CS00002JB13',
 PART_NUMBER='CS00002JB13',
 VALUE='0',
 PRIM_FILE='./archive_libs/logical/q_res/chips/chips.prt';

PART_NAME
 R482 'Q_RES_0402LF-0,5%,1/16W,CHIP,CS00002JB13':;

SECTION_NUMBER 1
 '@T6G_MB_LIB.T6G(SCH_1):PAGE273_I96@PURE_QUANTA.Q_RES(CHIPS)':
 C_PATH='@t6g_mb_lib.t6g(sch_1):page273_i96@pure_quanta.q_res(chips)',
 P_PATH='@t6g_mb_lib.t6g(sch_1):page188_i96@pure_quanta.q_res(chips)',
 PATH='I96',
 DRAWING='@T6G_MB_LIB.T6G(SCH_1):PAGE273',
 SEC_TYPE='0402LF',
 WATTAGE='1/16W',
 TOLERANCE='5%',
 MATERIAL='CHIP',
 PHYS_PAGE='188',
 XY='(-2500,2500)',
 ROT='0',
 VER='1',
 PACK_TYPE='0402LF',
 LOCATION='R482',
 SEC='1',
 CDS_LIB='pure_quanta',
 CDS_PART_NAME='Q_RES_0402LF-0,5%,1/16W,CHIP,CS00002JB13',
 PART_NUMBER='CS00002JB13',
 VALUE='0',
 PRIM_FILE='./archive_libs/logical/q_res/chips/chips.prt';

PART_NAME
 R483 'Q_RES_0402LF-0,5%,1/16W,CHIP,CS00002JB13':;

SECTION_NUMBER 1
 '@T6G_MB_LIB.T6G(SCH_1):PAGE27_I334@PURE_QUANTA.Q_RES(CHIPS)':
 C_PATH='@t6g_mb_lib.t6g(sch_1):page27_i334@pure_quanta.q_res(chips)',
 P_PATH='@t6g_mb_lib.t6g(sch_1):page27_i334@pure_quanta.q_res(chips)',
 PATH='I334',
 DRAWING='@T6G_MB_LIB.T6G(SCH_1):PAGE27',
 WATTAGE='1/16W',
 TOLERANCE='5%',
 MATERIAL='CHIP',
 PHYS_PAGE='27',
 XY='(-1475,2900)',
 ROT='0',
 VER='1',
 PACK_TYPE='0402LF',
 LOCATION='R483',
 CDS_LIB='pure_quanta',
 CDS_PART_NAME='Q_RES_0402LF-0,5%,1/16W,CHIP,CS00002JB13',
 PART_NUMBER='CS00002JB13',
 VALUE='0',
 PRIM_FILE='./archive_libs/logical/q_res/chips/chips.prt';

PART_NAME
 R484 'Q_RES_0402LF-0,5%,1/16W,CHIP,CS00002JB13':;

SECTION_NUMBER 1
 '@T6G_MB_LIB.T6G(SCH_1):PAGE27_I336@PURE_QUANTA.Q_RES(CHIPS)':
 C_PATH='@t6g_mb_lib.t6g(sch_1):page27_i336@pure_quanta.q_res(chips)',
 P_PATH='@t6g_mb_lib.t6g(sch_1):page27_i336@pure_quanta.q_res(chips)',
 PATH='I336',
 DRAWING='@T6G_MB_LIB.T6G(SCH_1):PAGE27',
 WATTAGE='1/16W',
 TOLERANCE='5%',
 MATERIAL='CHIP',
 PHYS_PAGE='27',
 XY='(-1475,2850)',
 ROT='0',
 VER='1',
 PACK_TYPE='0402LF',
 LOCATION='R484',
 CDS_LIB='pure_quanta',
 CDS_PART_NAME='Q_RES_0402LF-0,5%,1/16W,CHIP,CS00002JB13',
 PART_NUMBER='CS00002JB13',
 VALUE='0',
 PRIM_FILE='./archive_libs/logical/q_res/chips/chips.prt';

PART_NAME
 R485 'Q_RES_0402LF-0,5%,1/16W,CHIP,CS00002JB13':;

SECTION_NUMBER 1
 '@T6G_MB_LIB.T6G(SCH_1):PAGE27_I337@PURE_QUANTA.Q_RES(CHIPS)':
 C_PATH='@t6g_mb_lib.t6g(sch_1):page27_i337@pure_quanta.q_res(chips)',
 P_PATH='@t6g_mb_lib.t6g(sch_1):page27_i337@pure_quanta.q_res(chips)',
 PATH='I337',
 DRAWING='@T6G_MB_LIB.T6G(SCH_1):PAGE27',
 WATTAGE='1/16W',
 TOLERANCE='5%',
 MATERIAL='CHIP',
 PHYS_PAGE='27',
 XY='(-1475,2800)',
 ROT='0',
 VER='1',
 PACK_TYPE='0402LF',
 LOCATION='R485',
 CDS_LIB='pure_quanta',
 CDS_PART_NAME='Q_RES_0402LF-0,5%,1/16W,CHIP,CS00002JB13',
 PART_NUMBER='CS00002JB13',
 VALUE='0',
 PRIM_FILE='./archive_libs/logical/q_res/chips/chips.prt';

PART_NAME
 R486 'Q_RES_0402LF-0,5%,1/16W,CHIP,CS00002JB13':;

SECTION_NUMBER 1
 '@T6G_MB_LIB.T6G(SCH_1):PAGE54_I362@PURE_QUANTA.Q_RES(CHIPS)':
 C_PATH='@t6g_mb_lib.t6g(sch_1):page54_i362@pure_quanta.q_res(chips)',
 P_PATH='@t6g_mb_lib.t6g(sch_1):page54_i362@pure_quanta.q_res(chips)',
 PATH='I362',
 DRAWING='@T6G_MB_LIB.T6G(SCH_1):PAGE54',
 WATTAGE='1/16W',
 TOLERANCE='5%',
 MATERIAL='CHIP',
 PHYS_PAGE='54',
 XY='(-3100,4825)',
 ROT='0',
 VER='1',
 PACK_TYPE='0402LF',
 LOCATION='R486',
 CDS_LIB='pure_quanta',
 CDS_PART_NAME='Q_RES_0402LF-0,5%,1/16W,CHIP,CS00002JB13',
 PART_NUMBER='CS00002JB13',
 VALUE='0',
 PRIM_FILE='./archive_libs/logical/q_res/chips/chips.prt';

PART_NAME
 R487 'Q_RES_0402LF-0,5%,1/16W,CHIP,CS00002JB13':;

SECTION_NUMBER 1
 '@T6G_MB_LIB.T6G(SCH_1):PAGE273_I95@PURE_QUANTA.Q_RES(CHIPS)':
 C_PATH='@t6g_mb_lib.t6g(sch_1):page273_i95@pure_quanta.q_res(chips)',
 P_PATH='@t6g_mb_lib.t6g(sch_1):page188_i95@pure_quanta.q_res(chips)',
 PATH='I95',
 DRAWING='@T6G_MB_LIB.T6G(SCH_1):PAGE273',
 SEC_TYPE='0402LF',
 WATTAGE='1/16W',
 TOLERANCE='5%',
 MATERIAL='CHIP',
 PHYS_PAGE='188',
 XY='(-2475,4775)',
 ROT='0',
 VER='1',
 PACK_TYPE='0402LF',
 LOCATION='R487',
 SEC='1',
 CDS_LIB='pure_quanta',
 CDS_PART_NAME='Q_RES_0402LF-0,5%,1/16W,CHIP,CS00002JB13',
 PART_NUMBER='CS00002JB13',
 VALUE='0',
 PRIM_FILE='./archive_libs/logical/q_res/chips/chips.prt';

PART_NAME
 R488 'Q_RES_0402LF-33,5%,1/16W,CHIP,CS03302JB10':;

SECTION_NUMBER 1
 '@T6G_MB_LIB.T6G(SCH_1):PAGE54_I415@PURE_QUANTA.Q_RES(CHIPS)':
 C_PATH='@t6g_mb_lib.t6g(sch_1):page54_i415@pure_quanta.q_res(chips)',
 P_PATH='@t6g_mb_lib.t6g(sch_1):page54_i415@pure_quanta.q_res(chips)',
 PATH='I415',
 DRAWING='@T6G_MB_LIB.T6G(SCH_1):PAGE54',
 BOM_COST='MEM',
 WATTAGE='1/16W',
 TOLERANCE='5%',
 MATERIAL='CHIP',
 PHYS_PAGE='54',
 XY='(-3100,4975)',
 ROT='0',
 VER='1',
 PACK_TYPE='0402LF',
 LOCATION='R488',
 CDS_LIB='pure_quanta',
 CDS_PART_NAME='Q_RES_0402LF-33,5%,1/16W,CHIP,CS03302JB10',
 PART_NUMBER='CS03302JB10',
 VALUE='33',
 PRIM_FILE='./archive_libs/logical/q_res/chips/chips.prt';

PART_NAME
 R489 'Q_RES_0402LF-33,5%,1/16W,CHIP,CS03302JB10':;

SECTION_NUMBER 1
 '@T6G_MB_LIB.T6G(SCH_1):PAGE27_I399@PURE_QUANTA.Q_RES(CHIPS)':
 C_PATH='@t6g_mb_lib.t6g(sch_1):page27_i399@pure_quanta.q_res(chips)',
 P_PATH='@t6g_mb_lib.t6g(sch_1):page27_i399@pure_quanta.q_res(chips)',
 PATH='I399',
 DRAWING='@T6G_MB_LIB.T6G(SCH_1):PAGE27',
 BOM_COST='MEM',
 WATTAGE='1/16W',
 TOLERANCE='5%',
 MATERIAL='CHIP',
 PHYS_PAGE='27',
 XY='(-2725,4725)',
 ROT='0',
 VER='1',
 PACK_TYPE='0402LF',
 LOCATION='R489',
 CDS_LIB='pure_quanta',
 CDS_PART_NAME='Q_RES_0402LF-33,5%,1/16W,CHIP,CS03302JB10',
 PART_NUMBER='CS03302JB10',
 VALUE='33',
 PRIM_FILE='./archive_libs/logical/q_res/chips/chips.prt';

PART_NAME
 R490 'Q_RES_0402LF-0,5%,1/16W,EMPTY,CS00002JB13':;

SECTION_NUMBER 1
 '@T6G_MB_LIB.T6G(SCH_1):PAGE273_I88@PURE_QUANTA.Q_RES(CHIPS)':
 C_PATH='@t6g_mb_lib.t6g(sch_1):page273_i88@pure_quanta.q_res(chips)',
 P_PATH='@t6g_mb_lib.t6g(sch_1):page188_i88@pure_quanta.q_res(chips)',
 PATH='I88',
 DRAWING='@T6G_MB_LIB.T6G(SCH_1):PAGE273',
 SEC_TYPE='0402LF',
 WATTAGE='1/16W',
 TOLERANCE='5%',
 MATERIAL='EMPTY',
 PHYS_PAGE='188',
 XY='(-2275,3975)',
 ROT='0',
 VER='1',
 PACK_TYPE='0402LF',
 LOCATION='R490',
 SEC='1',
 CDS_LIB='pure_quanta',
 CDS_PART_NAME='Q_RES_0402LF-0,5%,1/16W,EMPTY,CS00002JB13',
 PART_NUMBER='CS00002JB13',
 VALUE='0',
 PRIM_FILE='./archive_libs/logical/q_res/chips/chips.prt';

PART_NAME
 R491 'Q_RES_0402LF-4.7K,5%,1/16W,EMPTY,CS24702JB10':;

SECTION_NUMBER 1
 '@T6G_MB_LIB.T6G(SCH_1):PAGE55_I335@PURE_QUANTA.Q_RES(CHIPS)':
 C_PATH='@t6g_mb_lib.t6g(sch_1):page55_i335@pure_quanta.q_res(chips)',
 P_PATH='@t6g_mb_lib.t6g(sch_1):page55_i335@pure_quanta.q_res(chips)',
 PATH='I335',
 DRAWING='@T6G_MB_LIB.T6G(SCH_1):PAGE55',
 WATTAGE='1/16W',
 TOLERANCE='5%',
 MATERIAL='EMPTY',
 PHYS_PAGE='55',
 XY='(-8700,425)',
 ROT='1',
 VER='1',
 PACK_TYPE='0402LF',
 LOCATION='R491',
 CDS_LIB='pure_quanta',
 CDS_PART_NAME='Q_RES_0402LF-4.7K,5%,1/16W,EMPTY,CS24702JB10',
 PART_NUMBER='CS24702JB10',
 VALUE='4.7K',
 PRIM_FILE='./archive_libs/logical/q_res/chips/chips.prt';

PART_NAME
 R492 'Q_RES_0402LF-4.7K,5%,1/16W,CHIP,CS24702JB10':;

SECTION_NUMBER 1
 '@T6G_MB_LIB.T6G(SCH_1):PAGE273_I99@PURE_QUANTA.Q_RES(CHIPS)':
 C_PATH='@t6g_mb_lib.t6g(sch_1):page273_i99@pure_quanta.q_res(chips)',
 P_PATH='@t6g_mb_lib.t6g(sch_1):page188_i99@pure_quanta.q_res(chips)',
 PATH='I99',
 DRAWING='@T6G_MB_LIB.T6G(SCH_1):PAGE273',
 SEC_TYPE='0402LF',
 WATTAGE='1/16W',
 TOLERANCE='5%',
 MATERIAL='CHIP',
 PHYS_PAGE='188',
 XY='(-1450,3000)',
 ROT='2',
 VER='2',
 PACK_TYPE='0402LF',
 LOCATION='R492',
 SEC='1',
 CDS_LIB='pure_quanta',
 CDS_PART_NAME='Q_RES_0402LF-4.7K,5%,1/16W,CHIP,CS24702JB10',
 PART_NUMBER='CS24702JB10',
 VALUE='4.7K',
 PRIM_FILE='./archive_libs/logical/q_res/chips/chips.prt';

PART_NAME
 R493 'Q_RES_0402LF-0,5%,1/16W,CHIP,CS00002JB13':;

SECTION_NUMBER 1
 '@T6G_MB_LIB.T6G(SCH_1):PAGE79_I18@PURE_QUANTA.Q_RES(CHIPS)':
 C_PATH='@t6g_mb_lib.t6g(sch_1):page79_i18@pure_quanta.q_res(chips)',
 P_PATH='@t6g_mb_lib.t6g(sch_1):page80_i18@pure_quanta.q_res(chips)',
 PATH='I18',
 DRAWING='@T6G_MB_LIB.T6G(SCH_1):PAGE79',
 BOM_COST='MEM',
 WATTAGE='1/16W',
 TOLERANCE='5%',
 MATERIAL='CHIP',
 PHYS_PAGE='80',
 XY='(-6850,2950)',
 ROT='2',
 VER='1',
 PACK_TYPE='0402LF',
 LOCATION='R493',
 CDS_LIB='pure_quanta',
 CDS_PART_NAME='Q_RES_0402LF-0,5%,1/16W,CHIP,CS00002JB13',
 PART_NUMBER='CS00002JB13',
 VALUE='0',
 PRIM_FILE='./archive_libs/logical/q_res/chips/chips.prt';

PART_NAME
 R494 'Q_RES_0402LF-0,5%,1/16W,CHIP,CS00002JB13':;

SECTION_NUMBER 1
 '@T6G_MB_LIB.T6G(SCH_1):PAGE273_I102@PURE_QUANTA.Q_RES(CHIPS)':
 C_PATH='@t6g_mb_lib.t6g(sch_1):page273_i102@pure_quanta.q_res(chips)',
 P_PATH='@t6g_mb_lib.t6g(sch_1):page188_i102@pure_quanta.q_res(chips)',
 PATH='I102',
 DRAWING='@T6G_MB_LIB.T6G(SCH_1):PAGE273',
 SEC_TYPE='0402LF',
 WATTAGE='1/16W',
 TOLERANCE='5%',
 MATERIAL='CHIP',
 PHYS_PAGE='188',
 XY='(-625,2850)',
 ROT='0',
 VER='1',
 PACK_TYPE='0402LF',
 LOCATION='R494',
 SEC='1',
 CDS_LIB='pure_quanta',
 CDS_PART_NAME='Q_RES_0402LF-0,5%,1/16W,CHIP,CS00002JB13',
 PART_NUMBER='CS00002JB13',
 VALUE='0',
 PRIM_FILE='./archive_libs/logical/q_res/chips/chips.prt';

PART_NAME
 R495 'Q_RES_0402LF-4.7K,5%,1/16W,CHIP,CS24702JB10':;

SECTION_NUMBER 1
 '@T6G_MB_LIB.T6G(SCH_1):PAGE34_I106@PURE_QUANTA.Q_RES(CHIPS)':
 C_PATH='@t6g_mb_lib.t6g(sch_1):page34_i106@pure_quanta.q_res(chips)',
 P_PATH='@t6g_mb_lib.t6g(sch_1):page34_i106@pure_quanta.q_res(chips)',
 PATH='I106',
 DRAWING='@T6G_MB_LIB.T6G(SCH_1):PAGE34',
 WATTAGE='1/16W',
 TOLERANCE='5%',
 MATERIAL='CHIP',
 PHYS_PAGE='34',
 XY='(-1625,4925)',
 ROT='0',
 VER='1',
 PACK_TYPE='0402LF',
 LOCATION='R495',
 CDS_LIB='pure_quanta',
 CDS_PART_NAME='Q_RES_0402LF-4.7K,5%,1/16W,CHIP,CS24702JB10',
 PART_NUMBER='CS24702JB10',
 VALUE='4.7K',
 PRIM_FILE='./archive_libs/logical/q_res/chips/chips.prt';

PART_NAME
 R496 'Q_RES_0402LF-10K,1%,1/16W,EMPTY,CS31002FB08':;

SECTION_NUMBER 1
 '@T6G_MB_LIB.T6G(SCH_1):PAGE273_I93@PURE_QUANTA.Q_RES(CHIPS)':
 C_PATH='@t6g_mb_lib.t6g(sch_1):page273_i93@pure_quanta.q_res(chips)',
 P_PATH='@t6g_mb_lib.t6g(sch_1):page188_i93@pure_quanta.q_res(chips)',
 PATH='I93',
 DRAWING='@T6G_MB_LIB.T6G(SCH_1):PAGE273',
 WATTAGE='1/16W',
 TOLERANCE='1%',
 MATERIAL='EMPTY',
 PHYS_PAGE='188',
 XY='(-3175,5075)',
 ROT='0',
 VER='2',
 PACK_TYPE='0402LF',
 LOCATION='R496',
 CDS_LIB='pure_quanta',
 CDS_PART_NAME='Q_RES_0402LF-10K,1%,1/16W,EMPTY,CS31002FB08',
 PART_NUMBER='CS31002FB08',
 VALUE='10K',
 PRIM_FILE='./archive_libs/logical/q_res/chips/chips.prt';

PART_NAME
 R497 'Q_RES_0402LF-33,5%,1/16W,CHIP,CS03302JB10':;

SECTION_NUMBER 1
 '@T6G_MB_LIB.T6G(SCH_1):PAGE54_I417@PURE_QUANTA.Q_RES(CHIPS)':
 C_PATH='@t6g_mb_lib.t6g(sch_1):page54_i417@pure_quanta.q_res(chips)',
 P_PATH='@t6g_mb_lib.t6g(sch_1):page54_i417@pure_quanta.q_res(chips)',
 PATH='I417',
 DRAWING='@T6G_MB_LIB.T6G(SCH_1):PAGE54',
 BOM_COST='MEM',
 WATTAGE='1/16W',
 TOLERANCE='5%',
 MATERIAL='CHIP',
 PHYS_PAGE='54',
 XY='(-3100,5125)',
 ROT='0',
 VER='1',
 PACK_TYPE='0402LF',
 LOCATION='R497',
 CDS_LIB='pure_quanta',
 CDS_PART_NAME='Q_RES_0402LF-33,5%,1/16W,CHIP,CS03302JB10',
 PART_NUMBER='CS03302JB10',
 VALUE='33',
 PRIM_FILE='./archive_libs/logical/q_res/chips/chips.prt';

PART_NAME
 R498 'Q_RES_0402LF-2.2K,5%,1/16W,CHIP,CS22202JB07':;

SECTION_NUMBER 1
 '@T6G_MB_LIB.T6G(SCH_1):PAGE34_I107@PURE_QUANTA.Q_RES(CHIPS)':
 C_PATH='@t6g_mb_lib.t6g(sch_1):page34_i107@pure_quanta.q_res(chips)',
 P_PATH='@t6g_mb_lib.t6g(sch_1):page34_i107@pure_quanta.q_res(chips)',
 PATH='I107',
 DRAWING='@T6G_MB_LIB.T6G(SCH_1):PAGE34',
 WATTAGE='1/16W',
 TOLERANCE='5%',
 MATERIAL='CHIP',
 PHYS_PAGE='34',
 XY='(-1625,4850)',
 ROT='0',
 VER='1',
 PACK_TYPE='0402LF',
 LOCATION='R498',
 CDS_LIB='pure_quanta',
 CDS_PART_NAME='Q_RES_0402LF-2.2K,5%,1/16W,CHIP,CS22202JB07',
 PART_NUMBER='CS22202JB07',
 VALUE='2.2K',
 PRIM_FILE='./archive_libs/logical/q_res/chips/chips.prt';

PART_NAME
 R499 'Q_RES_0402LF-4.7K,5%,1/16W,CHIP,CS24702JB10':;

SECTION_NUMBER 1
 '@T6G_MB_LIB.T6G(SCH_1):PAGE34_I4@PURE_QUANTA.Q_RES(CHIPS)':
 C_PATH='@t6g_mb_lib.t6g(sch_1):page34_i4@pure_quanta.q_res(chips)',
 P_PATH='@t6g_mb_lib.t6g(sch_1):page34_i4@pure_quanta.q_res(chips)',
 PATH='I4',
 DRAWING='@T6G_MB_LIB.T6G(SCH_1):PAGE34',
 WATTAGE='1/16W',
 TOLERANCE='5%',
 MATERIAL='CHIP',
 PHYS_PAGE='34',
 XY='(-1675,6000)',
 ROT='0',
 VER='1',
 PACK_TYPE='0402LF',
 LOCATION='R499',
 CDS_LIB='pure_quanta',
 CDS_PART_NAME='Q_RES_0402LF-4.7K,5%,1/16W,CHIP,CS24702JB10',
 PART_NUMBER='CS24702JB10',
 VALUE='4.7K',
 PRIM_FILE='./archive_libs/logical/q_res/chips/chips.prt';

PART_NAME
 R500 'Q_RES_0402LF-15,1%,1/16W,CHIP,CS01502FB03':;

SECTION_NUMBER 1
 '@T6G_MB_LIB.T6G(SCH_1):PAGE37_I322@PURE_QUANTA.Q_RES(CHIPS)':
 C_PATH='@t6g_mb_lib.t6g(sch_1):page37_i322@pure_quanta.q_res(chips)',
 P_PATH='@t6g_mb_lib.t6g(sch_1):page37_i322@pure_quanta.q_res(chips)',
 PATH='I322',
 DRAWING='@T6G_MB_LIB.T6G(SCH_1):PAGE37',
 WATTAGE='1/16W',
 TOLERANCE='1%',
 MATERIAL='CHIP',
 PHYS_PAGE='37',
 XY='(-6600,2225)',
 ROT='0',
 VER='1',
 PACK_TYPE='0402LF',
 LOCATION='R500',
 CDS_LIB='pure_quanta',
 CDS_PART_NAME='Q_RES_0402LF-15,1%,1/16W,CHIP,CS01502FB03',
 PART_NUMBER='CS01502FB03',
 VALUE='15',
 PRIM_FILE='./archive_libs/logical/q_res/chips/chips.prt';

PART_NAME
 R501 'Q_RES_0402LF-15,1%,1/16W,CHIP,CS01502FB03':;

SECTION_NUMBER 1
 '@T6G_MB_LIB.T6G(SCH_1):PAGE38_I314@PURE_QUANTA.Q_RES(CHIPS)':
 C_PATH='@t6g_mb_lib.t6g(sch_1):page38_i314@pure_quanta.q_res(chips)',
 P_PATH='@t6g_mb_lib.t6g(sch_1):page38_i314@pure_quanta.q_res(chips)',
 PATH='I314',
 DRAWING='@T6G_MB_LIB.T6G(SCH_1):PAGE38',
 WATTAGE='1/16W',
 TOLERANCE='1%',
 MATERIAL='CHIP',
 PHYS_PAGE='38',
 XY='(-6750,2175)',
 ROT='0',
 VER='1',
 PACK_TYPE='0402LF',
 LOCATION='R501',
 CDS_LIB='pure_quanta',
 CDS_PART_NAME='Q_RES_0402LF-15,1%,1/16W,CHIP,CS01502FB03',
 PART_NUMBER='CS01502FB03',
 VALUE='15',
 PRIM_FILE='./archive_libs/logical/q_res/chips/chips.prt';

PART_NAME
 R502 'Q_RES_0402LF-15,1%,1/16W,CHIP,CS01502FB03':;

SECTION_NUMBER 1
 '@T6G_MB_LIB.T6G(SCH_1):PAGE39_I313@PURE_QUANTA.Q_RES(CHIPS)':
 C_PATH='@t6g_mb_lib.t6g(sch_1):page39_i313@pure_quanta.q_res(chips)',
 P_PATH='@t6g_mb_lib.t6g(sch_1):page39_i313@pure_quanta.q_res(chips)',
 PATH='I313',
 DRAWING='@T6G_MB_LIB.T6G(SCH_1):PAGE39',
 WATTAGE='1/16W',
 TOLERANCE='1%',
 MATERIAL='CHIP',
 PHYS_PAGE='39',
 XY='(-6775,2200)',
 ROT='0',
 VER='1',
 PACK_TYPE='0402LF',
 LOCATION='R502',
 CDS_LIB='pure_quanta',
 CDS_PART_NAME='Q_RES_0402LF-15,1%,1/16W,CHIP,CS01502FB03',
 PART_NUMBER='CS01502FB03',
 VALUE='15',
 PRIM_FILE='./archive_libs/logical/q_res/chips/chips.prt';

PART_NAME
 R503 'Q_RES_0402LF-15,1%,1/16W,CHIP,CS01502FB03':;

SECTION_NUMBER 1
 '@T6G_MB_LIB.T6G(SCH_1):PAGE40_I314@PURE_QUANTA.Q_RES(CHIPS)':
 C_PATH='@t6g_mb_lib.t6g(sch_1):page40_i314@pure_quanta.q_res(chips)',
 P_PATH='@t6g_mb_lib.t6g(sch_1):page40_i314@pure_quanta.q_res(chips)',
 PATH='I314',
 DRAWING='@T6G_MB_LIB.T6G(SCH_1):PAGE40',
 WATTAGE='1/16W',
 TOLERANCE='1%',
 MATERIAL='CHIP',
 PHYS_PAGE='40',
 XY='(-6625,2175)',
 ROT='0',
 VER='1',
 PACK_TYPE='0402LF',
 LOCATION='R503',
 CDS_LIB='pure_quanta',
 CDS_PART_NAME='Q_RES_0402LF-15,1%,1/16W,CHIP,CS01502FB03',
 PART_NUMBER='CS01502FB03',
 VALUE='15',
 PRIM_FILE='./archive_libs/logical/q_res/chips/chips.prt';

PART_NAME
 R504 'Q_RES_0402LF-15,1%,1/16W,CHIP,CS01502FB03':;

SECTION_NUMBER 1
 '@T6G_MB_LIB.T6G(SCH_1):PAGE41_I314@PURE_QUANTA.Q_RES(CHIPS)':
 C_PATH='@t6g_mb_lib.t6g(sch_1):page41_i314@pure_quanta.q_res(chips)',
 P_PATH='@t6g_mb_lib.t6g(sch_1):page41_i314@pure_quanta.q_res(chips)',
 PATH='I314',
 DRAWING='@T6G_MB_LIB.T6G(SCH_1):PAGE41',
 WATTAGE='1/16W',
 TOLERANCE='1%',
 MATERIAL='CHIP',
 PHYS_PAGE='41',
 XY='(-6725,2125)',
 ROT='0',
 VER='1',
 PACK_TYPE='0402LF',
 LOCATION='R504',
 CDS_LIB='pure_quanta',
 CDS_PART_NAME='Q_RES_0402LF-15,1%,1/16W,CHIP,CS01502FB03',
 PART_NUMBER='CS01502FB03',
 VALUE='15',
 PRIM_FILE='./archive_libs/logical/q_res/chips/chips.prt';

PART_NAME
 R505 'Q_RES_0402LF-15,1%,1/16W,CHIP,CS01502FB03':;

SECTION_NUMBER 1
 '@T6G_MB_LIB.T6G(SCH_1):PAGE42_I314@PURE_QUANTA.Q_RES(CHIPS)':
 C_PATH='@t6g_mb_lib.t6g(sch_1):page42_i314@pure_quanta.q_res(chips)',
 P_PATH='@t6g_mb_lib.t6g(sch_1):page42_i314@pure_quanta.q_res(chips)',
 PATH='I314',
 DRAWING='@T6G_MB_LIB.T6G(SCH_1):PAGE42',
 WATTAGE='1/16W',
 TOLERANCE='1%',
 MATERIAL='CHIP',
 PHYS_PAGE='42',
 XY='(-6625,2300)',
 ROT='0',
 VER='1',
 PACK_TYPE='0402LF',
 LOCATION='R505',
 CDS_LIB='pure_quanta',
 CDS_PART_NAME='Q_RES_0402LF-15,1%,1/16W,CHIP,CS01502FB03',
 PART_NUMBER='CS01502FB03',
 VALUE='15',
 PRIM_FILE='./archive_libs/logical/q_res/chips/chips.prt';

PART_NAME
 R506 'Q_RES_0402LF-15,1%,1/16W,CHIP,CS01502FB03':;

SECTION_NUMBER 1
 '@T6G_MB_LIB.T6G(SCH_1):PAGE43_I322@PURE_QUANTA.Q_RES(CHIPS)':
 C_PATH='@t6g_mb_lib.t6g(sch_1):page43_i322@pure_quanta.q_res(chips)',
 P_PATH='@t6g_mb_lib.t6g(sch_1):page43_i322@pure_quanta.q_res(chips)',
 PATH='I322',
 DRAWING='@T6G_MB_LIB.T6G(SCH_1):PAGE43',
 WATTAGE='1/16W',
 TOLERANCE='1%',
 MATERIAL='CHIP',
 PHYS_PAGE='43',
 XY='(-6725,2200)',
 ROT='0',
 VER='1',
 PACK_TYPE='0402LF',
 LOCATION='R506',
 CDS_LIB='pure_quanta',
 CDS_PART_NAME='Q_RES_0402LF-15,1%,1/16W,CHIP,CS01502FB03',
 PART_NUMBER='CS01502FB03',
 VALUE='15',
 PRIM_FILE='./archive_libs/logical/q_res/chips/chips.prt';

PART_NAME
 R507 'Q_RES_0402LF-15,1%,1/16W,CHIP,CS01502FB03':;

SECTION_NUMBER 1
 '@T6G_MB_LIB.T6G(SCH_1):PAGE44_I314@PURE_QUANTA.Q_RES(CHIPS)':
 C_PATH='@t6g_mb_lib.t6g(sch_1):page44_i314@pure_quanta.q_res(chips)',
 P_PATH='@t6g_mb_lib.t6g(sch_1):page44_i314@pure_quanta.q_res(chips)',
 PATH='I314',
 DRAWING='@T6G_MB_LIB.T6G(SCH_1):PAGE44',
 WATTAGE='1/16W',
 TOLERANCE='1%',
 MATERIAL='CHIP',
 PHYS_PAGE='44',
 XY='(-6650,2050)',
 ROT='0',
 VER='1',
 PACK_TYPE='0402LF',
 LOCATION='R507',
 CDS_LIB='pure_quanta',
 CDS_PART_NAME='Q_RES_0402LF-15,1%,1/16W,CHIP,CS01502FB03',
 PART_NUMBER='CS01502FB03',
 VALUE='15',
 PRIM_FILE='./archive_libs/logical/q_res/chips/chips.prt';

PART_NAME
 R508 'Q_RES_0402LF-15,1%,1/16W,CHIP,CS01502FB03':;

SECTION_NUMBER 1
 '@T6G_MB_LIB.T6G(SCH_1):PAGE45_I314@PURE_QUANTA.Q_RES(CHIPS)':
 C_PATH='@t6g_mb_lib.t6g(sch_1):page45_i314@pure_quanta.q_res(chips)',
 P_PATH='@t6g_mb_lib.t6g(sch_1):page45_i314@pure_quanta.q_res(chips)',
 PATH='I314',
 DRAWING='@T6G_MB_LIB.T6G(SCH_1):PAGE45',
 WATTAGE='1/16W',
 TOLERANCE='1%',
 MATERIAL='CHIP',
 PHYS_PAGE='45',
 XY='(-6525,2100)',
 ROT='0',
 VER='1',
 PACK_TYPE='0402LF',
 LOCATION='R508',
 CDS_LIB='pure_quanta',
 CDS_PART_NAME='Q_RES_0402LF-15,1%,1/16W,CHIP,CS01502FB03',
 PART_NUMBER='CS01502FB03',
 VALUE='15',
 PRIM_FILE='./archive_libs/logical/q_res/chips/chips.prt';

PART_NAME
 R509 'Q_RES_0402LF-15,1%,1/16W,CHIP,CS01502FB03':;

SECTION_NUMBER 1
 '@T6G_MB_LIB.T6G(SCH_1):PAGE46_I314@PURE_QUANTA.Q_RES(CHIPS)':
 C_PATH='@t6g_mb_lib.t6g(sch_1):page46_i314@pure_quanta.q_res(chips)',
 P_PATH='@t6g_mb_lib.t6g(sch_1):page46_i314@pure_quanta.q_res(chips)',
 PATH='I314',
 DRAWING='@T6G_MB_LIB.T6G(SCH_1):PAGE46',
 WATTAGE='1/16W',
 TOLERANCE='1%',
 MATERIAL='CHIP',
 PHYS_PAGE='46',
 XY='(-6550,2050)',
 ROT='0',
 VER='1',
 PACK_TYPE='0402LF',
 LOCATION='R509',
 CDS_LIB='pure_quanta',
 CDS_PART_NAME='Q_RES_0402LF-15,1%,1/16W,CHIP,CS01502FB03',
 PART_NUMBER='CS01502FB03',
 VALUE='15',
 PRIM_FILE='./archive_libs/logical/q_res/chips/chips.prt';

PART_NAME
 R510 'Q_RES_0402LF-15,1%,1/16W,CHIP,CS01502FB03':;

SECTION_NUMBER 1
 '@T6G_MB_LIB.T6G(SCH_1):PAGE47_I314@PURE_QUANTA.Q_RES(CHIPS)':
 C_PATH='@t6g_mb_lib.t6g(sch_1):page47_i314@pure_quanta.q_res(chips)',
 P_PATH='@t6g_mb_lib.t6g(sch_1):page47_i314@pure_quanta.q_res(chips)',
 PATH='I314',
 DRAWING='@T6G_MB_LIB.T6G(SCH_1):PAGE47',
 WATTAGE='1/16W',
 TOLERANCE='1%',
 MATERIAL='CHIP',
 PHYS_PAGE='47',
 XY='(-6525,2050)',
 ROT='0',
 VER='1',
 PACK_TYPE='0402LF',
 LOCATION='R510',
 CDS_LIB='pure_quanta',
 CDS_PART_NAME='Q_RES_0402LF-15,1%,1/16W,CHIP,CS01502FB03',
 PART_NUMBER='CS01502FB03',
 VALUE='15',
 PRIM_FILE='./archive_libs/logical/q_res/chips/chips.prt';

PART_NAME
 R511 'Q_RES_0402LF-15,1%,1/16W,CHIP,CS01502FB03':;

SECTION_NUMBER 1
 '@T6G_MB_LIB.T6G(SCH_1):PAGE48_I313@PURE_QUANTA.Q_RES(CHIPS)':
 C_PATH='@t6g_mb_lib.t6g(sch_1):page48_i313@pure_quanta.q_res(chips)',
 P_PATH='@t6g_mb_lib.t6g(sch_1):page48_i313@pure_quanta.q_res(chips)',
 PATH='I313',
 DRAWING='@T6G_MB_LIB.T6G(SCH_1):PAGE48',
 WATTAGE='1/16W',
 TOLERANCE='1%',
 MATERIAL='CHIP',
 PHYS_PAGE='48',
 XY='(-6575,2075)',
 ROT='0',
 VER='1',
 PACK_TYPE='0402LF',
 LOCATION='R511',
 CDS_LIB='pure_quanta',
 CDS_PART_NAME='Q_RES_0402LF-15,1%,1/16W,CHIP,CS01502FB03',
 PART_NUMBER='CS01502FB03',
 VALUE='15',
 PRIM_FILE='./archive_libs/logical/q_res/chips/chips.prt';

PART_NAME
 R512 'Q_RES_0402LF-2.2K,5%,1/16W,CHIP,CS22202JB07':;

SECTION_NUMBER 1
 '@T6G_MB_LIB.T6G(SCH_1):PAGE54_I400@PURE_QUANTA.Q_RES(CHIPS)':
 C_PATH='@t6g_mb_lib.t6g(sch_1):page54_i400@pure_quanta.q_res(chips)',
 P_PATH='@t6g_mb_lib.t6g(sch_1):page54_i400@pure_quanta.q_res(chips)',
 PATH='I400',
 DRAWING='@T6G_MB_LIB.T6G(SCH_1):PAGE54',
 WATTAGE='1/16W',
 TOLERANCE='5%',
 MATERIAL='CHIP',
 PHYS_PAGE='54',
 XY='(-8750,3025)',
 ROT='0',
 VER='1',
 PACK_TYPE='0402LF',
 LOCATION='R512',
 CDS_LIB='pure_quanta',
 CDS_PART_NAME='Q_RES_0402LF-2.2K,5%,1/16W,CHIP,CS22202JB07',
 PART_NUMBER='CS22202JB07',
 VALUE='2.2K',
 PRIM_FILE='./archive_libs/logical/q_res/chips/chips.prt';

PART_NAME
 R513 'Q_RES_0402LF-2.2K,5%,1/16W,CHIP,CS22202JB07':;

SECTION_NUMBER 1
 '@T6G_MB_LIB.T6G(SCH_1):PAGE54_I390@PURE_QUANTA.Q_RES(CHIPS)':
 C_PATH='@t6g_mb_lib.t6g(sch_1):page54_i390@pure_quanta.q_res(chips)',
 P_PATH='@t6g_mb_lib.t6g(sch_1):page54_i390@pure_quanta.q_res(chips)',
 PATH='I390',
 DRAWING='@T6G_MB_LIB.T6G(SCH_1):PAGE54',
 WATTAGE='1/16W',
 TOLERANCE='5%',
 MATERIAL='CHIP',
 PHYS_PAGE='54',
 XY='(-8750,3175)',
 ROT='0',
 VER='1',
 PACK_TYPE='0402LF',
 LOCATION='R513',
 CDS_LIB='pure_quanta',
 CDS_PART_NAME='Q_RES_0402LF-2.2K,5%,1/16W,CHIP,CS22202JB07',
 PART_NUMBER='CS22202JB07',
 VALUE='2.2K',
 PRIM_FILE='./archive_libs/logical/q_res/chips/chips.prt';

PART_NAME
 R514 'Q_RES_0402LF-2.2K,5%,1/16W,CHIP,CS22202JB07':;

SECTION_NUMBER 1
 '@T6G_MB_LIB.T6G(SCH_1):PAGE54_I401@PURE_QUANTA.Q_RES(CHIPS)':
 C_PATH='@t6g_mb_lib.t6g(sch_1):page54_i401@pure_quanta.q_res(chips)',
 P_PATH='@t6g_mb_lib.t6g(sch_1):page54_i401@pure_quanta.q_res(chips)',
 PATH='I401',
 DRAWING='@T6G_MB_LIB.T6G(SCH_1):PAGE54',
 WATTAGE='1/16W',
 TOLERANCE='5%',
 MATERIAL='CHIP',
 PHYS_PAGE='54',
 XY='(-8750,3075)',
 ROT='0',
 VER='1',
 PACK_TYPE='0402LF',
 LOCATION='R514',
 CDS_LIB='pure_quanta',
 CDS_PART_NAME='Q_RES_0402LF-2.2K,5%,1/16W,CHIP,CS22202JB07',
 PART_NUMBER='CS22202JB07',
 VALUE='2.2K',
 PRIM_FILE='./archive_libs/logical/q_res/chips/chips.prt';

PART_NAME
 R515 'Q_RES_0402LF-2.2K,5%,1/16W,CHIP,CS22202JB07':;

SECTION_NUMBER 1
 '@T6G_MB_LIB.T6G(SCH_1):PAGE54_I391@PURE_QUANTA.Q_RES(CHIPS)':
 C_PATH='@t6g_mb_lib.t6g(sch_1):page54_i391@pure_quanta.q_res(chips)',
 P_PATH='@t6g_mb_lib.t6g(sch_1):page54_i391@pure_quanta.q_res(chips)',
 PATH='I391',
 DRAWING='@T6G_MB_LIB.T6G(SCH_1):PAGE54',
 WATTAGE='1/16W',
 TOLERANCE='5%',
 MATERIAL='CHIP',
 PHYS_PAGE='54',
 XY='(-8750,3225)',
 ROT='0',
 VER='1',
 PACK_TYPE='0402LF',
 LOCATION='R515',
 CDS_LIB='pure_quanta',
 CDS_PART_NAME='Q_RES_0402LF-2.2K,5%,1/16W,CHIP,CS22202JB07',
 PART_NUMBER='CS22202JB07',
 VALUE='2.2K',
 PRIM_FILE='./archive_libs/logical/q_res/chips/chips.prt';

PART_NAME
 R516 'Q_RES_0402LF-2.2K,5%,1/16W,CHIP,CS22202JB07':;

SECTION_NUMBER 1
 '@T6G_MB_LIB.T6G(SCH_1):PAGE54_I402@PURE_QUANTA.Q_RES(CHIPS)':
 C_PATH='@t6g_mb_lib.t6g(sch_1):page54_i402@pure_quanta.q_res(chips)',
 P_PATH='@t6g_mb_lib.t6g(sch_1):page54_i402@pure_quanta.q_res(chips)',
 PATH='I402',
 DRAWING='@T6G_MB_LIB.T6G(SCH_1):PAGE54',
 WATTAGE='1/16W',
 TOLERANCE='5%',
 MATERIAL='CHIP',
 PHYS_PAGE='54',
 XY='(-8750,3125)',
 ROT='0',
 VER='1',
 PACK_TYPE='0402LF',
 LOCATION='R516',
 CDS_LIB='pure_quanta',
 CDS_PART_NAME='Q_RES_0402LF-2.2K,5%,1/16W,CHIP,CS22202JB07',
 PART_NUMBER='CS22202JB07',
 VALUE='2.2K',
 PRIM_FILE='./archive_libs/logical/q_res/chips/chips.prt';

PART_NAME
 R517 'Q_RES_0402LF-2.2K,5%,1/16W,CHIP,CS22202JB07':;

SECTION_NUMBER 1
 '@T6G_MB_LIB.T6G(SCH_1):PAGE54_I387@PURE_QUANTA.Q_RES(CHIPS)':
 C_PATH='@t6g_mb_lib.t6g(sch_1):page54_i387@pure_quanta.q_res(chips)',
 P_PATH='@t6g_mb_lib.t6g(sch_1):page54_i387@pure_quanta.q_res(chips)',
 PATH='I387',
 DRAWING='@T6G_MB_LIB.T6G(SCH_1):PAGE54',
 WATTAGE='1/16W',
 TOLERANCE='5%',
 MATERIAL='CHIP',
 PHYS_PAGE='54',
 XY='(-8750,3275)',
 ROT='0',
 VER='1',
 PACK_TYPE='0402LF',
 LOCATION='R517',
 CDS_LIB='pure_quanta',
 CDS_PART_NAME='Q_RES_0402LF-2.2K,5%,1/16W,CHIP,CS22202JB07',
 PART_NUMBER='CS22202JB07',
 VALUE='2.2K',
 PRIM_FILE='./archive_libs/logical/q_res/chips/chips.prt';

PART_NAME
 R518 'Q_RES_0402LF-2.2K,5%,1/16W,CHIP,CS22202JB07':;

SECTION_NUMBER 1
 '@T6G_MB_LIB.T6G(SCH_1):PAGE54_I403@PURE_QUANTA.Q_RES(CHIPS)':
 C_PATH='@t6g_mb_lib.t6g(sch_1):page54_i403@pure_quanta.q_res(chips)',
 P_PATH='@t6g_mb_lib.t6g(sch_1):page54_i403@pure_quanta.q_res(chips)',
 PATH='I403',
 DRAWING='@T6G_MB_LIB.T6G(SCH_1):PAGE54',
 WATTAGE='1/16W',
 TOLERANCE='5%',
 MATERIAL='CHIP',
 PHYS_PAGE='54',
 XY='(-8750,4825)',
 ROT='2',
 VER='2',
 PACK_TYPE='0402LF',
 LOCATION='R518',
 CDS_LIB='pure_quanta',
 CDS_PART_NAME='Q_RES_0402LF-2.2K,5%,1/16W,CHIP,CS22202JB07',
 PART_NUMBER='CS22202JB07',
 VALUE='2.2K',
 PRIM_FILE='./archive_libs/logical/q_res/chips/chips.prt';

PART_NAME
 R519 'Q_RES_0402LF-2.2K,5%,1/16W,EMPTY,CS22202JB07':;

SECTION_NUMBER 1
 '@T6G_MB_LIB.T6G(SCH_1):PAGE54_I404@PURE_QUANTA.Q_RES(CHIPS)':
 C_PATH='@t6g_mb_lib.t6g(sch_1):page54_i404@pure_quanta.q_res(chips)',
 P_PATH='@t6g_mb_lib.t6g(sch_1):page54_i404@pure_quanta.q_res(chips)',
 PATH='I404',
 DRAWING='@T6G_MB_LIB.T6G(SCH_1):PAGE54',
 WATTAGE='1/16W',
 TOLERANCE='5%',
 MATERIAL='EMPTY',
 PHYS_PAGE='54',
 XY='(-8750,4475)',
 ROT='2',
 VER='2',
 PACK_TYPE='0402LF',
 LOCATION='R519',
 CDS_LIB='pure_quanta',
 CDS_PART_NAME='Q_RES_0402LF-2.2K,5%,1/16W,EMPTY,CS22202JB07',
 PART_NUMBER='CS22202JB07',
 VALUE='2.2K',
 PRIM_FILE='./archive_libs/logical/q_res/chips/chips.prt';

PART_NAME
 R520 'Q_RES_0402LF-2.2K,5%,1/16W,CHIP,CS22202JB07':;

SECTION_NUMBER 1
 '@T6G_MB_LIB.T6G(SCH_1):PAGE54_I396@PURE_QUANTA.Q_RES(CHIPS)':
 C_PATH='@t6g_mb_lib.t6g(sch_1):page54_i396@pure_quanta.q_res(chips)',
 P_PATH='@t6g_mb_lib.t6g(sch_1):page54_i396@pure_quanta.q_res(chips)',
 PATH='I396',
 DRAWING='@T6G_MB_LIB.T6G(SCH_1):PAGE54',
 WATTAGE='1/16W',
 TOLERANCE='5%',
 MATERIAL='CHIP',
 PHYS_PAGE='54',
 XY='(-500,5575)',
 ROT='0',
 VER='1',
 PACK_TYPE='0402LF',
 LOCATION='R520',
 CDS_LIB='pure_quanta',
 CDS_PART_NAME='Q_RES_0402LF-2.2K,5%,1/16W,CHIP,CS22202JB07',
 PART_NUMBER='CS22202JB07',
 VALUE='2.2K',
 PRIM_FILE='./archive_libs/logical/q_res/chips/chips.prt';

PART_NAME
 R521 'Q_RES_0402LF-2.2K,5%,1/16W,CHIP,CS22202JB07':;

SECTION_NUMBER 1
 '@T6G_MB_LIB.T6G(SCH_1):PAGE54_I405@PURE_QUANTA.Q_RES(CHIPS)':
 C_PATH='@t6g_mb_lib.t6g(sch_1):page54_i405@pure_quanta.q_res(chips)',
 P_PATH='@t6g_mb_lib.t6g(sch_1):page54_i405@pure_quanta.q_res(chips)',
 PATH='I405',
 DRAWING='@T6G_MB_LIB.T6G(SCH_1):PAGE54',
 WATTAGE='1/16W',
 TOLERANCE='5%',
 MATERIAL='CHIP',
 PHYS_PAGE='54',
 XY='(-8625,4475)',
 ROT='0',
 VER='2',
 PACK_TYPE='0402LF',
 LOCATION='R521',
 CDS_LIB='pure_quanta',
 CDS_PART_NAME='Q_RES_0402LF-2.2K,5%,1/16W,CHIP,CS22202JB07',
 PART_NUMBER='CS22202JB07',
 VALUE='2.2K',
 PRIM_FILE='./archive_libs/logical/q_res/chips/chips.prt';

PART_NAME
 R522 'Q_RES_0402LF-2.2K,5%,1/16W,CHIP,CS22202JB07':;

SECTION_NUMBER 1
 '@T6G_MB_LIB.T6G(SCH_1):PAGE54_I388@PURE_QUANTA.Q_RES(CHIPS)':
 C_PATH='@t6g_mb_lib.t6g(sch_1):page54_i388@pure_quanta.q_res(chips)',
 P_PATH='@t6g_mb_lib.t6g(sch_1):page54_i388@pure_quanta.q_res(chips)',
 PATH='I388',
 DRAWING='@T6G_MB_LIB.T6G(SCH_1):PAGE54',
 WATTAGE='1/16W',
 TOLERANCE='5%',
 MATERIAL='CHIP',
 PHYS_PAGE='54',
 XY='(-8750,3325)',
 ROT='0',
 VER='1',
 PACK_TYPE='0402LF',
 LOCATION='R522',
 CDS_LIB='pure_quanta',
 CDS_PART_NAME='Q_RES_0402LF-2.2K,5%,1/16W,CHIP,CS22202JB07',
 PART_NUMBER='CS22202JB07',
 VALUE='2.2K',
 PRIM_FILE='./archive_libs/logical/q_res/chips/chips.prt';

PART_NAME
 R523 'Q_RES_0402LF-1K,1%,1/16W,CHIP,CS21002FB06':;

SECTION_NUMBER 1
 '@T6G_MB_LIB.T6G(SCH_1):PAGE54_I324@PURE_QUANTA.Q_RES(CHIPS)':
 C_PATH='@t6g_mb_lib.t6g(sch_1):page54_i324@pure_quanta.q_res(chips)',
 P_PATH='@t6g_mb_lib.t6g(sch_1):page54_i324@pure_quanta.q_res(chips)',
 PATH='I324',
 DRAWING='@T6G_MB_LIB.T6G(SCH_1):PAGE54',
 WATTAGE='1/16W',
 TOLERANCE='1%',
 MATERIAL='CHIP',
 PHYS_PAGE='54',
 XY='(-8275,1325)',
 ROT='0',
 VER='2',
 PACK_TYPE='0402LF',
 LOCATION='R523',
 CDS_LIB='pure_quanta',
 CDS_PART_NAME='Q_RES_0402LF-1K,1%,1/16W,CHIP,CS21002FB06',
 PART_NUMBER='CS21002FB06',
 VALUE='1K',
 PRIM_FILE='./archive_libs/logical/q_res/chips/chips.prt';

PART_NAME
 R524 'Q_RES_0402LF-1K,1%,1/16W,CHIP,CS21002FB06':;

SECTION_NUMBER 1
 '@T6G_MB_LIB.T6G(SCH_1):PAGE54_I317@PURE_QUANTA.Q_RES(CHIPS)':
 C_PATH='@t6g_mb_lib.t6g(sch_1):page54_i317@pure_quanta.q_res(chips)',
 P_PATH='@t6g_mb_lib.t6g(sch_1):page54_i317@pure_quanta.q_res(chips)',
 PATH='I317',
 DRAWING='@T6G_MB_LIB.T6G(SCH_1):PAGE54',
 WATTAGE='1/16W',
 TOLERANCE='1%',
 MATERIAL='CHIP',
 PHYS_PAGE='54',
 XY='(-7950,1325)',
 ROT='0',
 VER='2',
 PACK_TYPE='0402LF',
 LOCATION='R524',
 CDS_LIB='pure_quanta',
 CDS_PART_NAME='Q_RES_0402LF-1K,1%,1/16W,CHIP,CS21002FB06',
 PART_NUMBER='CS21002FB06',
 VALUE='1K',
 PRIM_FILE='./archive_libs/logical/q_res/chips/chips.prt';

PART_NAME
 R525 'Q_RES_0402LF-1K,1%,1/16W,CHIP,CS21002FB06':;

SECTION_NUMBER 1
 '@T6G_MB_LIB.T6G(SCH_1):PAGE54_I316@PURE_QUANTA.Q_RES(CHIPS)':
 C_PATH='@t6g_mb_lib.t6g(sch_1):page54_i316@pure_quanta.q_res(chips)',
 P_PATH='@t6g_mb_lib.t6g(sch_1):page54_i316@pure_quanta.q_res(chips)',
 PATH='I316',
 DRAWING='@T6G_MB_LIB.T6G(SCH_1):PAGE54',
 WATTAGE='1/16W',
 TOLERANCE='1%',
 MATERIAL='CHIP',
 PHYS_PAGE='54',
 XY='(-7625,1325)',
 ROT='0',
 VER='2',
 PACK_TYPE='0402LF',
 LOCATION='R525',
 CDS_LIB='pure_quanta',
 CDS_PART_NAME='Q_RES_0402LF-1K,1%,1/16W,CHIP,CS21002FB06',
 PART_NUMBER='CS21002FB06',
 VALUE='1K',
 PRIM_FILE='./archive_libs/logical/q_res/chips/chips.prt';

PART_NAME
 R526 'Q_RES_0402LF-1K,1%,1/16W,CHIP,CS21002FB06':;

SECTION_NUMBER 1
 '@T6G_MB_LIB.T6G(SCH_1):PAGE54_I314@PURE_QUANTA.Q_RES(CHIPS)':
 C_PATH='@t6g_mb_lib.t6g(sch_1):page54_i314@pure_quanta.q_res(chips)',
 P_PATH='@t6g_mb_lib.t6g(sch_1):page54_i314@pure_quanta.q_res(chips)',
 PATH='I314',
 DRAWING='@T6G_MB_LIB.T6G(SCH_1):PAGE54',
 WATTAGE='1/16W',
 TOLERANCE='1%',
 MATERIAL='CHIP',
 PHYS_PAGE='54',
 XY='(-7300,1325)',
 ROT='0',
 VER='2',
 PACK_TYPE='0402LF',
 LOCATION='R526',
 CDS_LIB='pure_quanta',
 CDS_PART_NAME='Q_RES_0402LF-1K,1%,1/16W,CHIP,CS21002FB06',
 PART_NUMBER='CS21002FB06',
 VALUE='1K',
 PRIM_FILE='./archive_libs/logical/q_res/chips/chips.prt';

PART_NAME
 R527 'Q_RES_0402LF-1K,1%,1/16W,CHIP,CS21002FB06':;

SECTION_NUMBER 1
 '@T6G_MB_LIB.T6G(SCH_1):PAGE54_I309@PURE_QUANTA.Q_RES(CHIPS)':
 C_PATH='@t6g_mb_lib.t6g(sch_1):page54_i309@pure_quanta.q_res(chips)',
 P_PATH='@t6g_mb_lib.t6g(sch_1):page54_i309@pure_quanta.q_res(chips)',
 PATH='I309',
 DRAWING='@T6G_MB_LIB.T6G(SCH_1):PAGE54',
 WATTAGE='1/16W',
 TOLERANCE='1%',
 MATERIAL='CHIP',
 PHYS_PAGE='54',
 XY='(-7000,1325)',
 ROT='0',
 VER='2',
 PACK_TYPE='0402LF',
 LOCATION='R527',
 CDS_LIB='pure_quanta',
 CDS_PART_NAME='Q_RES_0402LF-1K,1%,1/16W,CHIP,CS21002FB06',
 PART_NUMBER='CS21002FB06',
 VALUE='1K',
 PRIM_FILE='./archive_libs/logical/q_res/chips/chips.prt';

PART_NAME
 R528 'Q_RES_0402LF-1K,1%,1/16W,CHIP,CS21002FB06':;

SECTION_NUMBER 1
 '@T6G_MB_LIB.T6G(SCH_1):PAGE54_I308@PURE_QUANTA.Q_RES(CHIPS)':
 C_PATH='@t6g_mb_lib.t6g(sch_1):page54_i308@pure_quanta.q_res(chips)',
 P_PATH='@t6g_mb_lib.t6g(sch_1):page54_i308@pure_quanta.q_res(chips)',
 PATH='I308',
 DRAWING='@T6G_MB_LIB.T6G(SCH_1):PAGE54',
 WATTAGE='1/16W',
 TOLERANCE='1%',
 MATERIAL='CHIP',
 PHYS_PAGE='54',
 XY='(-6725,1325)',
 ROT='0',
 VER='2',
 PACK_TYPE='0402LF',
 LOCATION='R528',
 CDS_LIB='pure_quanta',
 CDS_PART_NAME='Q_RES_0402LF-1K,1%,1/16W,CHIP,CS21002FB06',
 PART_NUMBER='CS21002FB06',
 VALUE='1K',
 PRIM_FILE='./archive_libs/logical/q_res/chips/chips.prt';

PART_NAME
 R529 'Q_RES_0402LF-0,5%,1/16W,CHIP,CS00002JB13':;

SECTION_NUMBER 1
 '@T6G_MB_LIB.T6G(SCH_1):PAGE54_I203@PURE_QUANTA.Q_RES(CHIPS)':
 C_PATH='@t6g_mb_lib.t6g(sch_1):page54_i203@pure_quanta.q_res(chips)',
 P_PATH='@t6g_mb_lib.t6g(sch_1):page54_i203@pure_quanta.q_res(chips)',
 PATH='I203',
 DRAWING='@T6G_MB_LIB.T6G(SCH_1):PAGE54',
 WATTAGE='1/16W',
 TOLERANCE='5%',
 MATERIAL='CHIP',
 PHYS_PAGE='54',
 XY='(-6100,4825)',
 ROT='2',
 VER='1',
 PACK_TYPE='0402LF',
 LOCATION='R529',
 CDS_LIB='pure_quanta',
 CDS_PART_NAME='Q_RES_0402LF-0,5%,1/16W,CHIP,CS00002JB13',
 PART_NUMBER='CS00002JB13',
 VALUE='0',
 PRIM_FILE='./archive_libs/logical/q_res/chips/chips.prt';

PART_NAME
 R530 'Q_RES_0402LF-0,5%,1/16W,CHIP,CS00002JB13':;

SECTION_NUMBER 1
 '@T6G_MB_LIB.T6G(SCH_1):PAGE84_I27@PURE_QUANTA.Q_RES(CHIPS)':
 C_PATH='@t6g_mb_lib.t6g(sch_1):page84_i27@pure_quanta.q_res(chips)',
 P_PATH='@t6g_mb_lib.t6g(sch_1):page85_i27@pure_quanta.q_res(chips)',
 PATH='I27',
 DRAWING='@T6G_MB_LIB.T6G(SCH_1):PAGE84',
 WATTAGE='1/16W',
 TOLERANCE='5%',
 MATERIAL='CHIP',
 PHYS_PAGE='85',
 XY='(-6525,6300)',
 ROT='2',
 VER='2',
 PACK_TYPE='0402LF',
 LOCATION='R530',
 CDS_LIB='pure_quanta',
 CDS_PART_NAME='Q_RES_0402LF-0,5%,1/16W,CHIP,CS00002JB13',
 PART_NUMBER='CS00002JB13',
 VALUE='0',
 PRIM_FILE='./archive_libs/logical/q_res/chips/chips.prt';

PART_NAME
 R531 'Q_RES_0402LF-2.2K,5%,1/16W,CHIP,CS22202JB07':;

SECTION_NUMBER 1
 '@T6G_MB_LIB.T6G(SCH_1):PAGE54_I406@PURE_QUANTA.Q_RES(CHIPS)':
 C_PATH='@t6g_mb_lib.t6g(sch_1):page54_i406@pure_quanta.q_res(chips)',
 P_PATH='@t6g_mb_lib.t6g(sch_1):page54_i406@pure_quanta.q_res(chips)',
 PATH='I406',
 DRAWING='@T6G_MB_LIB.T6G(SCH_1):PAGE54',
 WATTAGE='1/16W',
 TOLERANCE='5%',
 MATERIAL='CHIP',
 PHYS_PAGE='54',
 XY='(-500,6075)',
 ROT='0',
 VER='1',
 PACK_TYPE='0402LF',
 LOCATION='R531',
 CDS_LIB='pure_quanta',
 CDS_PART_NAME='Q_RES_0402LF-2.2K,5%,1/16W,CHIP,CS22202JB07',
 PART_NUMBER='CS22202JB07',
 VALUE='2.2K',
 PRIM_FILE='./archive_libs/logical/q_res/chips/chips.prt';

PART_NAME
 R532 'Q_RES_0402LF-2.2K,5%,1/16W,CHIP,CS22202JB07':;

SECTION_NUMBER 1
 '@T6G_MB_LIB.T6G(SCH_1):PAGE54_I407@PURE_QUANTA.Q_RES(CHIPS)':
 C_PATH='@t6g_mb_lib.t6g(sch_1):page54_i407@pure_quanta.q_res(chips)',
 P_PATH='@t6g_mb_lib.t6g(sch_1):page54_i407@pure_quanta.q_res(chips)',
 PATH='I407',
 DRAWING='@T6G_MB_LIB.T6G(SCH_1):PAGE54',
 WATTAGE='1/16W',
 TOLERANCE='5%',
 MATERIAL='CHIP',
 PHYS_PAGE='54',
 XY='(-500,6025)',
 ROT='0',
 VER='1',
 PACK_TYPE='0402LF',
 LOCATION='R532',
 CDS_LIB='pure_quanta',
 CDS_PART_NAME='Q_RES_0402LF-2.2K,5%,1/16W,CHIP,CS22202JB07',
 PART_NUMBER='CS22202JB07',
 VALUE='2.2K',
 PRIM_FILE='./archive_libs/logical/q_res/chips/chips.prt';

PART_NAME
 R533 'Q_RES_0402LF-2.2K,5%,1/16W,CHIP,CS22202JB07':;

SECTION_NUMBER 1
 '@T6G_MB_LIB.T6G(SCH_1):PAGE54_I408@PURE_QUANTA.Q_RES(CHIPS)':
 C_PATH='@t6g_mb_lib.t6g(sch_1):page54_i408@pure_quanta.q_res(chips)',
 P_PATH='@t6g_mb_lib.t6g(sch_1):page54_i408@pure_quanta.q_res(chips)',
 PATH='I408',
 DRAWING='@T6G_MB_LIB.T6G(SCH_1):PAGE54',
 WATTAGE='1/16W',
 TOLERANCE='5%',
 MATERIAL='CHIP',
 PHYS_PAGE='54',
 XY='(-500,5975)',
 ROT='0',
 VER='1',
 PACK_TYPE='0402LF',
 LOCATION='R533',
 CDS_LIB='pure_quanta',
 CDS_PART_NAME='Q_RES_0402LF-2.2K,5%,1/16W,CHIP,CS22202JB07',
 PART_NUMBER='CS22202JB07',
 VALUE='2.2K',
 PRIM_FILE='./archive_libs/logical/q_res/chips/chips.prt';

PART_NAME
 R534 'Q_RES_0402LF-2.2K,5%,1/16W,CHIP,CS22202JB07':;

SECTION_NUMBER 1
 '@T6G_MB_LIB.T6G(SCH_1):PAGE54_I409@PURE_QUANTA.Q_RES(CHIPS)':
 C_PATH='@t6g_mb_lib.t6g(sch_1):page54_i409@pure_quanta.q_res(chips)',
 P_PATH='@t6g_mb_lib.t6g(sch_1):page54_i409@pure_quanta.q_res(chips)',
 PATH='I409',
 DRAWING='@T6G_MB_LIB.T6G(SCH_1):PAGE54',
 WATTAGE='1/16W',
 TOLERANCE='5%',
 MATERIAL='CHIP',
 PHYS_PAGE='54',
 XY='(-500,5925)',
 ROT='0',
 VER='1',
 PACK_TYPE='0402LF',
 LOCATION='R534',
 CDS_LIB='pure_quanta',
 CDS_PART_NAME='Q_RES_0402LF-2.2K,5%,1/16W,CHIP,CS22202JB07',
 PART_NUMBER='CS22202JB07',
 VALUE='2.2K',
 PRIM_FILE='./archive_libs/logical/q_res/chips/chips.prt';

PART_NAME
 R535 'Q_RES_0402LF-2.2K,5%,1/16W,CHIP,CS22202JB07':;

SECTION_NUMBER 1
 '@T6G_MB_LIB.T6G(SCH_1):PAGE54_I398@PURE_QUANTA.Q_RES(CHIPS)':
 C_PATH='@t6g_mb_lib.t6g(sch_1):page54_i398@pure_quanta.q_res(chips)',
 P_PATH='@t6g_mb_lib.t6g(sch_1):page54_i398@pure_quanta.q_res(chips)',
 PATH='I398',
 DRAWING='@T6G_MB_LIB.T6G(SCH_1):PAGE54',
 WATTAGE='1/16W',
 TOLERANCE='5%',
 MATERIAL='CHIP',
 PHYS_PAGE='54',
 XY='(-500,5875)',
 ROT='0',
 VER='1',
 PACK_TYPE='0402LF',
 LOCATION='R535',
 CDS_LIB='pure_quanta',
 CDS_PART_NAME='Q_RES_0402LF-2.2K,5%,1/16W,CHIP,CS22202JB07',
 PART_NUMBER='CS22202JB07',
 VALUE='2.2K',
 PRIM_FILE='./archive_libs/logical/q_res/chips/chips.prt';

PART_NAME
 R536 'Q_RES_0402LF-2.2K,5%,1/16W,EMPTY,CS22202JB07':;

SECTION_NUMBER 1
 '@T6G_MB_LIB.T6G(SCH_1):PAGE54_I421@PURE_QUANTA.Q_RES(CHIPS)':
 C_PATH='@t6g_mb_lib.t6g(sch_1):page54_i421@pure_quanta.q_res(chips)',
 P_PATH='@t6g_mb_lib.t6g(sch_1):page54_i421@pure_quanta.q_res(chips)',
 PATH='I421',
 DRAWING='@T6G_MB_LIB.T6G(SCH_1):PAGE54',
 WATTAGE='1/16W',
 TOLERANCE='5%',
 MATERIAL='EMPTY',
 PHYS_PAGE='54',
 XY='(-500,5825)',
 ROT='0',
 VER='1',
 PACK_TYPE='0402LF',
 LOCATION='R536',
 CDS_LIB='pure_quanta',
 CDS_PART_NAME='Q_RES_0402LF-2.2K,5%,1/16W,EMPTY,CS22202JB07',
 PART_NUMBER='CS22202JB07',
 VALUE='2.2K',
 PRIM_FILE='./archive_libs/logical/q_res/chips/chips.prt';

PART_NAME
 R537 'Q_RES_0402LF-2.2K,5%,1/16W,CHIP,CS22202JB07':;

SECTION_NUMBER 1
 '@T6G_MB_LIB.T6G(SCH_1):PAGE54_I410@PURE_QUANTA.Q_RES(CHIPS)':
 C_PATH='@t6g_mb_lib.t6g(sch_1):page54_i410@pure_quanta.q_res(chips)',
 P_PATH='@t6g_mb_lib.t6g(sch_1):page54_i410@pure_quanta.q_res(chips)',
 PATH='I410',
 DRAWING='@T6G_MB_LIB.T6G(SCH_1):PAGE54',
 WATTAGE='1/16W',
 TOLERANCE='5%',
 MATERIAL='CHIP',
 PHYS_PAGE='54',
 XY='(-500,5775)',
 ROT='0',
 VER='1',
 PACK_TYPE='0402LF',
 LOCATION='R537',
 CDS_LIB='pure_quanta',
 CDS_PART_NAME='Q_RES_0402LF-2.2K,5%,1/16W,CHIP,CS22202JB07',
 PART_NUMBER='CS22202JB07',
 VALUE='2.2K',
 PRIM_FILE='./archive_libs/logical/q_res/chips/chips.prt';

PART_NAME
 R538 'Q_RES_0402LF-2.2K,5%,1/16W,CHIP,CS22202JB07':;

SECTION_NUMBER 1
 '@T6G_MB_LIB.T6G(SCH_1):PAGE54_I411@PURE_QUANTA.Q_RES(CHIPS)':
 C_PATH='@t6g_mb_lib.t6g(sch_1):page54_i411@pure_quanta.q_res(chips)',
 P_PATH='@t6g_mb_lib.t6g(sch_1):page54_i411@pure_quanta.q_res(chips)',
 PATH='I411',
 DRAWING='@T6G_MB_LIB.T6G(SCH_1):PAGE54',
 WATTAGE='1/16W',
 TOLERANCE='5%',
 MATERIAL='CHIP',
 PHYS_PAGE='54',
 XY='(-500,5725)',
 ROT='0',
 VER='1',
 PACK_TYPE='0402LF',
 LOCATION='R538',
 CDS_LIB='pure_quanta',
 CDS_PART_NAME='Q_RES_0402LF-2.2K,5%,1/16W,CHIP,CS22202JB07',
 PART_NUMBER='CS22202JB07',
 VALUE='2.2K',
 PRIM_FILE='./archive_libs/logical/q_res/chips/chips.prt';

PART_NAME
 R539 'Q_RES_0402LF-2.2K,5%,1/16W,CHIP,CS22202JB07':;

SECTION_NUMBER 1
 '@T6G_MB_LIB.T6G(SCH_1):PAGE54_I412@PURE_QUANTA.Q_RES(CHIPS)':
 C_PATH='@t6g_mb_lib.t6g(sch_1):page54_i412@pure_quanta.q_res(chips)',
 P_PATH='@t6g_mb_lib.t6g(sch_1):page54_i412@pure_quanta.q_res(chips)',
 PATH='I412',
 DRAWING='@T6G_MB_LIB.T6G(SCH_1):PAGE54',
 WATTAGE='1/16W',
 TOLERANCE='5%',
 MATERIAL='CHIP',
 PHYS_PAGE='54',
 XY='(-500,5675)',
 ROT='0',
 VER='1',
 PACK_TYPE='0402LF',
 LOCATION='R539',
 CDS_LIB='pure_quanta',
 CDS_PART_NAME='Q_RES_0402LF-2.2K,5%,1/16W,CHIP,CS22202JB07',
 PART_NUMBER='CS22202JB07',
 VALUE='2.2K',
 PRIM_FILE='./archive_libs/logical/q_res/chips/chips.prt';

PART_NAME
 R540 'Q_RES_0402LF-2.2K,5%,1/16W,CHIP,CS22202JB07':;

SECTION_NUMBER 1
 '@T6G_MB_LIB.T6G(SCH_1):PAGE54_I413@PURE_QUANTA.Q_RES(CHIPS)':
 C_PATH='@t6g_mb_lib.t6g(sch_1):page54_i413@pure_quanta.q_res(chips)',
 P_PATH='@t6g_mb_lib.t6g(sch_1):page54_i413@pure_quanta.q_res(chips)',
 PATH='I413',
 DRAWING='@T6G_MB_LIB.T6G(SCH_1):PAGE54',
 WATTAGE='1/16W',
 TOLERANCE='5%',
 MATERIAL='CHIP',
 PHYS_PAGE='54',
 XY='(-500,5625)',
 ROT='0',
 VER='1',
 PACK_TYPE='0402LF',
 LOCATION='R540',
 CDS_LIB='pure_quanta',
 CDS_PART_NAME='Q_RES_0402LF-2.2K,5%,1/16W,CHIP,CS22202JB07',
 PART_NUMBER='CS22202JB07',
 VALUE='2.2K',
 PRIM_FILE='./archive_libs/logical/q_res/chips/chips.prt';

PART_NAME
 R541 'Q_RES_0402LF-1K,1%,1/16W,EMPTY,CS21002FB06':;

SECTION_NUMBER 1
 '@T6G_MB_LIB.T6G(SCH_1):PAGE55_I365@PURE_QUANTA.Q_RES(CHIPS)':
 C_PATH='@t6g_mb_lib.t6g(sch_1):page55_i365@pure_quanta.q_res(chips)',
 P_PATH='@t6g_mb_lib.t6g(sch_1):page55_i365@pure_quanta.q_res(chips)',
 PATH='I365',
 DRAWING='@T6G_MB_LIB.T6G(SCH_1):PAGE55',
 WATTAGE='1/16W',
 TOLERANCE='1%',
 MATERIAL='EMPTY',
 PHYS_PAGE='55',
 XY='(-9050,3000)',
 ROT='0',
 VER='2',
 PACK_TYPE='0402LF',
 LOCATION='R541',
 CDS_LIB='pure_quanta',
 CDS_PART_NAME='Q_RES_0402LF-1K,1%,1/16W,EMPTY,CS21002FB06',
 PART_NUMBER='CS21002FB06',
 VALUE='1K',
 PRIM_FILE='./archive_libs/logical/q_res/chips/chips.prt';

PART_NAME
 R542 'Q_RES_0402LF-1K,1%,1/16W,EMPTY,CS21002FB06':;

SECTION_NUMBER 1
 '@T6G_MB_LIB.T6G(SCH_1):PAGE55_I366@PURE_QUANTA.Q_RES(CHIPS)':
 C_PATH='@t6g_mb_lib.t6g(sch_1):page55_i366@pure_quanta.q_res(chips)',
 P_PATH='@t6g_mb_lib.t6g(sch_1):page55_i366@pure_quanta.q_res(chips)',
 PATH='I366',
 DRAWING='@T6G_MB_LIB.T6G(SCH_1):PAGE55',
 WATTAGE='1/16W',
 TOLERANCE='1%',
 MATERIAL='EMPTY',
 PHYS_PAGE='55',
 XY='(-8875,3000)',
 ROT='0',
 VER='2',
 PACK_TYPE='0402LF',
 LOCATION='R542',
 CDS_LIB='pure_quanta',
 CDS_PART_NAME='Q_RES_0402LF-1K,1%,1/16W,EMPTY,CS21002FB06',
 PART_NUMBER='CS21002FB06',
 VALUE='1K',
 PRIM_FILE='./archive_libs/logical/q_res/chips/chips.prt';

PART_NAME
 R543 'Q_RES_0402LF-1K,1%,1/16W,EMPTY,CS21002FB06':;

SECTION_NUMBER 1
 '@T6G_MB_LIB.T6G(SCH_1):PAGE55_I367@PURE_QUANTA.Q_RES(CHIPS)':
 C_PATH='@t6g_mb_lib.t6g(sch_1):page55_i367@pure_quanta.q_res(chips)',
 P_PATH='@t6g_mb_lib.t6g(sch_1):page55_i367@pure_quanta.q_res(chips)',
 PATH='I367',
 DRAWING='@T6G_MB_LIB.T6G(SCH_1):PAGE55',
 WATTAGE='1/16W',
 TOLERANCE='1%',
 MATERIAL='EMPTY',
 PHYS_PAGE='55',
 XY='(-8700,3000)',
 ROT='0',
 VER='2',
 PACK_TYPE='0402LF',
 LOCATION='R543',
 CDS_LIB='pure_quanta',
 CDS_PART_NAME='Q_RES_0402LF-1K,1%,1/16W,EMPTY,CS21002FB06',
 PART_NUMBER='CS21002FB06',
 VALUE='1K',
 PRIM_FILE='./archive_libs/logical/q_res/chips/chips.prt';

PART_NAME
 R544 'Q_RES_0402LF-4.7K,5%,1/16W,CHIP,CS24702JB10':;

SECTION_NUMBER 1
 '@T6G_MB_LIB.T6G(SCH_1):PAGE55_I336@PURE_QUANTA.Q_RES(CHIPS)':
 C_PATH='@t6g_mb_lib.t6g(sch_1):page55_i336@pure_quanta.q_res(chips)',
 P_PATH='@t6g_mb_lib.t6g(sch_1):page55_i336@pure_quanta.q_res(chips)',
 PATH='I336',
 DRAWING='@T6G_MB_LIB.T6G(SCH_1):PAGE55',
 WATTAGE='1/16W',
 TOLERANCE='5%',
 MATERIAL='CHIP',
 PHYS_PAGE='55',
 XY='(-9100,1150)',
 ROT='1',
 VER='1',
 PACK_TYPE='0402LF',
 LOCATION='R544',
 CDS_LIB='pure_quanta',
 CDS_PART_NAME='Q_RES_0402LF-4.7K,5%,1/16W,CHIP,CS24702JB10',
 PART_NUMBER='CS24702JB10',
 VALUE='4.7K',
 PRIM_FILE='./archive_libs/logical/q_res/chips/chips.prt';

PART_NAME
 R545 'Q_RES_0402LF-4.7K,5%,1/16W,CHIP,CS24702JB10':;

SECTION_NUMBER 1
 '@T6G_MB_LIB.T6G(SCH_1):PAGE55_I337@PURE_QUANTA.Q_RES(CHIPS)':
 C_PATH='@t6g_mb_lib.t6g(sch_1):page55_i337@pure_quanta.q_res(chips)',
 P_PATH='@t6g_mb_lib.t6g(sch_1):page55_i337@pure_quanta.q_res(chips)',
 PATH='I337',
 DRAWING='@T6G_MB_LIB.T6G(SCH_1):PAGE55',
 WATTAGE='1/16W',
 TOLERANCE='5%',
 MATERIAL='CHIP',
 PHYS_PAGE='55',
 XY='(-8975,1150)',
 ROT='1',
 VER='1',
 PACK_TYPE='0402LF',
 LOCATION='R545',
 CDS_LIB='pure_quanta',
 CDS_PART_NAME='Q_RES_0402LF-4.7K,5%,1/16W,CHIP,CS24702JB10',
 PART_NUMBER='CS24702JB10',
 VALUE='4.7K',
 PRIM_FILE='./archive_libs/logical/q_res/chips/chips.prt';

PART_NAME
 R546 'Q_RES_0402LF-4.7K,5%,1/16W,CHIP,CS24702JB10':;

SECTION_NUMBER 1
 '@T6G_MB_LIB.T6G(SCH_1):PAGE55_I338@PURE_QUANTA.Q_RES(CHIPS)':
 C_PATH='@t6g_mb_lib.t6g(sch_1):page55_i338@pure_quanta.q_res(chips)',
 P_PATH='@t6g_mb_lib.t6g(sch_1):page55_i338@pure_quanta.q_res(chips)',
 PATH='I338',
 DRAWING='@T6G_MB_LIB.T6G(SCH_1):PAGE55',
 WATTAGE='1/16W',
 TOLERANCE='5%',
 MATERIAL='CHIP',
 PHYS_PAGE='55',
 XY='(-8850,1150)',
 ROT='1',
 VER='1',
 PACK_TYPE='0402LF',
 LOCATION='R546',
 CDS_LIB='pure_quanta',
 CDS_PART_NAME='Q_RES_0402LF-4.7K,5%,1/16W,CHIP,CS24702JB10',
 PART_NUMBER='CS24702JB10',
 VALUE='4.7K',
 PRIM_FILE='./archive_libs/logical/q_res/chips/chips.prt';

PART_NAME
 R547 'Q_RES_0402LF-4.7K,5%,1/16W,CHIP,CS24702JB10':;

SECTION_NUMBER 1
 '@T6G_MB_LIB.T6G(SCH_1):PAGE55_I362@PURE_QUANTA.Q_RES(CHIPS)':
 C_PATH='@t6g_mb_lib.t6g(sch_1):page55_i362@pure_quanta.q_res(chips)',
 P_PATH='@t6g_mb_lib.t6g(sch_1):page55_i362@pure_quanta.q_res(chips)',
 PATH='I362',
 DRAWING='@T6G_MB_LIB.T6G(SCH_1):PAGE55',
 WATTAGE='1/16W',
 TOLERANCE='5%',
 MATERIAL='CHIP',
 PHYS_PAGE='55',
 XY='(-8625,2250)',
 ROT='2',
 VER='1',
 PACK_TYPE='0402LF',
 LOCATION='R547',
 CDS_LIB='pure_quanta',
 CDS_PART_NAME='Q_RES_0402LF-4.7K,5%,1/16W,CHIP,CS24702JB10',
 PART_NUMBER='CS24702JB10',
 VALUE='4.7K',
 PRIM_FILE='./archive_libs/logical/q_res/chips/chips.prt';

PART_NAME
 R548 'Q_RES_0402LF-4.7K,5%,1/16W,EMPTY,CS24702JB10':;

SECTION_NUMBER 1
 '@T6G_MB_LIB.T6G(SCH_1):PAGE55_I352@PURE_QUANTA.Q_RES(CHIPS)':
 C_PATH='@t6g_mb_lib.t6g(sch_1):page55_i352@pure_quanta.q_res(chips)',
 P_PATH='@t6g_mb_lib.t6g(sch_1):page55_i352@pure_quanta.q_res(chips)',
 PATH='I352',
 DRAWING='@T6G_MB_LIB.T6G(SCH_1):PAGE55',
 WATTAGE='1/16W',
 TOLERANCE='5%',
 MATERIAL='EMPTY',
 PHYS_PAGE='55',
 XY='(-8625,1700)',
 ROT='2',
 VER='1',
 PACK_TYPE='0402LF',
 LOCATION='R548',
 CDS_LIB='pure_quanta',
 CDS_PART_NAME='Q_RES_0402LF-4.7K,5%,1/16W,EMPTY,CS24702JB10',
 PART_NUMBER='CS24702JB10',
 VALUE='4.7K',
 PRIM_FILE='./archive_libs/logical/q_res/chips/chips.prt';

PART_NAME
 R549 'Q_RES_0402LF-4.7K,5%,1/16W,EMPTY,CS24702JB10':;

SECTION_NUMBER 1
 '@T6G_MB_LIB.T6G(SCH_1):PAGE55_I353@PURE_QUANTA.Q_RES(CHIPS)':
 C_PATH='@t6g_mb_lib.t6g(sch_1):page55_i353@pure_quanta.q_res(chips)',
 P_PATH='@t6g_mb_lib.t6g(sch_1):page55_i353@pure_quanta.q_res(chips)',
 PATH='I353',
 DRAWING='@T6G_MB_LIB.T6G(SCH_1):PAGE55',
 WATTAGE='1/16W',
 TOLERANCE='5%',
 MATERIAL='EMPTY',
 PHYS_PAGE='55',
 XY='(-8625,1650)',
 ROT='2',
 VER='1',
 PACK_TYPE='0402LF',
 LOCATION='R549',
 CDS_LIB='pure_quanta',
 CDS_PART_NAME='Q_RES_0402LF-4.7K,5%,1/16W,EMPTY,CS24702JB10',
 PART_NUMBER='CS24702JB10',
 VALUE='4.7K',
 PRIM_FILE='./archive_libs/logical/q_res/chips/chips.prt';

PART_NAME
 R550 'Q_RES_0402LF-4.7K,5%,1/16W,CHIP,CS24702JB10':;

SECTION_NUMBER 1
 '@T6G_MB_LIB.T6G(SCH_1):PAGE55_I363@PURE_QUANTA.Q_RES(CHIPS)':
 C_PATH='@t6g_mb_lib.t6g(sch_1):page55_i363@pure_quanta.q_res(chips)',
 P_PATH='@t6g_mb_lib.t6g(sch_1):page55_i363@pure_quanta.q_res(chips)',
 PATH='I363',
 DRAWING='@T6G_MB_LIB.T6G(SCH_1):PAGE55',
 WATTAGE='1/16W',
 TOLERANCE='5%',
 MATERIAL='CHIP',
 PHYS_PAGE='55',
 XY='(-8625,2150)',
 ROT='2',
 VER='1',
 PACK_TYPE='0402LF',
 LOCATION='R550',
 CDS_LIB='pure_quanta',
 CDS_PART_NAME='Q_RES_0402LF-4.7K,5%,1/16W,CHIP,CS24702JB10',
 PART_NUMBER='CS24702JB10',
 VALUE='4.7K',
 PRIM_FILE='./archive_libs/logical/q_res/chips/chips.prt';

PART_NAME
 R551 'Q_RES_0402LF-4.7K,5%,1/16W,CHIP,CS24702JB10':;

SECTION_NUMBER 1
 '@T6G_MB_LIB.T6G(SCH_1):PAGE55_I360@PURE_QUANTA.Q_RES(CHIPS)':
 C_PATH='@t6g_mb_lib.t6g(sch_1):page55_i360@pure_quanta.q_res(chips)',
 P_PATH='@t6g_mb_lib.t6g(sch_1):page55_i360@pure_quanta.q_res(chips)',
 PATH='I360',
 DRAWING='@T6G_MB_LIB.T6G(SCH_1):PAGE55',
 WATTAGE='1/16W',
 TOLERANCE='5%',
 MATERIAL='CHIP',
 PHYS_PAGE='55',
 XY='(-8625,2100)',
 ROT='2',
 VER='1',
 PACK_TYPE='0402LF',
 LOCATION='R551',
 CDS_LIB='pure_quanta',
 CDS_PART_NAME='Q_RES_0402LF-4.7K,5%,1/16W,CHIP,CS24702JB10',
 PART_NUMBER='CS24702JB10',
 VALUE='4.7K',
 PRIM_FILE='./archive_libs/logical/q_res/chips/chips.prt';

PART_NAME
 R552 'Q_RES_0402LF-4.7K,5%,1/16W,CHIP,CS24702JB10':;

SECTION_NUMBER 1
 '@T6G_MB_LIB.T6G(SCH_1):PAGE273_I104@PURE_QUANTA.Q_RES(CHIPS)':
 C_PATH='@t6g_mb_lib.t6g(sch_1):page273_i104@pure_quanta.q_res(chips)',
 P_PATH='@t6g_mb_lib.t6g(sch_1):page188_i104@pure_quanta.q_res(chips)',
 PATH='I104',
 DRAWING='@T6G_MB_LIB.T6G(SCH_1):PAGE273',
 WATTAGE='1/16W',
 TOLERANCE='5%',
 MATERIAL='CHIP',
 PHYS_PAGE='188',
 XY='(300,3325)',
 ROT='2',
 VER='2',
 PACK_TYPE='0402LF',
 LOCATION='R552',
 CDS_LIB='pure_quanta',
 CDS_PART_NAME='Q_RES_0402LF-4.7K,5%,1/16W,CHIP,CS24702JB10',
 PART_NUMBER='CS24702JB10',
 VALUE='4.7K',
 PRIM_FILE='./archive_libs/logical/q_res/chips/chips.prt';

PART_NAME
 R553 'Q_RES_0402LF-4.7K,5%,1/16W,CHIP,CS24702JB10':;

SECTION_NUMBER 1
 '@T6G_MB_LIB.T6G(SCH_1):PAGE55_I359@PURE_QUANTA.Q_RES(CHIPS)':
 C_PATH='@t6g_mb_lib.t6g(sch_1):page55_i359@pure_quanta.q_res(chips)',
 P_PATH='@t6g_mb_lib.t6g(sch_1):page55_i359@pure_quanta.q_res(chips)',
 PATH='I359',
 DRAWING='@T6G_MB_LIB.T6G(SCH_1):PAGE55',
 WATTAGE='1/16W',
 TOLERANCE='5%',
 MATERIAL='CHIP',
 PHYS_PAGE='55',
 XY='(-8625,2050)',
 ROT='2',
 VER='1',
 PACK_TYPE='0402LF',
 LOCATION='R553',
 CDS_LIB='pure_quanta',
 CDS_PART_NAME='Q_RES_0402LF-4.7K,5%,1/16W,CHIP,CS24702JB10',
 PART_NUMBER='CS24702JB10',
 VALUE='4.7K',
 PRIM_FILE='./archive_libs/logical/q_res/chips/chips.prt';

PART_NAME
 R554 'Q_RES_0402LF-100K,1%,1/16W,CHIP,CS41002FB09':;

SECTION_NUMBER 1
 '@T6G_MB_LIB.T6G(SCH_1):PAGE273_I111@PURE_QUANTA.Q_RES(CHIPS)':
 C_PATH='@t6g_mb_lib.t6g(sch_1):page273_i111@pure_quanta.q_res(chips)',
 P_PATH='@t6g_mb_lib.t6g(sch_1):page188_i111@pure_quanta.q_res(chips)',
 PATH='I111',
 DRAWING='@T6G_MB_LIB.T6G(SCH_1):PAGE273',
 SEC_TYPE='0402LF',
 WATTAGE='1/16W',
 TOLERANCE='1%',
 MATERIAL='CHIP',
 PHYS_PAGE='188',
 XY='(-1075,4575)',
 ROT='0',
 VER='2',
 PACK_TYPE='0402LF',
 LOCATION='R554',
 SEC='1',
 CDS_LIB='pure_quanta',
 CDS_PART_NAME='Q_RES_0402LF-100K,1%,1/16W,CHIP,CS41002FB09',
 PART_NUMBER='CS41002FB09',
 VALUE='100K',
 PRIM_FILE='./archive_libs/logical/q_res/chips/chips.prt';

PART_NAME
 R555 'Q_RES_0603LF-1,1%,1/10W,CHIP,CS-1003F900':;

SECTION_NUMBER 1
 '@T6G_MB_LIB.T6G(SCH_1):PAGE379_I20@PURE_QUANTA.Q_RES(CHIPS)':
 C_PATH='@t6g_mb_lib.t6g(sch_1):page379_i20@pure_quanta.q_res(chips)',
 P_PATH='@t6g_mb_lib.t6g(sch_1):page183_i20@pure_quanta.q_res(chips)',
 PATH='I20',
 DRAWING='@T6G_MB_LIB.T6G(SCH_1):PAGE379',
 WATTAGE='1/10W',
 TOLERANCE='1%',
 MATERIAL='CHIP',
 PHYS_PAGE='183',
 XY='(-7550,5000)',
 ROT='0',
 VER='1',
 PACK_TYPE='0603LF',
 LOCATION='R555',
 CDS_LIB='pure_quanta',
 CDS_PART_NAME='Q_RES_0603LF-1,1%,1/10W,CHIP,CS-1003F900',
 PART_NUMBER='CS-1003F900',
 VALUE='1',
 PRIM_FILE='./archive_libs/logical/q_res/chips/chips.prt';

PART_NAME
 R556 'Q_RES_0402LF-1K,1%,1/16W,EMPTY,CS21002FB06':;

SECTION_NUMBER 1
 '@T6G_MB_LIB.T6G(SCH_1):PAGE55_I357@PURE_QUANTA.Q_RES(CHIPS)':
 C_PATH='@t6g_mb_lib.t6g(sch_1):page55_i357@pure_quanta.q_res(chips)',
 P_PATH='@t6g_mb_lib.t6g(sch_1):page55_i357@pure_quanta.q_res(chips)',
 PATH='I357',
 DRAWING='@T6G_MB_LIB.T6G(SCH_1):PAGE55',
 WATTAGE='1/16W',
 TOLERANCE='1%',
 MATERIAL='EMPTY',
 PHYS_PAGE='55',
 XY='(-8625,2000)',
 ROT='0',
 VER='1',
 PACK_TYPE='0402LF',
 LOCATION='R556',
 CDS_LIB='pure_quanta',
 CDS_PART_NAME='Q_RES_0402LF-1K,1%,1/16W,EMPTY,CS21002FB06',
 PART_NUMBER='CS21002FB06',
 VALUE='1K',
 PRIM_FILE='./archive_libs/logical/q_res/chips/chips.prt';

PART_NAME
 R557 'Q_RES_0402LF-1K,1%,1/16W,EMPTY,CS21002FB06':;

SECTION_NUMBER 1
 '@T6G_MB_LIB.T6G(SCH_1):PAGE55_I364@PURE_QUANTA.Q_RES(CHIPS)':
 C_PATH='@t6g_mb_lib.t6g(sch_1):page55_i364@pure_quanta.q_res(chips)',
 P_PATH='@t6g_mb_lib.t6g(sch_1):page55_i364@pure_quanta.q_res(chips)',
 PATH='I364',
 DRAWING='@T6G_MB_LIB.T6G(SCH_1):PAGE55',
 WATTAGE='1/16W',
 TOLERANCE='1%',
 MATERIAL='EMPTY',
 PHYS_PAGE='55',
 XY='(-8625,2200)',
 ROT='0',
 VER='1',
 PACK_TYPE='0402LF',
 LOCATION='R557',
 CDS_LIB='pure_quanta',
 CDS_PART_NAME='Q_RES_0402LF-1K,1%,1/16W,EMPTY,CS21002FB06',
 PART_NUMBER='CS21002FB06',
 VALUE='1K',
 PRIM_FILE='./archive_libs/logical/q_res/chips/chips.prt';

PART_NAME
 R558 'Q_RES_0402LF-4.7K,5%,1/16W,EMPTY,CS24702JB10':;

SECTION_NUMBER 1
 '@T6G_MB_LIB.T6G(SCH_1):PAGE55_I390@PURE_QUANTA.Q_RES(CHIPS)':
 C_PATH='@t6g_mb_lib.t6g(sch_1):page55_i390@pure_quanta.q_res(chips)',
 P_PATH='@t6g_mb_lib.t6g(sch_1):page55_i390@pure_quanta.q_res(chips)',
 PATH='I390',
 DRAWING='@T6G_MB_LIB.T6G(SCH_1):PAGE55',
 SEC_TYPE='0402LF',
 WATTAGE='1/16W',
 TOLERANCE='5%',
 MATERIAL='EMPTY',
 PHYS_PAGE='55',
 XY='(-8625,1950)',
 ROT='2',
 VER='1',
 PACK_TYPE='0402LF',
 LOCATION='R558',
 SEC='1',
 CDS_LIB='pure_quanta',
 CDS_PART_NAME='Q_RES_0402LF-4.7K,5%,1/16W,EMPTY,CS24702JB10',
 PART_NUMBER='CS24702JB10',
 VALUE='4.7K',
 PRIM_FILE='./archive_libs/logical/q_res/chips/chips.prt';

PART_NAME
 R559 'Q_RES_0402LF-2.2K,5%,1/16W,CHIP,CS22202JB07':;

SECTION_NUMBER 1
 '@T6G_MB_LIB.T6G(SCH_1):PAGE55_I356@PURE_QUANTA.Q_RES(CHIPS)':
 C_PATH='@t6g_mb_lib.t6g(sch_1):page55_i356@pure_quanta.q_res(chips)',
 P_PATH='@t6g_mb_lib.t6g(sch_1):page55_i356@pure_quanta.q_res(chips)',
 PATH='I356',
 DRAWING='@T6G_MB_LIB.T6G(SCH_1):PAGE55',
 WATTAGE='1/16W',
 TOLERANCE='5%',
 MATERIAL='CHIP',
 PHYS_PAGE='55',
 XY='(-8625,1900)',
 ROT='0',
 VER='1',
 PACK_TYPE='0402LF',
 LOCATION='R559',
 CDS_LIB='pure_quanta',
 CDS_PART_NAME='Q_RES_0402LF-2.2K,5%,1/16W,CHIP,CS22202JB07',
 PART_NUMBER='CS22202JB07',
 VALUE='2.2K',
 PRIM_FILE='./archive_libs/logical/q_res/chips/chips.prt';

PART_NAME
 R560 'Q_RES_0402LF-10K,1%,1/16W,CHIP,CS31002FB08':;

SECTION_NUMBER 1
 '@T6G_MB_LIB.T6G(SCH_1):PAGE379_I81@PURE_QUANTA.Q_RES(CHIPS)':
 C_PATH='@t6g_mb_lib.t6g(sch_1):page379_i81@pure_quanta.q_res(chips)',
 P_PATH='@t6g_mb_lib.t6g(sch_1):page183_i81@pure_quanta.q_res(chips)',
 PATH='I81',
 DRAWING='@T6G_MB_LIB.T6G(SCH_1):PAGE379',
 WATTAGE='1/16W',
 TOLERANCE='1%',
 MATERIAL='CHIP',
 PHYS_PAGE='183',
 XY='(-7000,3500)',
 ROT='0',
 VER='2',
 PACK_TYPE='0402LF',
 LOCATION='R560',
 CDS_LIB='pure_quanta',
 CDS_PART_NAME='Q_RES_0402LF-10K,1%,1/16W,CHIP,CS31002FB08',
 PART_NUMBER='CS31002FB08',
 VALUE='10K',
 PRIM_FILE='./archive_libs/logical/q_res/chips/chips.prt';

PART_NAME
 R561 'Q_RES_0402LF-0,5%,1/16W,CHIP,CS00002JB13':
 ROOM='NIC_P12V_MAM_TIC_BOM1';

SECTION_NUMBER 1
 '@T6G_MB_LIB.T6G(SCH_1):PAGE338_I125@PURE_QUANTA.Q_RES(CHIPS)':
 C_PATH='@t6g_mb_lib.t6g(sch_1):page338_i125@pure_quanta.q_res(chips)',
 P_PATH='@t6g_mb_lib.t6g(sch_1):page134_i125@pure_quanta.q_res(chips)',
 PATH='I125',
 DRAWING='@T6G_MB_LIB.T6G(SCH_1):PAGE338',
 WATTAGE='1/16W',
 TOLERANCE='5%',
 MATERIAL='CHIP',
 PHYS_PAGE='134',
 XY='(2900,10650)',
 ROT='0',
 VER='1',
 PACK_TYPE='0402LF',
 LOCATION='R561',
 CDS_LIB='pure_quanta',
 CDS_PART_NAME='Q_RES_0402LF-0,5%,1/16W,CHIP,CS00002JB13',
 ROOM='NIC_P12V_MAM_TIC_BOM1',
 PART_NUMBER='CS00002JB13',
 VALUE='0',
 PRIM_FILE='./archive_libs/logical/q_res/chips/chips.prt';

PART_NAME
 R562 'Q_RES_0402LF-2.2K,5%,1/16W,CHIP,CS22202JB07':;

SECTION_NUMBER 1
 '@T6G_MB_LIB.T6G(SCH_1):PAGE55_I355@PURE_QUANTA.Q_RES(CHIPS)':
 C_PATH='@t6g_mb_lib.t6g(sch_1):page55_i355@pure_quanta.q_res(chips)',
 P_PATH='@t6g_mb_lib.t6g(sch_1):page55_i355@pure_quanta.q_res(chips)',
 PATH='I355',
 DRAWING='@T6G_MB_LIB.T6G(SCH_1):PAGE55',
 WATTAGE='1/16W',
 TOLERANCE='5%',
 MATERIAL='CHIP',
 PHYS_PAGE='55',
 XY='(-8625,1850)',
 ROT='0',
 VER='1',
 PACK_TYPE='0402LF',
 LOCATION='R562',
 CDS_LIB='pure_quanta',
 CDS_PART_NAME='Q_RES_0402LF-2.2K,5%,1/16W,CHIP,CS22202JB07',
 PART_NUMBER='CS22202JB07',
 VALUE='2.2K',
 PRIM_FILE='./archive_libs/logical/q_res/chips/chips.prt';

PART_NAME
 R563 'Q_RES_0402LF-1K,1%,1/16W,EMPTY,CS21002FB06':;

SECTION_NUMBER 1
 '@T6G_MB_LIB.T6G(SCH_1):PAGE55_I368@PURE_QUANTA.Q_RES(CHIPS)':
 C_PATH='@t6g_mb_lib.t6g(sch_1):page55_i368@pure_quanta.q_res(chips)',
 P_PATH='@t6g_mb_lib.t6g(sch_1):page55_i368@pure_quanta.q_res(chips)',
 PATH='I368',
 DRAWING='@T6G_MB_LIB.T6G(SCH_1):PAGE55',
 WATTAGE='1/16W',
 TOLERANCE='1%',
 MATERIAL='EMPTY',
 PHYS_PAGE='55',
 XY='(-8525,3000)',
 ROT='0',
 VER='2',
 PACK_TYPE='0402LF',
 LOCATION='R563',
 CDS_LIB='pure_quanta',
 CDS_PART_NAME='Q_RES_0402LF-1K,1%,1/16W,EMPTY,CS21002FB06',
 PART_NUMBER='CS21002FB06',
 VALUE='1K',
 PRIM_FILE='./archive_libs/logical/q_res/chips/chips.prt';

PART_NAME
 R564 'Q_RES_0402LF-0,5%,1/16W,CHIP,CS00002JB13':;

SECTION_NUMBER 1
 '@T6G_MB_LIB.T6G(SCH_1):PAGE136_I108@PURE_QUANTA.Q_RES(CHIPS)':
 C_PATH='@t6g_mb_lib.t6g(sch_1):page136_i108@pure_quanta.q_res(chips)',
 P_PATH='@t6g_mb_lib.t6g(sch_1):page159_i108@pure_quanta.q_res(chips)',
 PATH='I108',
 DRAWING='@T6G_MB_LIB.T6G(SCH_1):PAGE136',
 WATTAGE='1/16W',
 TOLERANCE='5%',
 MATERIAL='CHIP',
 PHYS_PAGE='159',
 XY='(-6050,2850)',
 ROT='2',
 VER='1',
 PACK_TYPE='0402LF',
 LOCATION='R564',
 CDS_LIB='pure_quanta',
 CDS_PART_NAME='Q_RES_0402LF-0,5%,1/16W,CHIP,CS00002JB13',
 PART_NUMBER='CS00002JB13',
 VALUE='0',
 PRIM_FILE='./archive_libs/logical/q_res/chips/chips.prt';

PART_NAME
 R565 'Q_RES_0402LF-0,5%,1/16W,CHIP,CS00002JB13':;

SECTION_NUMBER 1
 '@T6G_MB_LIB.T6G(SCH_1):PAGE136_I107@PURE_QUANTA.Q_RES(CHIPS)':
 C_PATH='@t6g_mb_lib.t6g(sch_1):page136_i107@pure_quanta.q_res(chips)',
 P_PATH='@t6g_mb_lib.t6g(sch_1):page159_i107@pure_quanta.q_res(chips)',
 PATH='I107',
 DRAWING='@T6G_MB_LIB.T6G(SCH_1):PAGE136',
 WATTAGE='1/16W',
 TOLERANCE='5%',
 MATERIAL='CHIP',
 PHYS_PAGE='159',
 XY='(-6050,2800)',
 ROT='2',
 VER='1',
 PACK_TYPE='0402LF',
 LOCATION='R565',
 CDS_LIB='pure_quanta',
 CDS_PART_NAME='Q_RES_0402LF-0,5%,1/16W,CHIP,CS00002JB13',
 PART_NUMBER='CS00002JB13',
 VALUE='0',
 PRIM_FILE='./archive_libs/logical/q_res/chips/chips.prt';

PART_NAME
 R566 'Q_RES_0402LF-0,5%,1/16W,CHIP,CS00002JB13':;

SECTION_NUMBER 1
 '@T6G_MB_LIB.T6G(SCH_1):PAGE136_I111@PURE_QUANTA.Q_RES(CHIPS)':
 C_PATH='@t6g_mb_lib.t6g(sch_1):page136_i111@pure_quanta.q_res(chips)',
 P_PATH='@t6g_mb_lib.t6g(sch_1):page159_i111@pure_quanta.q_res(chips)',
 PATH='I111',
 DRAWING='@T6G_MB_LIB.T6G(SCH_1):PAGE136',
 WATTAGE='1/16W',
 TOLERANCE='5%',
 MATERIAL='CHIP',
 PHYS_PAGE='159',
 XY='(-5975,1400)',
 ROT='2',
 VER='1',
 PACK_TYPE='0402LF',
 LOCATION='R566',
 CDS_LIB='pure_quanta',
 CDS_PART_NAME='Q_RES_0402LF-0,5%,1/16W,CHIP,CS00002JB13',
 PART_NUMBER='CS00002JB13',
 VALUE='0',
 PRIM_FILE='./archive_libs/logical/q_res/chips/chips.prt';

PART_NAME
 R567 'Q_RES_0402LF-0,5%,1/16W,CHIP,CS00002JB13':;

SECTION_NUMBER 1
 '@T6G_MB_LIB.T6G(SCH_1):PAGE136_I112@PURE_QUANTA.Q_RES(CHIPS)':
 C_PATH='@t6g_mb_lib.t6g(sch_1):page136_i112@pure_quanta.q_res(chips)',
 P_PATH='@t6g_mb_lib.t6g(sch_1):page159_i112@pure_quanta.q_res(chips)',
 PATH='I112',
 DRAWING='@T6G_MB_LIB.T6G(SCH_1):PAGE136',
 WATTAGE='1/16W',
 TOLERANCE='5%',
 MATERIAL='CHIP',
 PHYS_PAGE='159',
 XY='(-5975,1350)',
 ROT='2',
 VER='1',
 PACK_TYPE='0402LF',
 LOCATION='R567',
 CDS_LIB='pure_quanta',
 CDS_PART_NAME='Q_RES_0402LF-0,5%,1/16W,CHIP,CS00002JB13',
 PART_NUMBER='CS00002JB13',
 VALUE='0',
 PRIM_FILE='./archive_libs/logical/q_res/chips/chips.prt';

PART_NAME
 R568 'Q_RES_0402LF-10K,1%,1/16W,CHIP,CS31002FB08':;

SECTION_NUMBER 1
 '@T6G_MB_LIB.T6G(SCH_1):PAGE273_I114@PURE_QUANTA.Q_RES(CHIPS)':
 C_PATH='@t6g_mb_lib.t6g(sch_1):page273_i114@pure_quanta.q_res(chips)',
 P_PATH='@t6g_mb_lib.t6g(sch_1):page188_i114@pure_quanta.q_res(chips)',
 PATH='I114',
 DRAWING='@T6G_MB_LIB.T6G(SCH_1):PAGE273',
 WATTAGE='1/16W',
 TOLERANCE='1%',
 MATERIAL='CHIP',
 PHYS_PAGE='188',
 XY='(-550,4925)',
 ROT='2',
 VER='2',
 PACK_TYPE='0402LF',
 LOCATION='R568',
 CDS_LIB='pure_quanta',
 CDS_PART_NAME='Q_RES_0402LF-10K,1%,1/16W,CHIP,CS31002FB08',
 PART_NUMBER='CS31002FB08',
 VALUE='10K',
 PRIM_FILE='./archive_libs/logical/q_res/chips/chips.prt';

PART_NAME
 R569 'Q_RES_0402LF-1K,1%,1/16W,CHIP,CS21002FB06':;

SECTION_NUMBER 1
 '@T6G_MB_LIB.T6G(SCH_1):PAGE273_I113@PURE_QUANTA.Q_RES(CHIPS)':
 C_PATH='@t6g_mb_lib.t6g(sch_1):page273_i113@pure_quanta.q_res(chips)',
 P_PATH='@t6g_mb_lib.t6g(sch_1):page188_i113@pure_quanta.q_res(chips)',
 PATH='I113',
 DRAWING='@T6G_MB_LIB.T6G(SCH_1):PAGE273',
 WATTAGE='1/16W',
 TOLERANCE='1%',
 MATERIAL='CHIP',
 PHYS_PAGE='188',
 XY='(-275,4575)',
 ROT='0',
 VER='2',
 PACK_TYPE='0402LF',
 LOCATION='R569',
 CDS_LIB='pure_quanta',
 CDS_PART_NAME='Q_RES_0402LF-1K,1%,1/16W,CHIP,CS21002FB06',
 PART_NUMBER='CS21002FB06',
 VALUE='1K',
 PRIM_FILE='./archive_libs/logical/q_res/chips/chips.prt';

PART_NAME
 R570 'Q_RES_0402LF-0,5%,1/16W,CHIP,CS00002JB13':;

SECTION_NUMBER 1
 '@T6G_MB_LIB.T6G(SCH_1):PAGE55_I236@PURE_QUANTA.Q_RES(CHIPS)':
 C_PATH='@t6g_mb_lib.t6g(sch_1):page55_i236@pure_quanta.q_res(chips)',
 P_PATH='@t6g_mb_lib.t6g(sch_1):page55_i236@pure_quanta.q_res(chips)',
 PATH='I236',
 DRAWING='@T6G_MB_LIB.T6G(SCH_1):PAGE55',
 WATTAGE='1/16W',
 TOLERANCE='5%',
 MATERIAL='CHIP',
 PHYS_PAGE='55',
 XY='(-6900,3475)',
 ROT='0',
 VER='1',
 PACK_TYPE='0402LF',
 LOCATION='R570',
 CDS_LIB='pure_quanta',
 CDS_PART_NAME='Q_RES_0402LF-0,5%,1/16W,CHIP,CS00002JB13',
 PART_NUMBER='CS00002JB13',
 VALUE='0',
 PRIM_FILE='./archive_libs/logical/q_res/chips/chips.prt';

PART_NAME
 R571 'Q_RES_0402LF-10M,1%,1/16W,CHIP,CS61002FB02':;

SECTION_NUMBER 1
 '@T6G_MB_LIB.T6G(SCH_1):PAGE55_I10@PURE_QUANTA.Q_RES(CHIPS)':
 C_PATH='@t6g_mb_lib.t6g(sch_1):page55_i10@pure_quanta.q_res(chips)',
 P_PATH='@t6g_mb_lib.t6g(sch_1):page55_i10@pure_quanta.q_res(chips)',
 PATH='I10',
 DRAWING='@T6G_MB_LIB.T6G(SCH_1):PAGE55',
 WATTAGE='1/16W',
 TOLERANCE='1%',
 MATERIAL='CHIP',
 PHYS_PAGE='55',
 XY='(-5525,1050)',
 ROT='0',
 VER='1',
 PACK_TYPE='0402LF',
 LOCATION='R571',
 CDS_LIB='pure_quanta',
 CDS_PART_NAME='Q_RES_0402LF-10M,1%,1/16W,CHIP,CS61002FB02',
 PART_NUMBER='CS61002FB02',
 VALUE='10M',
 PRIM_FILE='./archive_libs/logical/q_res/chips/chips.prt';

PART_NAME
 R572 'Q_RES_0402LF-20M,1%,1/16W,CHIP,CS62002FB01':;

SECTION_NUMBER 1
 '@T6G_MB_LIB.T6G(SCH_1):PAGE55_I389@PURE_QUANTA.Q_RES(CHIPS)':
 C_PATH='@t6g_mb_lib.t6g(sch_1):page55_i389@pure_quanta.q_res(chips)',
 P_PATH='@t6g_mb_lib.t6g(sch_1):page55_i389@pure_quanta.q_res(chips)',
 PATH='I389',
 DRAWING='@T6G_MB_LIB.T6G(SCH_1):PAGE55',
 SEC_TYPE='0402LF',
 WATTAGE='1/16W',
 TOLERANCE='1%',
 MATERIAL='CHIP',
 PHYS_PAGE='55',
 XY='(-3625,1450)',
 ROT='0',
 VER='1',
 PACK_TYPE='0402LF',
 LOCATION='R572',
 SEC='1',
 CDS_LIB='pure_quanta',
 CDS_PART_NAME='Q_RES_0402LF-20M,1%,1/16W,CHIP,CS62002FB01',
 PART_NUMBER='CS62002FB01',
 VALUE='20M',
 PRIM_FILE='./archive_libs/logical/q_res/chips/chips.prt';

PART_NAME
 R573 'Q_RES_0402LF-0,5%,1/16W,CHIP,CS00002JB13':;

SECTION_NUMBER 1
 '@T6G_MB_LIB.T6G(SCH_1):PAGE55_I26@PURE_QUANTA.Q_RES(CHIPS)':
 C_PATH='@t6g_mb_lib.t6g(sch_1):page55_i26@pure_quanta.q_res(chips)',
 P_PATH='@t6g_mb_lib.t6g(sch_1):page55_i26@pure_quanta.q_res(chips)',
 PATH='I26',
 DRAWING='@T6G_MB_LIB.T6G(SCH_1):PAGE55',
 WATTAGE='1/16W',
 TOLERANCE='5%',
 MATERIAL='CHIP',
 PHYS_PAGE='55',
 XY='(-2250,2425)',
 ROT='0',
 VER='1',
 PACK_TYPE='0402LF',
 LOCATION='R573',
 CDS_LIB='pure_quanta',
 CDS_PART_NAME='Q_RES_0402LF-0,5%,1/16W,CHIP,CS00002JB13',
 PART_NUMBER='CS00002JB13',
 VALUE='0',
 PRIM_FILE='./archive_libs/logical/q_res/chips/chips.prt';

PART_NAME
 R574 'Q_RES_0402LF-0,5%,1/16W,EMPTY,CS00002JB13':;

SECTION_NUMBER 1
 '@T6G_MB_LIB.T6G(SCH_1):PAGE55_I24@PURE_QUANTA.Q_RES(CHIPS)':
 C_PATH='@t6g_mb_lib.t6g(sch_1):page55_i24@pure_quanta.q_res(chips)',
 P_PATH='@t6g_mb_lib.t6g(sch_1):page55_i24@pure_quanta.q_res(chips)',
 PATH='I24',
 DRAWING='@T6G_MB_LIB.T6G(SCH_1):PAGE55',
 WATTAGE='1/16W',
 TOLERANCE='5%',
 MATERIAL='EMPTY',
 PHYS_PAGE='55',
 XY='(-2250,2175)',
 ROT='0',
 VER='1',
 PACK_TYPE='0402LF',
 LOCATION='R574',
 CDS_LIB='pure_quanta',
 CDS_PART_NAME='Q_RES_0402LF-0,5%,1/16W,EMPTY,CS00002JB13',
 PART_NUMBER='CS00002JB13',
 VALUE='0',
 PRIM_FILE='./archive_libs/logical/q_res/chips/chips.prt';

PART_NAME
 R575 'Q_RES_0402LF-0,5%,1/16W,EMPTY,CS00002JB13':;

SECTION_NUMBER 1
 '@T6G_MB_LIB.T6G(SCH_1):PAGE55_I296@PURE_QUANTA.Q_RES(CHIPS)':
 C_PATH='@t6g_mb_lib.t6g(sch_1):page55_i296@pure_quanta.q_res(chips)',
 P_PATH='@t6g_mb_lib.t6g(sch_1):page55_i296@pure_quanta.q_res(chips)',
 PATH='I296',
 DRAWING='@T6G_MB_LIB.T6G(SCH_1):PAGE55',
 WATTAGE='1/16W',
 TOLERANCE='5%',
 MATERIAL='EMPTY',
 PHYS_PAGE='55',
 XY='(-2250,2125)',
 ROT='0',
 VER='1',
 PACK_TYPE='0402LF',
 LOCATION='R575',
 CDS_LIB='pure_quanta',
 CDS_PART_NAME='Q_RES_0402LF-0,5%,1/16W,EMPTY,CS00002JB13',
 PART_NUMBER='CS00002JB13',
 VALUE='0',
 PRIM_FILE='./archive_libs/logical/q_res/chips/chips.prt';

PART_NAME
 R576 'Q_RES_0402LF-0,5%,1/16W,CHIP,CS00002JB13':;

SECTION_NUMBER 1
 '@T6G_MB_LIB.T6G(SCH_1):PAGE338_I116@PURE_QUANTA.Q_RES(CHIPS)':
 C_PATH='@t6g_mb_lib.t6g(sch_1):page338_i116@pure_quanta.q_res(chips)',
 P_PATH='@t6g_mb_lib.t6g(sch_1):page134_i116@pure_quanta.q_res(chips)',
 PATH='I116',
 DRAWING='@T6G_MB_LIB.T6G(SCH_1):PAGE338',
 WATTAGE='1/16W',
 TOLERANCE='5%',
 MATERIAL='CHIP',
 PHYS_PAGE='134',
 XY='(6850,8675)',
 ROT='0',
 VER='1',
 PACK_TYPE='0402LF',
 LOCATION='R576',
 CDS_LIB='pure_quanta',
 CDS_PART_NAME='Q_RES_0402LF-0,5%,1/16W,CHIP,CS00002JB13',
 PART_NUMBER='CS00002JB13',
 VALUE='0',
 PRIM_FILE='./archive_libs/logical/q_res/chips/chips.prt';

PART_NAME
 R577 'Q_RES_0402LF-10K,1%,1/16W,CHIP,CS31002FB08':;

SECTION_NUMBER 1
 '@T6G_MB_LIB.T6G(SCH_1):PAGE338_I118@PURE_QUANTA.Q_RES(CHIPS)':
 C_PATH='@t6g_mb_lib.t6g(sch_1):page338_i118@pure_quanta.q_res(chips)',
 P_PATH='@t6g_mb_lib.t6g(sch_1):page134_i118@pure_quanta.q_res(chips)',
 PATH='I118',
 DRAWING='@T6G_MB_LIB.T6G(SCH_1):PAGE338',
 WATTAGE='1/16W',
 TOLERANCE='1%',
 MATERIAL='CHIP',
 PHYS_PAGE='134',
 XY='(8200,9325)',
 ROT='2',
 VER='2',
 PACK_TYPE='0402LF',
 LOCATION='R577',
 CDS_LIB='pure_quanta',
 CDS_PART_NAME='Q_RES_0402LF-10K,1%,1/16W,CHIP,CS31002FB08',
 PART_NUMBER='CS31002FB08',
 VALUE='10K',
 PRIM_FILE='./archive_libs/logical/q_res/chips/chips.prt';

PART_NAME
 R578 'Q_RES_0402LF-4.75K,1%,1/16W,EMPTY,CS24752FB03':;

SECTION_NUMBER 1
 '@T6G_MB_LIB.T6G(SCH_1):PAGE379_I65@PURE_QUANTA.Q_RES(CHIPS)':
 C_PATH='@t6g_mb_lib.t6g(sch_1):page379_i65@pure_quanta.q_res(chips)',
 P_PATH='@t6g_mb_lib.t6g(sch_1):page183_i65@pure_quanta.q_res(chips)',
 PATH='I65',
 DRAWING='@T6G_MB_LIB.T6G(SCH_1):PAGE379',
 WATTAGE='1/16W',
 TOLERANCE='1%',
 MATERIAL='EMPTY',
 PHYS_PAGE='183',
 XY='(-5925,1575)',
 ROT='0',
 VER='2',
 PACK_TYPE='0402LF',
 LOCATION='R578',
 CDS_LIB='pure_quanta',
 CDS_PART_NAME='Q_RES_0402LF-4.75K,1%,1/16W,EMPTY,CS24752FB03',
 PART_NUMBER='CS24752FB03',
 VALUE='4.75K',
 PRIM_FILE='./archive_libs/logical/q_res/chips/chips.prt';

PART_NAME
 R579 'Q_RES_0402LF-4.75K,1%,1/16W,CHIP,CS24752FB03':;

SECTION_NUMBER 1
 '@T6G_MB_LIB.T6G(SCH_1):PAGE379_I64@PURE_QUANTA.Q_RES(CHIPS)':
 C_PATH='@t6g_mb_lib.t6g(sch_1):page379_i64@pure_quanta.q_res(chips)',
 P_PATH='@t6g_mb_lib.t6g(sch_1):page183_i64@pure_quanta.q_res(chips)',
 PATH='I64',
 DRAWING='@T6G_MB_LIB.T6G(SCH_1):PAGE379',
 WATTAGE='1/16W',
 TOLERANCE='1%',
 MATERIAL='CHIP',
 PHYS_PAGE='183',
 XY='(-5925,1150)',
 ROT='0',
 VER='2',
 PACK_TYPE='0402LF',
 LOCATION='R579',
 CDS_LIB='pure_quanta',
 CDS_PART_NAME='Q_RES_0402LF-4.75K,1%,1/16W,CHIP,CS24752FB03',
 PART_NUMBER='CS24752FB03',
 VALUE='4.75K',
 PRIM_FILE='./archive_libs/logical/q_res/chips/chips.prt';

PART_NAME
 R580 'Q_RES_0402LF-10K,1%,1/16W,CHIP,CS31002FB08':;

SECTION_NUMBER 1
 '@T6G_MB_LIB.T6G(SCH_1):PAGE379_I17@PURE_QUANTA.Q_RES(CHIPS)':
 C_PATH='@t6g_mb_lib.t6g(sch_1):page379_i17@pure_quanta.q_res(chips)',
 P_PATH='@t6g_mb_lib.t6g(sch_1):page183_i17@pure_quanta.q_res(chips)',
 PATH='I17',
 DRAWING='@T6G_MB_LIB.T6G(SCH_1):PAGE379',
 WATTAGE='1/16W',
 TOLERANCE='1%',
 MATERIAL='CHIP',
 PHYS_PAGE='183',
 XY='(-3925,1575)',
 ROT='0',
 VER='2',
 PACK_TYPE='0402LF',
 LOCATION='R580',
 CDS_LIB='pure_quanta',
 CDS_PART_NAME='Q_RES_0402LF-10K,1%,1/16W,CHIP,CS31002FB08',
 PART_NUMBER='CS31002FB08',
 VALUE='10K',
 PRIM_FILE='./archive_libs/logical/q_res/chips/chips.prt';

PART_NAME
 R581 'Q_RES_0402LF-4.7K,5%,1/16W,EMPTY,CS24702JB10':;

SECTION_NUMBER 1
 '@T6G_MB_LIB.T6G(SCH_1):PAGE28_I34@PURE_QUANTA.Q_RES(CHIPS)':
 C_PATH='@t6g_mb_lib.t6g(sch_1):page28_i34@pure_quanta.q_res(chips)',
 P_PATH='@t6g_mb_lib.t6g(sch_1):page28_i34@pure_quanta.q_res(chips)',
 PATH='I34',
 DRAWING='@T6G_MB_LIB.T6G(SCH_1):PAGE28',
 WATTAGE='1/16W',
 TOLERANCE='5%',
 MATERIAL='EMPTY',
 PHYS_PAGE='28',
 XY='(-7900,7775)',
 ROT='1',
 VER='1',
 PACK_TYPE='0402LF',
 LOCATION='R581',
 CDS_LIB='pure_quanta',
 CDS_PART_NAME='Q_RES_0402LF-4.7K,5%,1/16W,EMPTY,CS24702JB10',
 PART_NUMBER='CS24702JB10',
 VALUE='4.7K',
 PRIM_FILE='./archive_libs/logical/q_res/chips/chips.prt';

PART_NAME
 R582 'Q_RES_0402LF-4.7K,5%,1/16W,EMPTY,CS24702JB10':;

SECTION_NUMBER 1
 '@T6G_MB_LIB.T6G(SCH_1):PAGE28_I33@PURE_QUANTA.Q_RES(CHIPS)':
 C_PATH='@t6g_mb_lib.t6g(sch_1):page28_i33@pure_quanta.q_res(chips)',
 P_PATH='@t6g_mb_lib.t6g(sch_1):page28_i33@pure_quanta.q_res(chips)',
 PATH='I33',
 DRAWING='@T6G_MB_LIB.T6G(SCH_1):PAGE28',
 WATTAGE='1/16W',
 TOLERANCE='5%',
 MATERIAL='EMPTY',
 PHYS_PAGE='28',
 XY='(-7900,7225)',
 ROT='1',
 VER='1',
 PACK_TYPE='0402LF',
 LOCATION='R582',
 CDS_LIB='pure_quanta',
 CDS_PART_NAME='Q_RES_0402LF-4.7K,5%,1/16W,EMPTY,CS24702JB10',
 PART_NUMBER='CS24702JB10',
 VALUE='4.7K',
 PRIM_FILE='./archive_libs/logical/q_res/chips/chips.prt';

PART_NAME
 R583 'Q_RES_0402LF-4.7K,5%,1/16W,EMPTY,CS24702JB10':;

SECTION_NUMBER 1
 '@T6G_MB_LIB.T6G(SCH_1):PAGE55_I342@PURE_QUANTA.Q_RES(CHIPS)':
 C_PATH='@t6g_mb_lib.t6g(sch_1):page55_i342@pure_quanta.q_res(chips)',
 P_PATH='@t6g_mb_lib.t6g(sch_1):page55_i342@pure_quanta.q_res(chips)',
 PATH='I342',
 DRAWING='@T6G_MB_LIB.T6G(SCH_1):PAGE55',
 WATTAGE='1/16W',
 TOLERANCE='5%',
 MATERIAL='EMPTY',
 PHYS_PAGE='55',
 XY='(-8475,1150)',
 ROT='1',
 VER='1',
 PACK_TYPE='0402LF',
 LOCATION='R583',
 CDS_LIB='pure_quanta',
 CDS_PART_NAME='Q_RES_0402LF-4.7K,5%,1/16W,EMPTY,CS24702JB10',
 PART_NUMBER='CS24702JB10',
 VALUE='4.7K',
 PRIM_FILE='./archive_libs/logical/q_res/chips/chips.prt';

PART_NAME
 R584 'Q_RES_0402LF-4.7K,5%,1/16W,EMPTY,CS24702JB10':;

SECTION_NUMBER 1
 '@T6G_MB_LIB.T6G(SCH_1):PAGE55_I341@PURE_QUANTA.Q_RES(CHIPS)':
 C_PATH='@t6g_mb_lib.t6g(sch_1):page55_i341@pure_quanta.q_res(chips)',
 P_PATH='@t6g_mb_lib.t6g(sch_1):page55_i341@pure_quanta.q_res(chips)',
 PATH='I341',
 DRAWING='@T6G_MB_LIB.T6G(SCH_1):PAGE55',
 WATTAGE='1/16W',
 TOLERANCE='5%',
 MATERIAL='EMPTY',
 PHYS_PAGE='55',
 XY='(-8475,425)',
 ROT='1',
 VER='1',
 PACK_TYPE='0402LF',
 LOCATION='R584',
 CDS_LIB='pure_quanta',
 CDS_PART_NAME='Q_RES_0402LF-4.7K,5%,1/16W,EMPTY,CS24702JB10',
 PART_NUMBER='CS24702JB10',
 VALUE='4.7K',
 PRIM_FILE='./archive_libs/logical/q_res/chips/chips.prt';

PART_NAME
 R585 'Q_RES_0402LF-10K,1%,1/16W,CHIP,CS31002FB08':;

SECTION_NUMBER 1
 '@T6G_MB_LIB.T6G(SCH_1):PAGE379_I15@PURE_QUANTA.Q_RES(CHIPS)':
 C_PATH='@t6g_mb_lib.t6g(sch_1):page379_i15@pure_quanta.q_res(chips)',
 P_PATH='@t6g_mb_lib.t6g(sch_1):page183_i15@pure_quanta.q_res(chips)',
 PATH='I15',
 DRAWING='@T6G_MB_LIB.T6G(SCH_1):PAGE379',
 WATTAGE='1/16W',
 TOLERANCE='1%',
 MATERIAL='CHIP',
 PHYS_PAGE='183',
 XY='(-3925,1100)',
 ROT='0',
 VER='2',
 PACK_TYPE='0402LF',
 LOCATION='R585',
 CDS_LIB='pure_quanta',
 CDS_PART_NAME='Q_RES_0402LF-10K,1%,1/16W,CHIP,CS31002FB08',
 PART_NUMBER='CS31002FB08',
 VALUE='10K',
 PRIM_FILE='./archive_libs/logical/q_res/chips/chips.prt';

PART_NAME
 R586 'Q_RES_0603LF-1,1%,1/10W,CHIP,CS-1003F900':;

SECTION_NUMBER 1
 '@T6G_MB_LIB.T6G(SCH_1):PAGE379_I21@PURE_QUANTA.Q_RES(CHIPS)':
 C_PATH='@t6g_mb_lib.t6g(sch_1):page379_i21@pure_quanta.q_res(chips)',
 P_PATH='@t6g_mb_lib.t6g(sch_1):page183_i21@pure_quanta.q_res(chips)',
 PATH='I21',
 DRAWING='@T6G_MB_LIB.T6G(SCH_1):PAGE379',
 WATTAGE='1/10W',
 TOLERANCE='1%',
 MATERIAL='CHIP',
 PHYS_PAGE='183',
 XY='(-7600,5825)',
 ROT='0',
 VER='1',
 PACK_TYPE='0603LF',
 LOCATION='R586',
 CDS_LIB='pure_quanta',
 CDS_PART_NAME='Q_RES_0603LF-1,1%,1/10W,CHIP,CS-1003F900',
 PART_NUMBER='CS-1003F900',
 VALUE='1',
 PRIM_FILE='./archive_libs/logical/q_res/chips/chips.prt';

PART_NAME
 R587 'Q_RES_0402LF-1K,1%,1/16W,CHIP,CS21002FB06':;

SECTION_NUMBER 1
 '@T6G_MB_LIB.T6G(SCH_1):PAGE252_I6@PURE_QUANTA.Q_RES(CHIPS)':
 C_PATH='@t6g_mb_lib.t6g(sch_1):page252_i6@pure_quanta.q_res(chips)',
 P_PATH='@t6g_mb_lib.t6g(sch_1):page250_i6@pure_quanta.q_res(chips)',
 PATH='I6',
 DRAWING='@T6G_MB_LIB.T6G(SCH_1):PAGE252',
 WATTAGE='1/16W',
 TOLERANCE='1%',
 MATERIAL='CHIP',
 PHYS_PAGE='250',
 XY='(-5350,2325)',
 ROT='0',
 VER='2',
 PACK_TYPE='0402LF',
 LOCATION='R587',
 CDS_LIB='pure_quanta',
 CDS_PART_NAME='Q_RES_0402LF-1K,1%,1/16W,CHIP,CS21002FB06',
 PART_NUMBER='CS21002FB06',
 VALUE='1K',
 PRIM_FILE='./archive_libs/logical/q_res/chips/chips.prt';

PART_NAME
 R588 'Q_RES_0402LF-33,5%,1/16W,CHIP,CS03302JB10':;

SECTION_NUMBER 1
 '@T6G_MB_LIB.T6G(SCH_1):PAGE80_I164@PURE_QUANTA.Q_RES(CHIPS)':
 C_PATH='@t6g_mb_lib.t6g(sch_1):page80_i164@pure_quanta.q_res(chips)',
 P_PATH='@t6g_mb_lib.t6g(sch_1):page81_i164@pure_quanta.q_res(chips)',
 PATH='I164',
 DRAWING='@T6G_MB_LIB.T6G(SCH_1):PAGE80',
 BOM_COST='MEM',
 WATTAGE='1/16W',
 TOLERANCE='5%',
 MATERIAL='CHIP',
 PHYS_PAGE='81',
 XY='(-3225,4825)',
 ROT='0',
 VER='1',
 PACK_TYPE='0402LF',
 LOCATION='R588',
 CDS_LIB='pure_quanta',
 CDS_PART_NAME='Q_RES_0402LF-33,5%,1/16W,CHIP,CS03302JB10',
 PART_NUMBER='CS03302JB10',
 VALUE='33',
 PRIM_FILE='./archive_libs/logical/q_res/chips/chips.prt';

PART_NAME
 R589 'Q_RES_0402LF-0,5%,1/16W,CHIP,CS00002JB13':;

SECTION_NUMBER 1
 '@T6G_MB_LIB.T6G(SCH_1):PAGE29_I377@PURE_QUANTA.Q_RES(CHIPS)':
 C_PATH='@t6g_mb_lib.t6g(sch_1):page29_i377@pure_quanta.q_res(chips)',
 P_PATH='@t6g_mb_lib.t6g(sch_1):page29_i377@pure_quanta.q_res(chips)',
 PATH='I377',
 DRAWING='@T6G_MB_LIB.T6G(SCH_1):PAGE29',
 WATTAGE='1/16W',
 TOLERANCE='5%',
 MATERIAL='CHIP',
 PHYS_PAGE='29',
 XY='(-2525,2175)',
 ROT='0',
 VER='1',
 PACK_TYPE='0402LF',
 LOCATION='R589',
 CDS_LIB='pure_quanta',
 CDS_PART_NAME='Q_RES_0402LF-0,5%,1/16W,CHIP,CS00002JB13',
 PART_NUMBER='CS00002JB13',
 VALUE='0',
 PRIM_FILE='./archive_libs/logical/q_res/chips/chips.prt';

PART_NAME
 R590 'Q_RES_0402LF-4.7K,5%,1/16W,CHIP,CS24702JB10':;

SECTION_NUMBER 1
 '@T6G_MB_LIB.T6G(SCH_1):PAGE34_I5@PURE_QUANTA.Q_RES(CHIPS)':
 C_PATH='@t6g_mb_lib.t6g(sch_1):page34_i5@pure_quanta.q_res(chips)',
 P_PATH='@t6g_mb_lib.t6g(sch_1):page34_i5@pure_quanta.q_res(chips)',
 PATH='I5',
 DRAWING='@T6G_MB_LIB.T6G(SCH_1):PAGE34',
 WATTAGE='1/16W',
 TOLERANCE='5%',
 MATERIAL='CHIP',
 PHYS_PAGE='34',
 XY='(-1675,5925)',
 ROT='0',
 VER='1',
 PACK_TYPE='0402LF',
 LOCATION='R590',
 CDS_LIB='pure_quanta',
 CDS_PART_NAME='Q_RES_0402LF-4.7K,5%,1/16W,CHIP,CS24702JB10',
 PART_NUMBER='CS24702JB10',
 VALUE='4.7K',
 PRIM_FILE='./archive_libs/logical/q_res/chips/chips.prt';

PART_NAME
 R591 'Q_RES_0402LF-0,5%,1/16W,CHIP,CS00002JB13':
 ROOM='NIC_P12V_MPS_MAM_BOM2';

SECTION_NUMBER 1
 '@T6G_MB_LIB.T6G(SCH_1):PAGE339_I130@PURE_QUANTA.Q_RES(CHIPS)':
 C_PATH='@t6g_mb_lib.t6g(sch_1):page339_i130@pure_quanta.q_res(chips)',
 P_PATH='@t6g_mb_lib.t6g(sch_1):page135_i130@pure_quanta.q_res(chips)',
 PATH='I130',
 DRAWING='@T6G_MB_LIB.T6G(SCH_1):PAGE339',
 WATTAGE='1/16W',
 TOLERANCE='5%',
 MATERIAL='CHIP',
 PHYS_PAGE='135',
 XY='(-7825,9975)',
 ROT='0',
 VER='1',
 PACK_TYPE='0402LF',
 LOCATION='R591',
 CDS_LIB='pure_quanta',
 CDS_PART_NAME='Q_RES_0402LF-0,5%,1/16W,CHIP,CS00002JB13',
 ROOM='NIC_P12V_MPS_MAM_BOM2',
 PART_NUMBER='CS00002JB13',
 VALUE='0',
 PRIM_FILE='./archive_libs/logical/q_res/chips/chips.prt';

PART_NAME
 R592 'Q_RES_0402LF-10K,1%,1/16W,CHIP,CS31002FB08':;

SECTION_NUMBER 1
 '@T6G_MB_LIB.T6G(SCH_1):PAGE379_I49@PURE_QUANTA.Q_RES(CHIPS)':
 C_PATH='@t6g_mb_lib.t6g(sch_1):page379_i49@pure_quanta.q_res(chips)',
 P_PATH='@t6g_mb_lib.t6g(sch_1):page183_i49@pure_quanta.q_res(chips)',
 PATH='I49',
 DRAWING='@T6G_MB_LIB.T6G(SCH_1):PAGE379',
 WATTAGE='1/16W',
 TOLERANCE='1%',
 MATERIAL='CHIP',
 PHYS_PAGE='183',
 XY='(-2550,2775)',
 ROT='0',
 VER='2',
 PACK_TYPE='0402LF',
 LOCATION='R592',
 CDS_LIB='pure_quanta',
 CDS_PART_NAME='Q_RES_0402LF-10K,1%,1/16W,CHIP,CS31002FB08',
 PART_NUMBER='CS31002FB08',
 VALUE='10K',
 PRIM_FILE='./archive_libs/logical/q_res/chips/chips.prt';

PART_NAME
 R593 'Q_RES_0402LF-10K,1%,1/16W,CHIP,CS31002FB08':;

SECTION_NUMBER 1
 '@T6G_MB_LIB.T6G(SCH_1):PAGE379_I50@PURE_QUANTA.Q_RES(CHIPS)':
 C_PATH='@t6g_mb_lib.t6g(sch_1):page379_i50@pure_quanta.q_res(chips)',
 P_PATH='@t6g_mb_lib.t6g(sch_1):page183_i50@pure_quanta.q_res(chips)',
 PATH='I50',
 DRAWING='@T6G_MB_LIB.T6G(SCH_1):PAGE379',
 WATTAGE='1/16W',
 TOLERANCE='1%',
 MATERIAL='CHIP',
 PHYS_PAGE='183',
 XY='(-2350,2775)',
 ROT='0',
 VER='2',
 PACK_TYPE='0402LF',
 LOCATION='R593',
 CDS_LIB='pure_quanta',
 CDS_PART_NAME='Q_RES_0402LF-10K,1%,1/16W,CHIP,CS31002FB08',
 PART_NUMBER='CS31002FB08',
 VALUE='10K',
 PRIM_FILE='./archive_libs/logical/q_res/chips/chips.prt';

PART_NAME
 R594 'Q_RES_0402LF-10K,1%,1/16W,CHIP,CS31002FB08':;

SECTION_NUMBER 1
 '@T6G_MB_LIB.T6G(SCH_1):PAGE379_I51@PURE_QUANTA.Q_RES(CHIPS)':
 C_PATH='@t6g_mb_lib.t6g(sch_1):page379_i51@pure_quanta.q_res(chips)',
 P_PATH='@t6g_mb_lib.t6g(sch_1):page183_i51@pure_quanta.q_res(chips)',
 PATH='I51',
 DRAWING='@T6G_MB_LIB.T6G(SCH_1):PAGE379',
 WATTAGE='1/16W',
 TOLERANCE='1%',
 MATERIAL='CHIP',
 PHYS_PAGE='183',
 XY='(-2125,2775)',
 ROT='0',
 VER='2',
 PACK_TYPE='0402LF',
 LOCATION='R594',
 CDS_LIB='pure_quanta',
 CDS_PART_NAME='Q_RES_0402LF-10K,1%,1/16W,CHIP,CS31002FB08',
 PART_NUMBER='CS31002FB08',
 VALUE='10K',
 PRIM_FILE='./archive_libs/logical/q_res/chips/chips.prt';

PART_NAME
 R595 'Q_RES_0201LF-0,5%,1/20W,CHIP,CS00001JE10':;

SECTION_NUMBER 1
 '@T6G_MB_LIB.T6G(SCH_1):PAGE385_I39@PURE_QUANTA.Q_RES(CHIPS)':
 C_PATH='@t6g_mb_lib.t6g(sch_1):page385_i39@pure_quanta.q_res(chips)',
 P_PATH='@t6g_mb_lib.t6g(sch_1):page276_i39@pure_quanta.q_res(chips)',
 PATH='I39',
 DRAWING='@T6G_MB_LIB.T6G(SCH_1):PAGE385',
 SEC_TYPE='0201LF',
 WATTAGE='1/20W',
 TOLERANCE='5%',
 MATERIAL='CHIP',
 PHYS_PAGE='276',
 XY='(-6600,1150)',
 ROT='0',
 VER='1',
 PACK_TYPE='0201LF',
 LOCATION='R595',
 SEC='1',
 CDS_LIB='pure_quanta',
 CDS_PART_NAME='Q_RES_0201LF-0,5%,1/20W,CHIP,CS00001JE10',
 PART_NUMBER='CS00001JE10',
 VALUE='0',
 PRIM_FILE='./archive_libs/logical/q_res/chips/chips.prt';

PART_NAME
 R596 'Q_RES_0201LF-0,5%,1/20W,CHIP,CS00001JE10':;

SECTION_NUMBER 1
 '@T6G_MB_LIB.T6G(SCH_1):PAGE385_I40@PURE_QUANTA.Q_RES(CHIPS)':
 C_PATH='@t6g_mb_lib.t6g(sch_1):page385_i40@pure_quanta.q_res(chips)',
 P_PATH='@t6g_mb_lib.t6g(sch_1):page276_i40@pure_quanta.q_res(chips)',
 PATH='I40',
 DRAWING='@T6G_MB_LIB.T6G(SCH_1):PAGE385',
 SEC_TYPE='0201LF',
 WATTAGE='1/20W',
 TOLERANCE='5%',
 MATERIAL='CHIP',
 PHYS_PAGE='276',
 XY='(-6600,1000)',
 ROT='0',
 VER='1',
 PACK_TYPE='0201LF',
 LOCATION='R596',
 SEC='1',
 CDS_LIB='pure_quanta',
 CDS_PART_NAME='Q_RES_0201LF-0,5%,1/20W,CHIP,CS00001JE10',
 PART_NUMBER='CS00001JE10',
 VALUE='0',
 PRIM_FILE='./archive_libs/logical/q_res/chips/chips.prt';

PART_NAME
 R597 'Q_RES_0201LF-0,5%,1/20W,CHIP,CS00001JE10':;

SECTION_NUMBER 1
 '@T6G_MB_LIB.T6G(SCH_1):PAGE392_I33@PURE_QUANTA.Q_RES(CHIPS)':
 C_PATH='@t6g_mb_lib.t6g(sch_1):page392_i33@pure_quanta.q_res(chips)',
 P_PATH='@t6g_mb_lib.t6g(sch_1):page331_i33@pure_quanta.q_res(chips)',
 PATH='I33',
 DRAWING='@T6G_MB_LIB.T6G(SCH_1):PAGE392',
 SEC_TYPE='0201LF',
 WATTAGE='1/20W',
 TOLERANCE='5%',
 MATERIAL='CHIP',
 PHYS_PAGE='331',
 XY='(-6450,1050)',
 ROT='0',
 VER='1',
 PACK_TYPE='0201LF',
 LOCATION='R597',
 SEC='1',
 CDS_LIB='pure_quanta',
 CDS_PART_NAME='Q_RES_0201LF-0,5%,1/20W,CHIP,CS00001JE10',
 PART_NUMBER='CS00001JE10',
 VALUE='0',
 PRIM_FILE='./archive_libs/logical/q_res/chips/chips.prt';

PART_NAME
 R598 'Q_RES_0201LF-0,5%,1/20W,CHIP,CS00001JE10':;

SECTION_NUMBER 1
 '@T6G_MB_LIB.T6G(SCH_1):PAGE392_I34@PURE_QUANTA.Q_RES(CHIPS)':
 C_PATH='@t6g_mb_lib.t6g(sch_1):page392_i34@pure_quanta.q_res(chips)',
 P_PATH='@t6g_mb_lib.t6g(sch_1):page331_i34@pure_quanta.q_res(chips)',
 PATH='I34',
 DRAWING='@T6G_MB_LIB.T6G(SCH_1):PAGE392',
 SEC_TYPE='0201LF',
 WATTAGE='1/20W',
 TOLERANCE='5%',
 MATERIAL='CHIP',
 PHYS_PAGE='331',
 XY='(-6450,900)',
 ROT='0',
 VER='1',
 PACK_TYPE='0201LF',
 LOCATION='R598',
 SEC='1',
 CDS_LIB='pure_quanta',
 CDS_PART_NAME='Q_RES_0201LF-0,5%,1/20W,CHIP,CS00001JE10',
 PART_NUMBER='CS00001JE10',
 VALUE='0',
 PRIM_FILE='./archive_libs/logical/q_res/chips/chips.prt';

PART_NAME
 R599 'Q_RES_0201LF-0,5%,1/20W,CHIP,CS00001JE10':;

SECTION_NUMBER 1
 '@T6G_MB_LIB.T6G(SCH_1):PAGE401_I9@PURE_QUANTA.Q_RES(CHIPS)':
 C_PATH='@t6g_mb_lib.t6g(sch_1):page401_i9@pure_quanta.q_res(chips)',
 P_PATH='@t6g_mb_lib.t6g(sch_1):page320_i9@pure_quanta.q_res(chips)',
 PATH='I9',
 DRAWING='@T6G_MB_LIB.T6G(SCH_1):PAGE401',
 SEC_TYPE='0201LF',
 WATTAGE='1/20W',
 TOLERANCE='5%',
 MATERIAL='CHIP',
 PHYS_PAGE='320',
 XY='(-6600,1300)',
 ROT='0',
 VER='1',
 PACK_TYPE='0201LF',
 LOCATION='R599',
 SEC='1',
 CDS_LIB='pure_quanta',
 CDS_PART_NAME='Q_RES_0201LF-0,5%,1/20W,CHIP,CS00001JE10',
 PART_NUMBER='CS00001JE10',
 VALUE='0',
 PRIM_FILE='./archive_libs/logical/q_res/chips/chips.prt';

PART_NAME
 R600 'Q_RES_0402LF-0,5%,1/16W,CHIP,CS00002JB13':;

SECTION_NUMBER 1
 '@T6G_MB_LIB.T6G(SCH_1):PAGE76_I180@PURE_QUANTA.Q_RES(CHIPS)':
 C_PATH='@t6g_mb_lib.t6g(sch_1):page76_i180@pure_quanta.q_res(chips)',
 P_PATH='@t6g_mb_lib.t6g(sch_1):page77_i180@pure_quanta.q_res(chips)',
 PATH='I180',
 DRAWING='@T6G_MB_LIB.T6G(SCH_1):PAGE76',
 WATTAGE='1/16W',
 TOLERANCE='5%',
 MATERIAL='CHIP',
 PHYS_PAGE='77',
 XY='(-3950,4225)',
 ROT='0',
 VER='1',
 PACK_TYPE='0402LF',
 LOCATION='R600',
 CDS_LIB='pure_quanta',
 CDS_PART_NAME='Q_RES_0402LF-0,5%,1/16W,CHIP,CS00002JB13',
 PART_NUMBER='CS00002JB13',
 VALUE='0',
 PRIM_FILE='./archive_libs/logical/q_res/chips/chips.prt';

PART_NAME
 R601 'Q_RES_0402LF-1K,1%,1/16W,CHIP,CS21002FB06':;

SECTION_NUMBER 1
 '@T6G_MB_LIB.T6G(SCH_1):PAGE76_I108@PURE_QUANTA.Q_RES(CHIPS)':
 C_PATH='@t6g_mb_lib.t6g(sch_1):page76_i108@pure_quanta.q_res(chips)',
 P_PATH='@t6g_mb_lib.t6g(sch_1):page77_i108@pure_quanta.q_res(chips)',
 PATH='I108',
 DRAWING='@T6G_MB_LIB.T6G(SCH_1):PAGE76',
 WATTAGE='1/16W',
 TOLERANCE='1%',
 MATERIAL='CHIP',
 PHYS_PAGE='77',
 XY='(-8375,5875)',
 ROT='0',
 VER='2',
 PACK_TYPE='0402LF',
 LOCATION='R601',
 CDS_LIB='pure_quanta',
 CDS_PART_NAME='Q_RES_0402LF-1K,1%,1/16W,CHIP,CS21002FB06',
 PART_NUMBER='CS21002FB06',
 VALUE='1K',
 PRIM_FILE='./archive_libs/logical/q_res/chips/chips.prt';

PART_NAME
 R602 'Q_RES_0402LF-33,5%,1/16W,CHIP,CS03302JB10':;

SECTION_NUMBER 1
 '@T6G_MB_LIB.T6G(SCH_1):PAGE76_I230@PURE_QUANTA.Q_RES(CHIPS)':
 C_PATH='@t6g_mb_lib.t6g(sch_1):page76_i230@pure_quanta.q_res(chips)',
 P_PATH='@t6g_mb_lib.t6g(sch_1):page77_i230@pure_quanta.q_res(chips)',
 PATH='I230',
 DRAWING='@T6G_MB_LIB.T6G(SCH_1):PAGE76',
 WATTAGE='1/16W',
 TOLERANCE='5%',
 MATERIAL='CHIP',
 PHYS_PAGE='77',
 XY='(-3950,4275)',
 ROT='0',
 VER='1',
 PACK_TYPE='0402LF',
 LOCATION='R602',
 CDS_LIB='pure_quanta',
 CDS_PART_NAME='Q_RES_0402LF-33,5%,1/16W,CHIP,CS03302JB10',
 PART_NUMBER='CS03302JB10',
 VALUE='33',
 PRIM_FILE='./archive_libs/logical/q_res/chips/chips.prt';

PART_NAME
 R603 'Q_RES_0402LF-0,5%,1/16W,CHIP,CS00002JB13':;

SECTION_NUMBER 1
 '@T6G_MB_LIB.T6G(SCH_1):PAGE76_I228@PURE_QUANTA.Q_RES(CHIPS)':
 C_PATH='@t6g_mb_lib.t6g(sch_1):page76_i228@pure_quanta.q_res(chips)',
 P_PATH='@t6g_mb_lib.t6g(sch_1):page77_i228@pure_quanta.q_res(chips)',
 PATH='I228',
 DRAWING='@T6G_MB_LIB.T6G(SCH_1):PAGE76',
 WATTAGE='1/16W',
 TOLERANCE='5%',
 MATERIAL='CHIP',
 PHYS_PAGE='77',
 XY='(-3950,4325)',
 ROT='0',
 VER='1',
 PACK_TYPE='0402LF',
 LOCATION='R603',
 CDS_LIB='pure_quanta',
 CDS_PART_NAME='Q_RES_0402LF-0,5%,1/16W,CHIP,CS00002JB13',
 PART_NUMBER='CS00002JB13',
 VALUE='0',
 PRIM_FILE='./archive_libs/logical/q_res/chips/chips.prt';

PART_NAME
 R604 'Q_RES_0402LF-33.2,1%,1/16W,CHIP,CS03322FB03':;

SECTION_NUMBER 1
 '@T6G_MB_LIB.T6G(SCH_1):PAGE76_I221@PURE_QUANTA.Q_RES(CHIPS)':
 C_PATH='@t6g_mb_lib.t6g(sch_1):page76_i221@pure_quanta.q_res(chips)',
 P_PATH='@t6g_mb_lib.t6g(sch_1):page77_i221@pure_quanta.q_res(chips)',
 PATH='I221',
 DRAWING='@T6G_MB_LIB.T6G(SCH_1):PAGE76',
 WATTAGE='1/16W',
 TOLERANCE='1%',
 MATERIAL='CHIP',
 PHYS_PAGE='77',
 XY='(-4075,2275)',
 ROT='0',
 VER='1',
 PACK_TYPE='0402LF',
 LOCATION='R604',
 CDS_LIB='pure_quanta',
 CDS_PART_NAME='Q_RES_0402LF-33.2,1%,1/16W,CHIP,CS03322FB03',
 PART_NUMBER='CS03322FB03',
 VALUE='33.2',
 PRIM_FILE='./archive_libs/logical/q_res/chips/chips.prt';

PART_NAME
 R605 'Q_RES_0402LF-49.9,1%,1/16W,CHIP,CS04992FB07':;

SECTION_NUMBER 1
 '@T6G_MB_LIB.T6G(SCH_1):PAGE76_I219@PURE_QUANTA.Q_RES(CHIPS)':
 C_PATH='@t6g_mb_lib.t6g(sch_1):page76_i219@pure_quanta.q_res(chips)',
 P_PATH='@t6g_mb_lib.t6g(sch_1):page77_i219@pure_quanta.q_res(chips)',
 PATH='I219',
 DRAWING='@T6G_MB_LIB.T6G(SCH_1):PAGE76',
 WATTAGE='1/16W',
 TOLERANCE='1%',
 MATERIAL='CHIP',
 PHYS_PAGE='77',
 XY='(-4075,2225)',
 ROT='0',
 VER='1',
 PACK_TYPE='0402LF',
 LOCATION='R605',
 CDS_LIB='pure_quanta',
 CDS_PART_NAME='Q_RES_0402LF-49.9,1%,1/16W,CHIP,CS04992FB07',
 PART_NUMBER='CS04992FB07',
 VALUE='49.9',
 PRIM_FILE='./archive_libs/logical/q_res/chips/chips.prt';

PART_NAME
 R606 'Q_RES_0402LF-0,5%,1/16W,CHIP,CS00002JB13':;

SECTION_NUMBER 1
 '@T6G_MB_LIB.T6G(SCH_1):PAGE76_I205@PURE_QUANTA.Q_RES(CHIPS)':
 C_PATH='@t6g_mb_lib.t6g(sch_1):page76_i205@pure_quanta.q_res(chips)',
 P_PATH='@t6g_mb_lib.t6g(sch_1):page77_i205@pure_quanta.q_res(chips)',
 PATH='I205',
 DRAWING='@T6G_MB_LIB.T6G(SCH_1):PAGE76',
 WATTAGE='1/16W',
 TOLERANCE='5%',
 MATERIAL='CHIP',
 PHYS_PAGE='77',
 XY='(-4075,2325)',
 ROT='0',
 VER='1',
 PACK_TYPE='0402LF',
 LOCATION='R606',
 CDS_LIB='pure_quanta',
 CDS_PART_NAME='Q_RES_0402LF-0,5%,1/16W,CHIP,CS00002JB13',
 PART_NUMBER='CS00002JB13',
 VALUE='0',
 PRIM_FILE='./archive_libs/logical/q_res/chips/chips.prt';

PART_NAME
 R607 'Q_RES_0402LF-0,5%,1/16W,CHIP,CS00002JB13':;

SECTION_NUMBER 1
 '@T6G_MB_LIB.T6G(SCH_1):PAGE76_I207@PURE_QUANTA.Q_RES(CHIPS)':
 C_PATH='@t6g_mb_lib.t6g(sch_1):page76_i207@pure_quanta.q_res(chips)',
 P_PATH='@t6g_mb_lib.t6g(sch_1):page77_i207@pure_quanta.q_res(chips)',
 PATH='I207',
 DRAWING='@T6G_MB_LIB.T6G(SCH_1):PAGE76',
 WATTAGE='1/16W',
 TOLERANCE='5%',
 MATERIAL='CHIP',
 PHYS_PAGE='77',
 XY='(-4075,2375)',
 ROT='0',
 VER='1',
 PACK_TYPE='0402LF',
 LOCATION='R607',
 CDS_LIB='pure_quanta',
 CDS_PART_NAME='Q_RES_0402LF-0,5%,1/16W,CHIP,CS00002JB13',
 PART_NUMBER='CS00002JB13',
 VALUE='0',
 PRIM_FILE='./archive_libs/logical/q_res/chips/chips.prt';

PART_NAME
 R608 'Q_RES_0402LF-33,5%,1/16W,CHIP,CS03302JB10':;

SECTION_NUMBER 1
 '@T6G_MB_LIB.T6G(SCH_1):PAGE76_I242@PURE_QUANTA.Q_RES(CHIPS)':
 C_PATH='@t6g_mb_lib.t6g(sch_1):page76_i242@pure_quanta.q_res(chips)',
 P_PATH='@t6g_mb_lib.t6g(sch_1):page77_i242@pure_quanta.q_res(chips)',
 PATH='I242',
 DRAWING='@T6G_MB_LIB.T6G(SCH_1):PAGE76',
 WATTAGE='1/16W',
 TOLERANCE='5%',
 MATERIAL='CHIP',
 PHYS_PAGE='77',
 XY='(-3950,4175)',
 ROT='0',
 VER='1',
 PACK_TYPE='0402LF',
 LOCATION='R608',
 CDS_LIB='pure_quanta',
 CDS_PART_NAME='Q_RES_0402LF-33,5%,1/16W,CHIP,CS03302JB10',
 PART_NUMBER='CS03302JB10',
 VALUE='33',
 PRIM_FILE='./archive_libs/logical/q_res/chips/chips.prt';

PART_NAME
 R609 'Q_RES_0201LF-0,5%,1/20W,CHIP,CS00001JE10':;

SECTION_NUMBER 1
 '@T6G_MB_LIB.T6G(SCH_1):PAGE401_I8@PURE_QUANTA.Q_RES(CHIPS)':
 C_PATH='@t6g_mb_lib.t6g(sch_1):page401_i8@pure_quanta.q_res(chips)',
 P_PATH='@t6g_mb_lib.t6g(sch_1):page320_i8@pure_quanta.q_res(chips)',
 PATH='I8',
 DRAWING='@T6G_MB_LIB.T6G(SCH_1):PAGE401',
 SEC_TYPE='0201LF',
 WATTAGE='1/20W',
 TOLERANCE='5%',
 MATERIAL='CHIP',
 PHYS_PAGE='320',
 XY='(-6600,1150)',
 ROT='0',
 VER='1',
 PACK_TYPE='0201LF',
 LOCATION='R609',
 SEC='1',
 CDS_LIB='pure_quanta',
 CDS_PART_NAME='Q_RES_0201LF-0,5%,1/20W,CHIP,CS00001JE10',
 PART_NUMBER='CS00001JE10',
 VALUE='0',
 PRIM_FILE='./archive_libs/logical/q_res/chips/chips.prt';

PART_NAME
 R610 'Q_RES_0402LF-1K,1%,1/16W,EMPTY,CS21002FB06':;

SECTION_NUMBER 1
 '@T6G_MB_LIB.T6G(SCH_1):PAGE76_I97@PURE_QUANTA.Q_RES(CHIPS)':
 C_PATH='@t6g_mb_lib.t6g(sch_1):page76_i97@pure_quanta.q_res(chips)',
 P_PATH='@t6g_mb_lib.t6g(sch_1):page77_i97@pure_quanta.q_res(chips)',
 PATH='I97',
 DRAWING='@T6G_MB_LIB.T6G(SCH_1):PAGE76',
 WATTAGE='1/16W',
 TOLERANCE='1%',
 MATERIAL='EMPTY',
 PHYS_PAGE='77',
 XY='(-2050,5625)',
 ROT='2',
 VER='2',
 PACK_TYPE='0402LF',
 LOCATION='R610',
 CDS_LIB='pure_quanta',
 CDS_PART_NAME='Q_RES_0402LF-1K,1%,1/16W,EMPTY,CS21002FB06',
 PART_NUMBER='CS21002FB06',
 VALUE='1K',
 PRIM_FILE='./archive_libs/logical/q_res/chips/chips.prt';

PART_NAME
 R611 'Q_RES_0201LF-0,5%,1/20W,CHIP,CS00001JE10':;

SECTION_NUMBER 1
 '@T6G_MB_LIB.T6G(SCH_1):PAGE408_I20@PURE_QUANTA.Q_RES(CHIPS)':
 C_PATH='@t6g_mb_lib.t6g(sch_1):page408_i20@pure_quanta.q_res(chips)',
 P_PATH='@t6g_mb_lib.t6g(sch_1):page287_i20@pure_quanta.q_res(chips)',
 PATH='I20',
 DRAWING='@T6G_MB_LIB.T6G(SCH_1):PAGE408',
 SEC_TYPE='0201LF',
 WATTAGE='1/20W',
 TOLERANCE='5%',
 MATERIAL='CHIP',
 PHYS_PAGE='287',
 XY='(-6600,1200)',
 ROT='0',
 VER='1',
 PACK_TYPE='0201LF',
 LOCATION='R611',
 SEC='1',
 CDS_LIB='pure_quanta',
 CDS_PART_NAME='Q_RES_0201LF-0,5%,1/20W,CHIP,CS00001JE10',
 PART_NUMBER='CS00001JE10',
 VALUE='0',
 PRIM_FILE='./archive_libs/logical/q_res/chips/chips.prt';

PART_NAME
 R612 'Q_RES_0201LF-0,5%,1/20W,CHIP,CS00001JE10':;

SECTION_NUMBER 1
 '@T6G_MB_LIB.T6G(SCH_1):PAGE408_I15@PURE_QUANTA.Q_RES(CHIPS)':
 C_PATH='@t6g_mb_lib.t6g(sch_1):page408_i15@pure_quanta.q_res(chips)',
 P_PATH='@t6g_mb_lib.t6g(sch_1):page287_i15@pure_quanta.q_res(chips)',
 PATH='I15',
 DRAWING='@T6G_MB_LIB.T6G(SCH_1):PAGE408',
 SEC_TYPE='0201LF',
 WATTAGE='1/20W',
 TOLERANCE='5%',
 MATERIAL='CHIP',
 PHYS_PAGE='287',
 XY='(-6600,1050)',
 ROT='0',
 VER='1',
 PACK_TYPE='0201LF',
 LOCATION='R612',
 SEC='1',
 CDS_LIB='pure_quanta',
 CDS_PART_NAME='Q_RES_0201LF-0,5%,1/20W,CHIP,CS00001JE10',
 PART_NUMBER='CS00001JE10',
 VALUE='0',
 PRIM_FILE='./archive_libs/logical/q_res/chips/chips.prt';

PART_NAME
 R613 'Q_RES_0201LF-0,5%,1/20W,CHIP,CS00001JE10':;

SECTION_NUMBER 1
 '@T6G_MB_LIB.T6G(SCH_1):PAGE419_I19@PURE_QUANTA.Q_RES(CHIPS)':
 C_PATH='@t6g_mb_lib.t6g(sch_1):page419_i19@pure_quanta.q_res(chips)',
 P_PATH='@t6g_mb_lib.t6g(sch_1):page298_i19@pure_quanta.q_res(chips)',
 PATH='I19',
 DRAWING='@T6G_MB_LIB.T6G(SCH_1):PAGE419',
 SEC_TYPE='0201LF',
 WATTAGE='1/20W',
 TOLERANCE='5%',
 MATERIAL='CHIP',
 PHYS_PAGE='298',
 XY='(-6625,1100)',
 ROT='0',
 VER='1',
 PACK_TYPE='0201LF',
 LOCATION='R613',
 SEC='1',
 CDS_LIB='pure_quanta',
 CDS_PART_NAME='Q_RES_0201LF-0,5%,1/20W,CHIP,CS00001JE10',
 PART_NUMBER='CS00001JE10',
 VALUE='0',
 PRIM_FILE='./archive_libs/logical/q_res/chips/chips.prt';

PART_NAME
 R614 'Q_RES_0201LF-0,5%,1/20W,CHIP,CS00001JE10':;

SECTION_NUMBER 1
 '@T6G_MB_LIB.T6G(SCH_1):PAGE419_I20@PURE_QUANTA.Q_RES(CHIPS)':
 C_PATH='@t6g_mb_lib.t6g(sch_1):page419_i20@pure_quanta.q_res(chips)',
 P_PATH='@t6g_mb_lib.t6g(sch_1):page298_i20@pure_quanta.q_res(chips)',
 PATH='I20',
 DRAWING='@T6G_MB_LIB.T6G(SCH_1):PAGE419',
 SEC_TYPE='0201LF',
 WATTAGE='1/20W',
 TOLERANCE='5%',
 MATERIAL='CHIP',
 PHYS_PAGE='298',
 XY='(-6625,950)',
 ROT='0',
 VER='1',
 PACK_TYPE='0201LF',
 LOCATION='R614',
 SEC='1',
 CDS_LIB='pure_quanta',
 CDS_PART_NAME='Q_RES_0201LF-0,5%,1/20W,CHIP,CS00001JE10',
 PART_NUMBER='CS00001JE10',
 VALUE='0',
 PRIM_FILE='./archive_libs/logical/q_res/chips/chips.prt';

PART_NAME
 R615 'Q_RES_0201LF-0,5%,1/20W,CHIP,CS00001JE10':;

SECTION_NUMBER 1
 '@T6G_MB_LIB.T6G(SCH_1):PAGE430_I20@PURE_QUANTA.Q_RES(CHIPS)':
 C_PATH='@t6g_mb_lib.t6g(sch_1):page430_i20@pure_quanta.q_res(chips)',
 P_PATH='@t6g_mb_lib.t6g(sch_1):page309_i20@pure_quanta.q_res(chips)',
 PATH='I20',
 DRAWING='@T6G_MB_LIB.T6G(SCH_1):PAGE430',
 SEC_TYPE='0201LF',
 WATTAGE='1/20W',
 TOLERANCE='5%',
 MATERIAL='CHIP',
 PHYS_PAGE='309',
 XY='(-6600,1200)',
 ROT='0',
 VER='1',
 PACK_TYPE='0201LF',
 LOCATION='R615',
 SEC='1',
 CDS_LIB='pure_quanta',
 CDS_PART_NAME='Q_RES_0201LF-0,5%,1/20W,CHIP,CS00001JE10',
 PART_NUMBER='CS00001JE10',
 VALUE='0',
 PRIM_FILE='./archive_libs/logical/q_res/chips/chips.prt';

PART_NAME
 R616 'Q_RES_0201LF-0,5%,1/20W,CHIP,CS00001JE10':;

SECTION_NUMBER 1
 '@T6G_MB_LIB.T6G(SCH_1):PAGE430_I15@PURE_QUANTA.Q_RES(CHIPS)':
 C_PATH='@t6g_mb_lib.t6g(sch_1):page430_i15@pure_quanta.q_res(chips)',
 P_PATH='@t6g_mb_lib.t6g(sch_1):page309_i15@pure_quanta.q_res(chips)',
 PATH='I15',
 DRAWING='@T6G_MB_LIB.T6G(SCH_1):PAGE430',
 SEC_TYPE='0201LF',
 WATTAGE='1/20W',
 TOLERANCE='5%',
 MATERIAL='CHIP',
 PHYS_PAGE='309',
 XY='(-6600,1050)',
 ROT='0',
 VER='1',
 PACK_TYPE='0201LF',
 LOCATION='R616',
 SEC='1',
 CDS_LIB='pure_quanta',
 CDS_PART_NAME='Q_RES_0201LF-0,5%,1/20W,CHIP,CS00001JE10',
 PART_NUMBER='CS00001JE10',
 VALUE='0',
 PRIM_FILE='./archive_libs/logical/q_res/chips/chips.prt';

PART_NAME
 R617 'Q_RES_0402LF-4.7K,5%,1/16W,CHIP,CS24702JB10':;

SECTION_NUMBER 1
 '@T6G_MB_LIB.T6G(SCH_1):PAGE149_I101@PURE_QUANTA.Q_RES(CHIPS)':
 C_PATH='@t6g_mb_lib.t6g(sch_1):page149_i101@pure_quanta.q_res(chips)',
 P_PATH='@t6g_mb_lib.t6g(sch_1):page172_i101@pure_quanta.q_res(chips)',
 PATH='I101',
 DRAWING='@T6G_MB_LIB.T6G(SCH_1):PAGE149',
 WATTAGE='1/16W',
 TOLERANCE='5%',
 MATERIAL='CHIP',
 PHYS_PAGE='172',
 XY='(-6425,3550)',
 ROT='0',
 VER='2',
 PACK_TYPE='0402LF',
 LOCATION='R617',
 CDS_LIB='pure_quanta',
 CDS_PART_NAME='Q_RES_0402LF-4.7K,5%,1/16W,CHIP,CS24702JB10',
 PART_NUMBER='CS24702JB10',
 VALUE='4.7K',
 PRIM_FILE='./archive_libs/logical/q_res/chips/chips.prt';

PART_NAME
 R618 'Q_RES_0402LF-0,5%,1/16W,CHIP,CS00002JB13':;

SECTION_NUMBER 1
 '@T6G_MB_LIB.T6G(SCH_1):PAGE54_I361@PURE_QUANTA.Q_RES(CHIPS)':
 C_PATH='@t6g_mb_lib.t6g(sch_1):page54_i361@pure_quanta.q_res(chips)',
 P_PATH='@t6g_mb_lib.t6g(sch_1):page54_i361@pure_quanta.q_res(chips)',
 PATH='I361',
 DRAWING='@T6G_MB_LIB.T6G(SCH_1):PAGE54',
 WATTAGE='1/16W',
 TOLERANCE='5%',
 MATERIAL='CHIP',
 PHYS_PAGE='54',
 XY='(-3100,4775)',
 ROT='0',
 VER='1',
 PACK_TYPE='0402LF',
 LOCATION='R618',
 CDS_LIB='pure_quanta',
 CDS_PART_NAME='Q_RES_0402LF-0,5%,1/16W,CHIP,CS00002JB13',
 PART_NUMBER='CS00002JB13',
 VALUE='0',
 PRIM_FILE='./archive_libs/logical/q_res/chips/chips.prt';

PART_NAME
 R619 'Q_RES_0201LF-0,5%,1/20W,CHIP,CS00001JE10':;

SECTION_NUMBER 1
 '@T6G_MB_LIB.T6G(SCH_1):PAGE451_I28@PURE_QUANTA.Q_RES(CHIPS)':
 C_PATH='@t6g_mb_lib.t6g(sch_1):page451_i28@pure_quanta.q_res(chips)',
 P_PATH='@t6g_mb_lib.t6g(sch_1):page342_i28@pure_quanta.q_res(chips)',
 PATH='I28',
 DRAWING='@T6G_MB_LIB.T6G(SCH_1):PAGE451',
 SEC_TYPE='0201LF',
 WATTAGE='1/20W',
 TOLERANCE='5%',
 MATERIAL='CHIP',
 PHYS_PAGE='342',
 XY='(-6575,1175)',
 ROT='0',
 VER='1',
 PACK_TYPE='0201LF',
 LOCATION='R619',
 SEC='1',
 CDS_LIB='pure_quanta',
 CDS_PART_NAME='Q_RES_0201LF-0,5%,1/20W,CHIP,CS00001JE10',
 PART_NUMBER='CS00001JE10',
 VALUE='0',
 PRIM_FILE='./archive_libs/logical/q_res/chips/chips.prt';

PART_NAME
 R620 'Q_RES_0201LF-0,5%,1/20W,CHIP,CS00001JE10':;

SECTION_NUMBER 1
 '@T6G_MB_LIB.T6G(SCH_1):PAGE451_I27@PURE_QUANTA.Q_RES(CHIPS)':
 C_PATH='@t6g_mb_lib.t6g(sch_1):page451_i27@pure_quanta.q_res(chips)',
 P_PATH='@t6g_mb_lib.t6g(sch_1):page342_i27@pure_quanta.q_res(chips)',
 PATH='I27',
 DRAWING='@T6G_MB_LIB.T6G(SCH_1):PAGE451',
 SEC_TYPE='0201LF',
 WATTAGE='1/20W',
 TOLERANCE='5%',
 MATERIAL='CHIP',
 PHYS_PAGE='342',
 XY='(-6575,1025)',
 ROT='0',
 VER='1',
 PACK_TYPE='0201LF',
 LOCATION='R620',
 SEC='1',
 CDS_LIB='pure_quanta',
 CDS_PART_NAME='Q_RES_0201LF-0,5%,1/20W,CHIP,CS00001JE10',
 PART_NUMBER='CS00001JE10',
 VALUE='0',
 PRIM_FILE='./archive_libs/logical/q_res/chips/chips.prt';

PART_NAME
 R621 'Q_RES_0201LF-0,5%,1/20W,CHIP,CS00001JE10':;

SECTION_NUMBER 1
 '@T6G_MB_LIB.T6G(SCH_1):PAGE462_I32@PURE_QUANTA.Q_RES(CHIPS)':
 C_PATH='@t6g_mb_lib.t6g(sch_1):page462_i32@pure_quanta.q_res(chips)',
 P_PATH='@t6g_mb_lib.t6g(sch_1):page353_i32@pure_quanta.q_res(chips)',
 PATH='I32',
 DRAWING='@T6G_MB_LIB.T6G(SCH_1):PAGE462',
 SEC_TYPE='0201LF',
 WATTAGE='1/20W',
 TOLERANCE='5%',
 MATERIAL='CHIP',
 PHYS_PAGE='353',
 XY='(-6650,1200)',
 ROT='0',
 VER='1',
 PACK_TYPE='0201LF',
 LOCATION='R621',
 SEC='1',
 CDS_LIB='pure_quanta',
 CDS_PART_NAME='Q_RES_0201LF-0,5%,1/20W,CHIP,CS00001JE10',
 PART_NUMBER='CS00001JE10',
 VALUE='0',
 PRIM_FILE='./archive_libs/logical/q_res/chips/chips.prt';

PART_NAME
 R622 'Q_RES_0201LF-0,5%,1/20W,CHIP,CS00001JE10':;

SECTION_NUMBER 1
 '@T6G_MB_LIB.T6G(SCH_1):PAGE462_I31@PURE_QUANTA.Q_RES(CHIPS)':
 C_PATH='@t6g_mb_lib.t6g(sch_1):page462_i31@pure_quanta.q_res(chips)',
 P_PATH='@t6g_mb_lib.t6g(sch_1):page353_i31@pure_quanta.q_res(chips)',
 PATH='I31',
 DRAWING='@T6G_MB_LIB.T6G(SCH_1):PAGE462',
 SEC_TYPE='0201LF',
 WATTAGE='1/20W',
 TOLERANCE='5%',
 MATERIAL='CHIP',
 PHYS_PAGE='353',
 XY='(-6650,1050)',
 ROT='0',
 VER='1',
 PACK_TYPE='0201LF',
 LOCATION='R622',
 SEC='1',
 CDS_LIB='pure_quanta',
 CDS_PART_NAME='Q_RES_0201LF-0,5%,1/20W,CHIP,CS00001JE10',
 PART_NUMBER='CS00001JE10',
 VALUE='0',
 PRIM_FILE='./archive_libs/logical/q_res/chips/chips.prt';

PART_NAME
 R623 'Q_RES_0201LF-51.1,1%,1/20W,EMPTY,CS05111FE00':;

SECTION_NUMBER 1
 '@T6G_MB_LIB.T6G(SCH_1):PAGE385_I37@PURE_QUANTA.Q_RES(CHIPS)':
 C_PATH='@t6g_mb_lib.t6g(sch_1):page385_i37@pure_quanta.q_res(chips)',
 P_PATH='@t6g_mb_lib.t6g(sch_1):page276_i37@pure_quanta.q_res(chips)',
 PATH='I37',
 DRAWING='@T6G_MB_LIB.T6G(SCH_1):PAGE385',
 WATTAGE='1/20W',
 TOLERANCE='1%',
 MATERIAL='EMPTY',
 PHYS_PAGE='276',
 XY='(-6300,675)',
 ROT='2',
 VER='2',
 PACK_TYPE='0201LF',
 LOCATION='R623',
 CDS_LIB='pure_quanta',
 CDS_PART_NAME='Q_RES_0201LF-51.1,1%,1/20W,EMPTY,CS05111FE00',
 PART_NUMBER='CS05111FE00',
 VALUE='51.1',
 PRIM_FILE='./archive_libs/logical/q_res/chips/chips.prt';

PART_NAME
 R624 'Q_RES_0201LF-51.1,1%,1/20W,EMPTY,CS05111FE00':;

SECTION_NUMBER 1
 '@T6G_MB_LIB.T6G(SCH_1):PAGE385_I38@PURE_QUANTA.Q_RES(CHIPS)':
 C_PATH='@t6g_mb_lib.t6g(sch_1):page385_i38@pure_quanta.q_res(chips)',
 P_PATH='@t6g_mb_lib.t6g(sch_1):page276_i38@pure_quanta.q_res(chips)',
 PATH='I38',
 DRAWING='@T6G_MB_LIB.T6G(SCH_1):PAGE385',
 WATTAGE='1/20W',
 TOLERANCE='1%',
 MATERIAL='EMPTY',
 PHYS_PAGE='276',
 XY='(-6150,675)',
 ROT='0',
 VER='2',
 PACK_TYPE='0201LF',
 LOCATION='R624',
 CDS_LIB='pure_quanta',
 CDS_PART_NAME='Q_RES_0201LF-51.1,1%,1/20W,EMPTY,CS05111FE00',
 PART_NUMBER='CS05111FE00',
 VALUE='51.1',
 PRIM_FILE='./archive_libs/logical/q_res/chips/chips.prt';

PART_NAME
 R625 'Q_RES_0201LF-51.1,1%,1/20W,EMPTY,CS05111FE00':;

SECTION_NUMBER 1
 '@T6G_MB_LIB.T6G(SCH_1):PAGE392_I31@PURE_QUANTA.Q_RES(CHIPS)':
 C_PATH='@t6g_mb_lib.t6g(sch_1):page392_i31@pure_quanta.q_res(chips)',
 P_PATH='@t6g_mb_lib.t6g(sch_1):page331_i31@pure_quanta.q_res(chips)',
 PATH='I31',
 DRAWING='@T6G_MB_LIB.T6G(SCH_1):PAGE392',
 WATTAGE='1/20W',
 TOLERANCE='1%',
 MATERIAL='EMPTY',
 PHYS_PAGE='331',
 XY='(-6150,575)',
 ROT='2',
 VER='2',
 PACK_TYPE='0201LF',
 LOCATION='R625',
 CDS_LIB='pure_quanta',
 CDS_PART_NAME='Q_RES_0201LF-51.1,1%,1/20W,EMPTY,CS05111FE00',
 PART_NUMBER='CS05111FE00',
 VALUE='51.1',
 PRIM_FILE='./archive_libs/logical/q_res/chips/chips.prt';

PART_NAME
 R626 'Q_RES_0201LF-51.1,1%,1/20W,EMPTY,CS05111FE00':;

SECTION_NUMBER 1
 '@T6G_MB_LIB.T6G(SCH_1):PAGE392_I32@PURE_QUANTA.Q_RES(CHIPS)':
 C_PATH='@t6g_mb_lib.t6g(sch_1):page392_i32@pure_quanta.q_res(chips)',
 P_PATH='@t6g_mb_lib.t6g(sch_1):page331_i32@pure_quanta.q_res(chips)',
 PATH='I32',
 DRAWING='@T6G_MB_LIB.T6G(SCH_1):PAGE392',
 WATTAGE='1/20W',
 TOLERANCE='1%',
 MATERIAL='EMPTY',
 PHYS_PAGE='331',
 XY='(-6000,575)',
 ROT='0',
 VER='2',
 PACK_TYPE='0201LF',
 LOCATION='R626',
 CDS_LIB='pure_quanta',
 CDS_PART_NAME='Q_RES_0201LF-51.1,1%,1/20W,EMPTY,CS05111FE00',
 PART_NUMBER='CS05111FE00',
 VALUE='51.1',
 PRIM_FILE='./archive_libs/logical/q_res/chips/chips.prt';

PART_NAME
 R627 'Q_RES_0201LF-51.1,1%,1/20W,EMPTY,CS05111FE00':;

SECTION_NUMBER 1
 '@T6G_MB_LIB.T6G(SCH_1):PAGE401_I23@PURE_QUANTA.Q_RES(CHIPS)':
 C_PATH='@t6g_mb_lib.t6g(sch_1):page401_i23@pure_quanta.q_res(chips)',
 P_PATH='@t6g_mb_lib.t6g(sch_1):page320_i23@pure_quanta.q_res(chips)',
 PATH='I23',
 DRAWING='@T6G_MB_LIB.T6G(SCH_1):PAGE401',
 WATTAGE='1/20W',
 TOLERANCE='1%',
 MATERIAL='EMPTY',
 PHYS_PAGE='320',
 XY='(-6300,825)',
 ROT='2',
 VER='2',
 PACK_TYPE='0201LF',
 LOCATION='R627',
 CDS_LIB='pure_quanta',
 CDS_PART_NAME='Q_RES_0201LF-51.1,1%,1/20W,EMPTY,CS05111FE00',
 PART_NUMBER='CS05111FE00',
 VALUE='51.1',
 PRIM_FILE='./archive_libs/logical/q_res/chips/chips.prt';

PART_NAME
 R628 'Q_RES_0201LF-51.1,1%,1/20W,EMPTY,CS05111FE00':;

SECTION_NUMBER 1
 '@T6G_MB_LIB.T6G(SCH_1):PAGE401_I24@PURE_QUANTA.Q_RES(CHIPS)':
 C_PATH='@t6g_mb_lib.t6g(sch_1):page401_i24@pure_quanta.q_res(chips)',
 P_PATH='@t6g_mb_lib.t6g(sch_1):page320_i24@pure_quanta.q_res(chips)',
 PATH='I24',
 DRAWING='@T6G_MB_LIB.T6G(SCH_1):PAGE401',
 WATTAGE='1/20W',
 TOLERANCE='1%',
 MATERIAL='EMPTY',
 PHYS_PAGE='320',
 XY='(-6150,825)',
 ROT='0',
 VER='2',
 PACK_TYPE='0201LF',
 LOCATION='R628',
 CDS_LIB='pure_quanta',
 CDS_PART_NAME='Q_RES_0201LF-51.1,1%,1/20W,EMPTY,CS05111FE00',
 PART_NUMBER='CS05111FE00',
 VALUE='51.1',
 PRIM_FILE='./archive_libs/logical/q_res/chips/chips.prt';

PART_NAME
 R629 'Q_RES_0201LF-51.1,1%,1/20W,EMPTY,CS05111FE00':;

SECTION_NUMBER 1
 '@T6G_MB_LIB.T6G(SCH_1):PAGE408_I18@PURE_QUANTA.Q_RES(CHIPS)':
 C_PATH='@t6g_mb_lib.t6g(sch_1):page408_i18@pure_quanta.q_res(chips)',
 P_PATH='@t6g_mb_lib.t6g(sch_1):page287_i18@pure_quanta.q_res(chips)',
 PATH='I18',
 DRAWING='@T6G_MB_LIB.T6G(SCH_1):PAGE408',
 WATTAGE='1/20W',
 TOLERANCE='1%',
 MATERIAL='EMPTY',
 PHYS_PAGE='287',
 XY='(-6300,725)',
 ROT='2',
 VER='2',
 PACK_TYPE='0201LF',
 LOCATION='R629',
 CDS_LIB='pure_quanta',
 CDS_PART_NAME='Q_RES_0201LF-51.1,1%,1/20W,EMPTY,CS05111FE00',
 PART_NUMBER='CS05111FE00',
 VALUE='51.1',
 PRIM_FILE='./archive_libs/logical/q_res/chips/chips.prt';

PART_NAME
 R630 'Q_RES_0201LF-51.1,1%,1/20W,EMPTY,CS05111FE00':;

SECTION_NUMBER 1
 '@T6G_MB_LIB.T6G(SCH_1):PAGE408_I19@PURE_QUANTA.Q_RES(CHIPS)':
 C_PATH='@t6g_mb_lib.t6g(sch_1):page408_i19@pure_quanta.q_res(chips)',
 P_PATH='@t6g_mb_lib.t6g(sch_1):page287_i19@pure_quanta.q_res(chips)',
 PATH='I19',
 DRAWING='@T6G_MB_LIB.T6G(SCH_1):PAGE408',
 WATTAGE='1/20W',
 TOLERANCE='1%',
 MATERIAL='EMPTY',
 PHYS_PAGE='287',
 XY='(-6150,725)',
 ROT='0',
 VER='2',
 PACK_TYPE='0201LF',
 LOCATION='R630',
 CDS_LIB='pure_quanta',
 CDS_PART_NAME='Q_RES_0201LF-51.1,1%,1/20W,EMPTY,CS05111FE00',
 PART_NUMBER='CS05111FE00',
 VALUE='51.1',
 PRIM_FILE='./archive_libs/logical/q_res/chips/chips.prt';

PART_NAME
 R631 'Q_RES_0201LF-51.1,1%,1/20W,EMPTY,CS05111FE00':;

SECTION_NUMBER 1
 '@T6G_MB_LIB.T6G(SCH_1):PAGE419_I17@PURE_QUANTA.Q_RES(CHIPS)':
 C_PATH='@t6g_mb_lib.t6g(sch_1):page419_i17@pure_quanta.q_res(chips)',
 P_PATH='@t6g_mb_lib.t6g(sch_1):page298_i17@pure_quanta.q_res(chips)',
 PATH='I17',
 DRAWING='@T6G_MB_LIB.T6G(SCH_1):PAGE419',
 WATTAGE='1/20W',
 TOLERANCE='1%',
 MATERIAL='EMPTY',
 PHYS_PAGE='298',
 XY='(-6325,625)',
 ROT='2',
 VER='2',
 PACK_TYPE='0201LF',
 LOCATION='R631',
 CDS_LIB='pure_quanta',
 CDS_PART_NAME='Q_RES_0201LF-51.1,1%,1/20W,EMPTY,CS05111FE00',
 PART_NUMBER='CS05111FE00',
 VALUE='51.1',
 PRIM_FILE='./archive_libs/logical/q_res/chips/chips.prt';

PART_NAME
 R632 'Q_RES_0402LF-2.2K,5%,1/16W,CHIP,CS22202JB07':;

SECTION_NUMBER 1
 '@T6G_MB_LIB.T6G(SCH_1):PAGE349_I18@PURE_QUANTA.Q_RES(CHIPS)':
 C_PATH='@t6g_mb_lib.t6g(sch_1):page349_i18@pure_quanta.q_res(chips)',
 P_PATH='@t6g_mb_lib.t6g(sch_1):page151_i18@pure_quanta.q_res(chips)',
 PATH='I18',
 DRAWING='@T6G_MB_LIB.T6G(SCH_1):PAGE349',
 WATTAGE='1/16W',
 TOLERANCE='5%',
 MATERIAL='CHIP',
 PHYS_PAGE='151',
 XY='(-250,4600)',
 ROT='0',
 VER='1',
 PACK_TYPE='0402LF',
 LOCATION='R632',
 CDS_LIB='pure_quanta',
 CDS_PART_NAME='Q_RES_0402LF-2.2K,5%,1/16W,CHIP,CS22202JB07',
 PART_NUMBER='CS22202JB07',
 VALUE='2.2K',
 PRIM_FILE='./archive_libs/logical/q_res/chips/chips.prt';

PART_NAME
 R633 'Q_RES_0402LF-2.2K,5%,1/16W,CHIP,CS22202JB07':;

SECTION_NUMBER 1
 '@T6G_MB_LIB.T6G(SCH_1):PAGE349_I17@PURE_QUANTA.Q_RES(CHIPS)':
 C_PATH='@t6g_mb_lib.t6g(sch_1):page349_i17@pure_quanta.q_res(chips)',
 P_PATH='@t6g_mb_lib.t6g(sch_1):page151_i17@pure_quanta.q_res(chips)',
 PATH='I17',
 DRAWING='@T6G_MB_LIB.T6G(SCH_1):PAGE349',
 WATTAGE='1/16W',
 TOLERANCE='5%',
 MATERIAL='CHIP',
 PHYS_PAGE='151',
 XY='(-250,4550)',
 ROT='0',
 VER='1',
 PACK_TYPE='0402LF',
 LOCATION='R633',
 CDS_LIB='pure_quanta',
 CDS_PART_NAME='Q_RES_0402LF-2.2K,5%,1/16W,CHIP,CS22202JB07',
 PART_NUMBER='CS22202JB07',
 VALUE='2.2K',
 PRIM_FILE='./archive_libs/logical/q_res/chips/chips.prt';

PART_NAME
 R634 'Q_RES_0201LF-51.1,1%,1/20W,EMPTY,CS05111FE00':;

SECTION_NUMBER 1
 '@T6G_MB_LIB.T6G(SCH_1):PAGE419_I18@PURE_QUANTA.Q_RES(CHIPS)':
 C_PATH='@t6g_mb_lib.t6g(sch_1):page419_i18@pure_quanta.q_res(chips)',
 P_PATH='@t6g_mb_lib.t6g(sch_1):page298_i18@pure_quanta.q_res(chips)',
 PATH='I18',
 DRAWING='@T6G_MB_LIB.T6G(SCH_1):PAGE419',
 WATTAGE='1/20W',
 TOLERANCE='1%',
 MATERIAL='EMPTY',
 PHYS_PAGE='298',
 XY='(-6175,625)',
 ROT='0',
 VER='2',
 PACK_TYPE='0201LF',
 LOCATION='R634',
 CDS_LIB='pure_quanta',
 CDS_PART_NAME='Q_RES_0201LF-51.1,1%,1/20W,EMPTY,CS05111FE00',
 PART_NUMBER='CS05111FE00',
 VALUE='51.1',
 PRIM_FILE='./archive_libs/logical/q_res/chips/chips.prt';

PART_NAME
 R635 'Q_RES_0201LF-51.1,1%,1/20W,EMPTY,CS05111FE00':;

SECTION_NUMBER 1
 '@T6G_MB_LIB.T6G(SCH_1):PAGE430_I18@PURE_QUANTA.Q_RES(CHIPS)':
 C_PATH='@t6g_mb_lib.t6g(sch_1):page430_i18@pure_quanta.q_res(chips)',
 P_PATH='@t6g_mb_lib.t6g(sch_1):page309_i18@pure_quanta.q_res(chips)',
 PATH='I18',
 DRAWING='@T6G_MB_LIB.T6G(SCH_1):PAGE430',
 WATTAGE='1/20W',
 TOLERANCE='1%',
 MATERIAL='EMPTY',
 PHYS_PAGE='309',
 XY='(-6300,725)',
 ROT='2',
 VER='2',
 PACK_TYPE='0201LF',
 LOCATION='R635',
 CDS_LIB='pure_quanta',
 CDS_PART_NAME='Q_RES_0201LF-51.1,1%,1/20W,EMPTY,CS05111FE00',
 PART_NUMBER='CS05111FE00',
 VALUE='51.1',
 PRIM_FILE='./archive_libs/logical/q_res/chips/chips.prt';

PART_NAME
 R636 'Q_RES_0201LF-51.1,1%,1/20W,EMPTY,CS05111FE00':;

SECTION_NUMBER 1
 '@T6G_MB_LIB.T6G(SCH_1):PAGE430_I19@PURE_QUANTA.Q_RES(CHIPS)':
 C_PATH='@t6g_mb_lib.t6g(sch_1):page430_i19@pure_quanta.q_res(chips)',
 P_PATH='@t6g_mb_lib.t6g(sch_1):page309_i19@pure_quanta.q_res(chips)',
 PATH='I19',
 DRAWING='@T6G_MB_LIB.T6G(SCH_1):PAGE430',
 WATTAGE='1/20W',
 TOLERANCE='1%',
 MATERIAL='EMPTY',
 PHYS_PAGE='309',
 XY='(-6150,725)',
 ROT='0',
 VER='2',
 PACK_TYPE='0201LF',
 LOCATION='R636',
 CDS_LIB='pure_quanta',
 CDS_PART_NAME='Q_RES_0201LF-51.1,1%,1/20W,EMPTY,CS05111FE00',
 PART_NUMBER='CS05111FE00',
 VALUE='51.1',
 PRIM_FILE='./archive_libs/logical/q_res/chips/chips.prt';

PART_NAME
 R637 'Q_RES_0201LF-51.1,1%,1/20W,EMPTY,CS05111FE00':;

SECTION_NUMBER 1
 '@T6G_MB_LIB.T6G(SCH_1):PAGE451_I92@PURE_QUANTA.Q_RES(CHIPS)':
 C_PATH='@t6g_mb_lib.t6g(sch_1):page451_i92@pure_quanta.q_res(chips)',
 P_PATH='@t6g_mb_lib.t6g(sch_1):page342_i92@pure_quanta.q_res(chips)',
 PATH='I92',
 DRAWING='@T6G_MB_LIB.T6G(SCH_1):PAGE451',
 WATTAGE='1/20W',
 TOLERANCE='1%',
 MATERIAL='EMPTY',
 PHYS_PAGE='342',
 XY='(-6275,700)',
 ROT='2',
 VER='2',
 PACK_TYPE='0201LF',
 LOCATION='R637',
 CDS_LIB='pure_quanta',
 CDS_PART_NAME='Q_RES_0201LF-51.1,1%,1/20W,EMPTY,CS05111FE00',
 PART_NUMBER='CS05111FE00',
 VALUE='51.1',
 PRIM_FILE='./archive_libs/logical/q_res/chips/chips.prt';

PART_NAME
 R638 'Q_RES_0402LF-1K,1%,1/16W,CHIP,CS21002FB06':;

SECTION_NUMBER 1
 '@T6G_MB_LIB.T6G(SCH_1):PAGE82_I35@PURE_QUANTA.Q_RES(CHIPS)':
 C_PATH='@t6g_mb_lib.t6g(sch_1):page82_i35@pure_quanta.q_res(chips)',
 P_PATH='@t6g_mb_lib.t6g(sch_1):page83_i35@pure_quanta.q_res(chips)',
 PATH='I35',
 DRAWING='@T6G_MB_LIB.T6G(SCH_1):PAGE82',
 WATTAGE='1/16W',
 TOLERANCE='1%',
 MATERIAL='CHIP',
 PHYS_PAGE='83',
 XY='(-7075,3125)',
 ROT='0',
 VER='1',
 PACK_TYPE='0402LF',
 LOCATION='R638',
 CDS_LIB='pure_quanta',
 CDS_PART_NAME='Q_RES_0402LF-1K,1%,1/16W,CHIP,CS21002FB06',
 PART_NUMBER='CS21002FB06',
 VALUE='1K',
 PRIM_FILE='./archive_libs/logical/q_res/chips/chips.prt';

PART_NAME
 R639 'Q_RES_0402LF-1K,1%,1/16W,CHIP,CS21002FB06':;

SECTION_NUMBER 1
 '@T6G_MB_LIB.T6G(SCH_1):PAGE82_I33@PURE_QUANTA.Q_RES(CHIPS)':
 C_PATH='@t6g_mb_lib.t6g(sch_1):page82_i33@pure_quanta.q_res(chips)',
 P_PATH='@t6g_mb_lib.t6g(sch_1):page83_i33@pure_quanta.q_res(chips)',
 PATH='I33',
 DRAWING='@T6G_MB_LIB.T6G(SCH_1):PAGE82',
 WATTAGE='1/16W',
 TOLERANCE='1%',
 MATERIAL='CHIP',
 PHYS_PAGE='83',
 XY='(-7075,3075)',
 ROT='0',
 VER='1',
 PACK_TYPE='0402LF',
 LOCATION='R639',
 CDS_LIB='pure_quanta',
 CDS_PART_NAME='Q_RES_0402LF-1K,1%,1/16W,CHIP,CS21002FB06',
 PART_NUMBER='CS21002FB06',
 VALUE='1K',
 PRIM_FILE='./archive_libs/logical/q_res/chips/chips.prt';

PART_NAME
 R640 'Q_RES_0201LF-51.1,1%,1/20W,EMPTY,CS05111FE00':;

SECTION_NUMBER 1
 '@T6G_MB_LIB.T6G(SCH_1):PAGE451_I36@PURE_QUANTA.Q_RES(CHIPS)':
 C_PATH='@t6g_mb_lib.t6g(sch_1):page451_i36@pure_quanta.q_res(chips)',
 P_PATH='@t6g_mb_lib.t6g(sch_1):page342_i36@pure_quanta.q_res(chips)',
 PATH='I36',
 DRAWING='@T6G_MB_LIB.T6G(SCH_1):PAGE451',
 WATTAGE='1/20W',
 TOLERANCE='1%',
 MATERIAL='EMPTY',
 PHYS_PAGE='342',
 XY='(-6125,700)',
 ROT='0',
 VER='2',
 PACK_TYPE='0201LF',
 LOCATION='R640',
 CDS_LIB='pure_quanta',
 CDS_PART_NAME='Q_RES_0201LF-51.1,1%,1/20W,EMPTY,CS05111FE00',
 PART_NUMBER='CS05111FE00',
 VALUE='51.1',
 PRIM_FILE='./archive_libs/logical/q_res/chips/chips.prt';

PART_NAME
 R641 'Q_RES_0201LF-51.1,1%,1/20W,EMPTY,CS05111FE00':;

SECTION_NUMBER 1
 '@T6G_MB_LIB.T6G(SCH_1):PAGE462_I30@PURE_QUANTA.Q_RES(CHIPS)':
 C_PATH='@t6g_mb_lib.t6g(sch_1):page462_i30@pure_quanta.q_res(chips)',
 P_PATH='@t6g_mb_lib.t6g(sch_1):page353_i30@pure_quanta.q_res(chips)',
 PATH='I30',
 DRAWING='@T6G_MB_LIB.T6G(SCH_1):PAGE462',
 WATTAGE='1/20W',
 TOLERANCE='1%',
 MATERIAL='EMPTY',
 PHYS_PAGE='353',
 XY='(-6350,725)',
 ROT='2',
 VER='2',
 PACK_TYPE='0201LF',
 LOCATION='R641',
 CDS_LIB='pure_quanta',
 CDS_PART_NAME='Q_RES_0201LF-51.1,1%,1/20W,EMPTY,CS05111FE00',
 PART_NUMBER='CS05111FE00',
 VALUE='51.1',
 PRIM_FILE='./archive_libs/logical/q_res/chips/chips.prt';

PART_NAME
 R642 'Q_RES_0201LF-51.1,1%,1/20W,EMPTY,CS05111FE00':;

SECTION_NUMBER 1
 '@T6G_MB_LIB.T6G(SCH_1):PAGE462_I46@PURE_QUANTA.Q_RES(CHIPS)':
 C_PATH='@t6g_mb_lib.t6g(sch_1):page462_i46@pure_quanta.q_res(chips)',
 P_PATH='@t6g_mb_lib.t6g(sch_1):page353_i46@pure_quanta.q_res(chips)',
 PATH='I46',
 DRAWING='@T6G_MB_LIB.T6G(SCH_1):PAGE462',
 WATTAGE='1/20W',
 TOLERANCE='1%',
 MATERIAL='EMPTY',
 PHYS_PAGE='353',
 XY='(-6200,725)',
 ROT='0',
 VER='2',
 PACK_TYPE='0201LF',
 LOCATION='R642',
 CDS_LIB='pure_quanta',
 CDS_PART_NAME='Q_RES_0201LF-51.1,1%,1/20W,EMPTY,CS05111FE00',
 PART_NUMBER='CS05111FE00',
 VALUE='51.1',
 PRIM_FILE='./archive_libs/logical/q_res/chips/chips.prt';

PART_NAME
 R643 'Q_RES_0402LF-1K,1%,1/16W,EMPTY,CS21002FB06':;

SECTION_NUMBER 1
 '@T6G_MB_LIB.T6G(SCH_1):PAGE475_I212@PURE_QUANTA.Q_RES(CHIPS)':
 C_PATH='@t6g_mb_lib.t6g(sch_1):page475_i212@pure_quanta.q_res(chips)',
 P_PATH='@t6g_mb_lib.t6g(sch_1):page362_i212@pure_quanta.q_res(chips)',
 PATH='I212',
 DRAWING='@T6G_MB_LIB.T6G(SCH_1):PAGE475',
 WATTAGE='1/16W',
 TOLERANCE='1%',
 MATERIAL='EMPTY',
 PHYS_PAGE='362',
 XY='(-9150,8025)',
 ROT='0',
 VER='1',
 PACK_TYPE='0402LF',
 LOCATION='R643',
 CDS_LIB='pure_quanta',
 CDS_PART_NAME='Q_RES_0402LF-1K,1%,1/16W,EMPTY,CS21002FB06',
 PART_NUMBER='CS21002FB06',
 VALUE='1K',
 PRIM_FILE='./archive_libs/logical/q_res/chips/chips.prt';

PART_NAME
 R644 'Q_RES_0402LF-10K,5%,1/16W,CHIP,CS31002JB08':;

SECTION_NUMBER 1
 '@T6G_MB_LIB.T6G(SCH_1):PAGE470_I29@PURE_QUANTA.Q_RES(CHIPS)':
 C_PATH='@t6g_mb_lib.t6g(sch_1):page470_i29@pure_quanta.q_res(chips)',
 P_PATH='@t6g_mb_lib.t6g(sch_1):page361_i29@pure_quanta.q_res(chips)',
 PATH='I29',
 DRAWING='@T6G_MB_LIB.T6G(SCH_1):PAGE470',
 SEC_TYPE='0402LF',
 WATTAGE='1/16W',
 TOLERANCE='5%',
 MATERIAL='CHIP',
 PHYS_PAGE='361',
 XY='(-4625,4250)',
 ROT='0',
 VER='2',
 PACK_TYPE='0402LF',
 LOCATION='R644',
 SEC='1',
 CDS_LIB='pure_quanta',
 CDS_PART_NAME='Q_RES_0402LF-10K,5%,1/16W,CHIP,CS31002JB08',
 PART_NUMBER='CS31002JB08',
 VALUE='10K',
 PRIM_FILE='./archive_libs/logical/q_res/chips/chips.prt';

PART_NAME
 R645 'Q_RES_0402LF-33,5%,1/16W,CHIP,CS03302JB10':;

SECTION_NUMBER 1
 '@T6G_MB_LIB.T6G(SCH_1):PAGE470_I36@PURE_QUANTA.Q_RES(CHIPS)':
 C_PATH='@t6g_mb_lib.t6g(sch_1):page470_i36@pure_quanta.q_res(chips)',
 P_PATH='@t6g_mb_lib.t6g(sch_1):page361_i36@pure_quanta.q_res(chips)',
 PATH='I36',
 DRAWING='@T6G_MB_LIB.T6G(SCH_1):PAGE470',
 BOM_COST='MEM',
 WATTAGE='1/16W',
 TOLERANCE='5%',
 MATERIAL='CHIP',
 PHYS_PAGE='361',
 XY='(-3575,3950)',
 ROT='0',
 VER='1',
 PACK_TYPE='0402LF',
 LOCATION='R645',
 CDS_LIB='pure_quanta',
 CDS_PART_NAME='Q_RES_0402LF-33,5%,1/16W,CHIP,CS03302JB10',
 PART_NUMBER='CS03302JB10',
 VALUE='33',
 PRIM_FILE='./archive_libs/logical/q_res/chips/chips.prt';

PART_NAME
 R646 'Q_RES_0402LF-0,5%,1/16W,CHIP,CS00002JB13':;

SECTION_NUMBER 1
 '@T6G_MB_LIB.T6G(SCH_1):PAGE475_I94@PURE_QUANTA.Q_RES(CHIPS)':
 C_PATH='@t6g_mb_lib.t6g(sch_1):page475_i94@pure_quanta.q_res(chips)',
 P_PATH='@t6g_mb_lib.t6g(sch_1):page362_i94@pure_quanta.q_res(chips)',
 PATH='I94',
 DRAWING='@T6G_MB_LIB.T6G(SCH_1):PAGE475',
 SEC_TYPE='0402LF',
 WATTAGE='1/16W',
 TOLERANCE='5%',
 MATERIAL='CHIP',
 PHYS_PAGE='362',
 XY='(-9300,6725)',
 ROT='0',
 VER='1',
 PACK_TYPE='0402LF',
 LOCATION='R646',
 SEC='1',
 CDS_LIB='pure_quanta',
 CDS_PART_NAME='Q_RES_0402LF-0,5%,1/16W,CHIP,CS00002JB13',
 PART_NUMBER='CS00002JB13',
 VALUE='0',
 PRIM_FILE='./archive_libs/logical/q_res/chips/chips.prt';

PART_NAME
 R647 'Q_RES_0402LF-0,5%,1/16W,CHIP,CS00002JB13':;

SECTION_NUMBER 1
 '@T6G_MB_LIB.T6G(SCH_1):PAGE475_I95@PURE_QUANTA.Q_RES(CHIPS)':
 C_PATH='@t6g_mb_lib.t6g(sch_1):page475_i95@pure_quanta.q_res(chips)',
 P_PATH='@t6g_mb_lib.t6g(sch_1):page362_i95@pure_quanta.q_res(chips)',
 PATH='I95',
 DRAWING='@T6G_MB_LIB.T6G(SCH_1):PAGE475',
 SEC_TYPE='0402LF',
 WATTAGE='1/16W',
 TOLERANCE='5%',
 MATERIAL='CHIP',
 PHYS_PAGE='362',
 XY='(-9300,6575)',
 ROT='0',
 VER='1',
 PACK_TYPE='0402LF',
 LOCATION='R647',
 SEC='1',
 CDS_LIB='pure_quanta',
 CDS_PART_NAME='Q_RES_0402LF-0,5%,1/16W,CHIP,CS00002JB13',
 PART_NUMBER='CS00002JB13',
 VALUE='0',
 PRIM_FILE='./archive_libs/logical/q_res/chips/chips.prt';

PART_NAME
 R648 'Q_RES_0402LF-33,5%,1/16W,CHIP,CS03302JB10':;

SECTION_NUMBER 1
 '@T6G_MB_LIB.T6G(SCH_1):PAGE80_I25@PURE_QUANTA.Q_RES(CHIPS)':
 C_PATH='@t6g_mb_lib.t6g(sch_1):page80_i25@pure_quanta.q_res(chips)',
 P_PATH='@t6g_mb_lib.t6g(sch_1):page81_i25@pure_quanta.q_res(chips)',
 PATH='I25',
 DRAWING='@T6G_MB_LIB.T6G(SCH_1):PAGE80',
 BOM_COST='MEM',
 WATTAGE='1/16W',
 TOLERANCE='5%',
 MATERIAL='CHIP',
 PHYS_PAGE='81',
 XY='(-6725,575)',
 ROT='0',
 VER='1',
 PACK_TYPE='0402LF',
 LOCATION='R648',
 CDS_LIB='pure_quanta',
 CDS_PART_NAME='Q_RES_0402LF-33,5%,1/16W,CHIP,CS03302JB10',
 PART_NUMBER='CS03302JB10',
 VALUE='33',
 PRIM_FILE='./archive_libs/logical/q_res/chips/chips.prt';

PART_NAME
 R649 'Q_RES_0402LF-4.7K,1%,1/16W,EMPTY,CS24702FB06':;

SECTION_NUMBER 1
 '@T6G_MB_LIB.T6G(SCH_1):PAGE475_I207@PURE_QUANTA.Q_RES(CHIPS)':
 C_PATH='@t6g_mb_lib.t6g(sch_1):page475_i207@pure_quanta.q_res(chips)',
 P_PATH='@t6g_mb_lib.t6g(sch_1):page362_i207@pure_quanta.q_res(chips)',
 PATH='I207',
 DRAWING='@T6G_MB_LIB.T6G(SCH_1):PAGE475',
 WATTAGE='1/16W',
 TOLERANCE='1%',
 MATERIAL='EMPTY',
 PHYS_PAGE='362',
 XY='(-9300,6425)',
 ROT='0',
 VER='1',
 PACK_TYPE='0402LF',
 LOCATION='R649',
 CDS_LIB='pure_quanta',
 CDS_PART_NAME='Q_RES_0402LF-4.7K,1%,1/16W,EMPTY,CS24702FB06',
 PART_NUMBER='CS24702FB06',
 VALUE='4.7K',
 PRIM_FILE='./archive_libs/logical/q_res/chips/chips.prt';

PART_NAME
 R650 'Q_RES_0402LF-0,5%,1/16W,CHIP,CS00002JB13':;

SECTION_NUMBER 1
 '@T6G_MB_LIB.T6G(SCH_1):PAGE475_I119@PURE_QUANTA.Q_RES(CHIPS)':
 C_PATH='@t6g_mb_lib.t6g(sch_1):page475_i119@pure_quanta.q_res(chips)',
 P_PATH='@t6g_mb_lib.t6g(sch_1):page362_i119@pure_quanta.q_res(chips)',
 PATH='I119',
 DRAWING='@T6G_MB_LIB.T6G(SCH_1):PAGE475',
 SEC_TYPE='0402LF',
 WATTAGE='1/16W',
 TOLERANCE='5%',
 MATERIAL='CHIP',
 PHYS_PAGE='362',
 XY='(-9950,7875)',
 ROT='0',
 VER='1',
 PACK_TYPE='0402LF',
 LOCATION='R650',
 SEC='1',
 CDS_LIB='pure_quanta',
 CDS_PART_NAME='Q_RES_0402LF-0,5%,1/16W,CHIP,CS00002JB13',
 PART_NUMBER='CS00002JB13',
 VALUE='0',
 PRIM_FILE='./archive_libs/logical/q_res/chips/chips.prt';

PART_NAME
 R651 'Q_RES_0402LF-0,5%,1/16W,CHIP,CS00002JB13':;

SECTION_NUMBER 1
 '@T6G_MB_LIB.T6G(SCH_1):PAGE475_I120@PURE_QUANTA.Q_RES(CHIPS)':
 C_PATH='@t6g_mb_lib.t6g(sch_1):page475_i120@pure_quanta.q_res(chips)',
 P_PATH='@t6g_mb_lib.t6g(sch_1):page362_i120@pure_quanta.q_res(chips)',
 PATH='I120',
 DRAWING='@T6G_MB_LIB.T6G(SCH_1):PAGE475',
 SEC_TYPE='0402LF',
 WATTAGE='1/16W',
 TOLERANCE='5%',
 MATERIAL='CHIP',
 PHYS_PAGE='362',
 XY='(-9300,7725)',
 ROT='0',
 VER='1',
 PACK_TYPE='0402LF',
 LOCATION='R651',
 SEC='1',
 CDS_LIB='pure_quanta',
 CDS_PART_NAME='Q_RES_0402LF-0,5%,1/16W,CHIP,CS00002JB13',
 PART_NUMBER='CS00002JB13',
 VALUE='0',
 PRIM_FILE='./archive_libs/logical/q_res/chips/chips.prt';

PART_NAME
 R652 'Q_RES_0402LF-1K,1%,1/16W,CHIP,CS21002FB06':;

SECTION_NUMBER 1
 '@T6G_MB_LIB.T6G(SCH_1):PAGE475_I128@PURE_QUANTA.Q_RES(CHIPS)':
 C_PATH='@t6g_mb_lib.t6g(sch_1):page475_i128@pure_quanta.q_res(chips)',
 P_PATH='@t6g_mb_lib.t6g(sch_1):page362_i128@pure_quanta.q_res(chips)',
 PATH='I128',
 DRAWING='@T6G_MB_LIB.T6G(SCH_1):PAGE475',
 SEC_TYPE='0402LF',
 WATTAGE='1/16W',
 TOLERANCE='1%',
 MATERIAL='CHIP',
 PHYS_PAGE='362',
 XY='(-8725,4075)',
 ROT='2',
 VER='2',
 PACK_TYPE='0402LF',
 LOCATION='R652',
 SEC='1',
 CDS_LIB='pure_quanta',
 CDS_PART_NAME='Q_RES_0402LF-1K,1%,1/16W,CHIP,CS21002FB06',
 PART_NUMBER='CS21002FB06',
 VALUE='1K',
 PRIM_FILE='./archive_libs/logical/q_res/chips/chips.prt';

PART_NAME
 R653 'Q_RES_0402LF-0,5%,1/16W,EMPTY,CS00002JB13':;

SECTION_NUMBER 1
 '@T6G_MB_LIB.T6G(SCH_1):PAGE443_I5@PURE_QUANTA.Q_RES(CHIPS)':
 C_PATH='@t6g_mb_lib.t6g(sch_1):page443_i5@pure_quanta.q_res(chips)',
 P_PATH='@t6g_mb_lib.t6g(sch_1):page334_i5@pure_quanta.q_res(chips)',
 PATH='I5',
 DRAWING='@T6G_MB_LIB.T6G(SCH_1):PAGE443',
 SEC_TYPE='0402LF',
 WATTAGE='1/16W',
 TOLERANCE='5%',
 MATERIAL='EMPTY',
 PHYS_PAGE='334',
 XY='(-7725,3575)',
 ROT='0',
 VER='1',
 PACK_TYPE='0402LF',
 LOCATION='R653',
 SEC='1',
 CDS_LIB='pure_quanta',
 CDS_PART_NAME='Q_RES_0402LF-0,5%,1/16W,EMPTY,CS00002JB13',
 PART_NUMBER='CS00002JB13',
 VALUE='0',
 PRIM_FILE='./archive_libs/logical/q_res/chips/chips.prt';

PART_NAME
 R654 'Q_RES_0402LF-4.7K,5%,1/16W,CHIP,CS24702JB10':;

SECTION_NUMBER 1
 '@T6G_MB_LIB.T6G(SCH_1):PAGE82_I64@PURE_QUANTA.Q_RES(CHIPS)':
 C_PATH='@t6g_mb_lib.t6g(sch_1):page82_i64@pure_quanta.q_res(chips)',
 P_PATH='@t6g_mb_lib.t6g(sch_1):page83_i64@pure_quanta.q_res(chips)',
 PATH='I64',
 DRAWING='@T6G_MB_LIB.T6G(SCH_1):PAGE82',
 WATTAGE='1/16W',
 TOLERANCE='5%',
 MATERIAL='CHIP',
 PHYS_PAGE='83',
 XY='(-7050,5750)',
 ROT='0',
 VER='1',
 PACK_TYPE='0402LF',
 LOCATION='R654',
 CDS_LIB='pure_quanta',
 CDS_PART_NAME='Q_RES_0402LF-4.7K,5%,1/16W,CHIP,CS24702JB10',
 PART_NUMBER='CS24702JB10',
 VALUE='4.7K',
 PRIM_FILE='./archive_libs/logical/q_res/chips/chips.prt';

PART_NAME
 R655 'Q_RES_0402LF-1K,1%,1/16W,CHIP,CS21002FB06':;

SECTION_NUMBER 1
 '@T6G_MB_LIB.T6G(SCH_1):PAGE475_I127@PURE_QUANTA.Q_RES(CHIPS)':
 C_PATH='@t6g_mb_lib.t6g(sch_1):page475_i127@pure_quanta.q_res(chips)',
 P_PATH='@t6g_mb_lib.t6g(sch_1):page362_i127@pure_quanta.q_res(chips)',
 PATH='I127',
 DRAWING='@T6G_MB_LIB.T6G(SCH_1):PAGE475',
 SEC_TYPE='0402LF',
 WATTAGE='1/16W',
 TOLERANCE='1%',
 MATERIAL='CHIP',
 PHYS_PAGE='362',
 XY='(-9100,4075)',
 ROT='2',
 VER='2',
 PACK_TYPE='0402LF',
 LOCATION='R655',
 SEC='1',
 CDS_LIB='pure_quanta',
 CDS_PART_NAME='Q_RES_0402LF-1K,1%,1/16W,CHIP,CS21002FB06',
 PART_NUMBER='CS21002FB06',
 VALUE='1K',
 PRIM_FILE='./archive_libs/logical/q_res/chips/chips.prt';

PART_NAME
 R656 'Q_RES_0402LF-1K,1%,1/16W,EMPTY,CS21002FB06':;

SECTION_NUMBER 1
 '@T6G_MB_LIB.T6G(SCH_1):PAGE477_I92@PURE_QUANTA.Q_RES(CHIPS)':
 C_PATH='@t6g_mb_lib.t6g(sch_1):page477_i92@pure_quanta.q_res(chips)',
 P_PATH='@t6g_mb_lib.t6g(sch_1):page364_i92@pure_quanta.q_res(chips)',
 PATH='I92',
 DRAWING='@T6G_MB_LIB.T6G(SCH_1):PAGE477',
 WATTAGE='1/16W',
 TOLERANCE='1%',
 MATERIAL='EMPTY',
 PHYS_PAGE='364',
 XY='(-6325,6325)',
 ROT='0',
 VER='1',
 PACK_TYPE='0402LF',
 LOCATION='R656',
 CDS_LIB='pure_quanta',
 CDS_PART_NAME='Q_RES_0402LF-1K,1%,1/16W,EMPTY,CS21002FB06',
 PART_NUMBER='CS21002FB06',
 VALUE='1K',
 PRIM_FILE='./archive_libs/logical/q_res/chips/chips.prt';

PART_NAME
 R657 'Q_RES_0402LF-0,5%,1/16W,CHIP,CS00002JB13':;

SECTION_NUMBER 1
 '@T6G_MB_LIB.T6G(SCH_1):PAGE477_I33@PURE_QUANTA.Q_RES(CHIPS)':
 C_PATH='@t6g_mb_lib.t6g(sch_1):page477_i33@pure_quanta.q_res(chips)',
 P_PATH='@t6g_mb_lib.t6g(sch_1):page364_i33@pure_quanta.q_res(chips)',
 PATH='I33',
 DRAWING='@T6G_MB_LIB.T6G(SCH_1):PAGE477',
 WATTAGE='1/16W',
 TOLERANCE='5%',
 MATERIAL='CHIP',
 PHYS_PAGE='364',
 XY='(-6500,5025)',
 ROT='0',
 VER='1',
 PACK_TYPE='0402LF',
 LOCATION='R657',
 CDS_LIB='pure_quanta',
 CDS_PART_NAME='Q_RES_0402LF-0,5%,1/16W,CHIP,CS00002JB13',
 PART_NUMBER='CS00002JB13',
 VALUE='0',
 PRIM_FILE='./archive_libs/logical/q_res/chips/chips.prt';

PART_NAME
 R658 'Q_RES_0402LF-0,5%,1/16W,CHIP,CS00002JB13':;

SECTION_NUMBER 1
 '@T6G_MB_LIB.T6G(SCH_1):PAGE477_I31@PURE_QUANTA.Q_RES(CHIPS)':
 C_PATH='@t6g_mb_lib.t6g(sch_1):page477_i31@pure_quanta.q_res(chips)',
 P_PATH='@t6g_mb_lib.t6g(sch_1):page364_i31@pure_quanta.q_res(chips)',
 PATH='I31',
 DRAWING='@T6G_MB_LIB.T6G(SCH_1):PAGE477',
 WATTAGE='1/16W',
 TOLERANCE='5%',
 MATERIAL='CHIP',
 PHYS_PAGE='364',
 XY='(-6500,4875)',
 ROT='0',
 VER='1',
 PACK_TYPE='0402LF',
 LOCATION='R658',
 CDS_LIB='pure_quanta',
 CDS_PART_NAME='Q_RES_0402LF-0,5%,1/16W,CHIP,CS00002JB13',
 PART_NUMBER='CS00002JB13',
 VALUE='0',
 PRIM_FILE='./archive_libs/logical/q_res/chips/chips.prt';

PART_NAME
 R659 'Q_RES_0402LF-1K,1%,1/16W,CHIP,CS21002FB06':;

SECTION_NUMBER 1
 '@T6G_MB_LIB.T6G(SCH_1):PAGE76_I107@PURE_QUANTA.Q_RES(CHIPS)':
 C_PATH='@t6g_mb_lib.t6g(sch_1):page76_i107@pure_quanta.q_res(chips)',
 P_PATH='@t6g_mb_lib.t6g(sch_1):page77_i107@pure_quanta.q_res(chips)',
 PATH='I107',
 DRAWING='@T6G_MB_LIB.T6G(SCH_1):PAGE76',
 WATTAGE='1/16W',
 TOLERANCE='1%',
 MATERIAL='CHIP',
 PHYS_PAGE='77',
 XY='(-8200,5875)',
 ROT='0',
 VER='2',
 PACK_TYPE='0402LF',
 LOCATION='R659',
 CDS_LIB='pure_quanta',
 CDS_PART_NAME='Q_RES_0402LF-1K,1%,1/16W,CHIP,CS21002FB06',
 PART_NUMBER='CS21002FB06',
 VALUE='1K',
 PRIM_FILE='./archive_libs/logical/q_res/chips/chips.prt';

PART_NAME
 R660 'Q_RES_0402LF-4.7K,1%,1/16W,EMPTY,CS24702FB06':;

SECTION_NUMBER 1
 '@T6G_MB_LIB.T6G(SCH_1):PAGE477_I89@PURE_QUANTA.Q_RES(CHIPS)':
 C_PATH='@t6g_mb_lib.t6g(sch_1):page477_i89@pure_quanta.q_res(chips)',
 P_PATH='@t6g_mb_lib.t6g(sch_1):page364_i89@pure_quanta.q_res(chips)',
 PATH='I89',
 DRAWING='@T6G_MB_LIB.T6G(SCH_1):PAGE477',
 WATTAGE='1/16W',
 TOLERANCE='1%',
 MATERIAL='EMPTY',
 PHYS_PAGE='364',
 XY='(-6475,4725)',
 ROT='0',
 VER='1',
 PACK_TYPE='0402LF',
 LOCATION='R660',
 CDS_LIB='pure_quanta',
 CDS_PART_NAME='Q_RES_0402LF-4.7K,1%,1/16W,EMPTY,CS24702FB06',
 PART_NUMBER='CS24702FB06',
 VALUE='4.7K',
 PRIM_FILE='./archive_libs/logical/q_res/chips/chips.prt';

PART_NAME
 R661 'Q_RES_0402LF-0,5%,1/16W,CHIP,CS00002JB13':;

SECTION_NUMBER 1
 '@T6G_MB_LIB.T6G(SCH_1):PAGE477_I39@PURE_QUANTA.Q_RES(CHIPS)':
 C_PATH='@t6g_mb_lib.t6g(sch_1):page477_i39@pure_quanta.q_res(chips)',
 P_PATH='@t6g_mb_lib.t6g(sch_1):page364_i39@pure_quanta.q_res(chips)',
 PATH='I39',
 DRAWING='@T6G_MB_LIB.T6G(SCH_1):PAGE477',
 WATTAGE='1/16W',
 TOLERANCE='5%',
 MATERIAL='CHIP',
 PHYS_PAGE='364',
 XY='(-7225,6175)',
 ROT='0',
 VER='1',
 PACK_TYPE='0402LF',
 LOCATION='R661',
 CDS_LIB='pure_quanta',
 CDS_PART_NAME='Q_RES_0402LF-0,5%,1/16W,CHIP,CS00002JB13',
 PART_NUMBER='CS00002JB13',
 VALUE='0',
 PRIM_FILE='./archive_libs/logical/q_res/chips/chips.prt';

PART_NAME
 R662 'Q_RES_0402LF-0,5%,1/16W,CHIP,CS00002JB13':;

SECTION_NUMBER 1
 '@T6G_MB_LIB.T6G(SCH_1):PAGE477_I38@PURE_QUANTA.Q_RES(CHIPS)':
 C_PATH='@t6g_mb_lib.t6g(sch_1):page477_i38@pure_quanta.q_res(chips)',
 P_PATH='@t6g_mb_lib.t6g(sch_1):page364_i38@pure_quanta.q_res(chips)',
 PATH='I38',
 DRAWING='@T6G_MB_LIB.T6G(SCH_1):PAGE477',
 WATTAGE='1/16W',
 TOLERANCE='5%',
 MATERIAL='CHIP',
 PHYS_PAGE='364',
 XY='(-6500,6025)',
 ROT='0',
 VER='1',
 PACK_TYPE='0402LF',
 LOCATION='R662',
 CDS_LIB='pure_quanta',
 CDS_PART_NAME='Q_RES_0402LF-0,5%,1/16W,CHIP,CS00002JB13',
 PART_NUMBER='CS00002JB13',
 VALUE='0',
 PRIM_FILE='./archive_libs/logical/q_res/chips/chips.prt';

PART_NAME
 R663 'Q_RES_0402LF-1K,1%,1/16W,CHIP,CS21002FB06':;

SECTION_NUMBER 1
 '@T6G_MB_LIB.T6G(SCH_1):PAGE477_I15@PURE_QUANTA.Q_RES(CHIPS)':
 C_PATH='@t6g_mb_lib.t6g(sch_1):page477_i15@pure_quanta.q_res(chips)',
 P_PATH='@t6g_mb_lib.t6g(sch_1):page364_i15@pure_quanta.q_res(chips)',
 PATH='I15',
 DRAWING='@T6G_MB_LIB.T6G(SCH_1):PAGE477',
 WATTAGE='1/16W',
 TOLERANCE='1%',
 MATERIAL='CHIP',
 PHYS_PAGE='364',
 XY='(-5925,2375)',
 ROT='2',
 VER='2',
 PACK_TYPE='0402LF',
 LOCATION='R663',
 CDS_LIB='pure_quanta',
 CDS_PART_NAME='Q_RES_0402LF-1K,1%,1/16W,CHIP,CS21002FB06',
 PART_NUMBER='CS21002FB06',
 VALUE='1K',
 PRIM_FILE='./archive_libs/logical/q_res/chips/chips.prt';

PART_NAME
 R664 'Q_RES_0402LF-0,5%,1/16W,EMPTY,CS00002JB13':;

SECTION_NUMBER 1
 '@T6G_MB_LIB.T6G(SCH_1):PAGE443_I4@PURE_QUANTA.Q_RES(CHIPS)':
 C_PATH='@t6g_mb_lib.t6g(sch_1):page443_i4@pure_quanta.q_res(chips)',
 P_PATH='@t6g_mb_lib.t6g(sch_1):page334_i4@pure_quanta.q_res(chips)',
 PATH='I4',
 DRAWING='@T6G_MB_LIB.T6G(SCH_1):PAGE443',
 SEC_TYPE='0402LF',
 WATTAGE='1/16W',
 TOLERANCE='5%',
 MATERIAL='EMPTY',
 PHYS_PAGE='334',
 XY='(-7725,3375)',
 ROT='0',
 VER='1',
 PACK_TYPE='0402LF',
 LOCATION='R664',
 SEC='1',
 CDS_LIB='pure_quanta',
 CDS_PART_NAME='Q_RES_0402LF-0,5%,1/16W,EMPTY,CS00002JB13',
 PART_NUMBER='CS00002JB13',
 VALUE='0',
 PRIM_FILE='./archive_libs/logical/q_res/chips/chips.prt';

PART_NAME
 R665 'Q_RES_0402LF-1K,1%,1/16W,CHIP,CS21002FB06':;

SECTION_NUMBER 1
 '@T6G_MB_LIB.T6G(SCH_1):PAGE477_I14@PURE_QUANTA.Q_RES(CHIPS)':
 C_PATH='@t6g_mb_lib.t6g(sch_1):page477_i14@pure_quanta.q_res(chips)',
 P_PATH='@t6g_mb_lib.t6g(sch_1):page364_i14@pure_quanta.q_res(chips)',
 PATH='I14',
 DRAWING='@T6G_MB_LIB.T6G(SCH_1):PAGE477',
 WATTAGE='1/16W',
 TOLERANCE='1%',
 MATERIAL='CHIP',
 PHYS_PAGE='364',
 XY='(-6300,2375)',
 ROT='2',
 VER='2',
 PACK_TYPE='0402LF',
 LOCATION='R665',
 CDS_LIB='pure_quanta',
 CDS_PART_NAME='Q_RES_0402LF-1K,1%,1/16W,CHIP,CS21002FB06',
 PART_NUMBER='CS21002FB06',
 VALUE='1K',
 PRIM_FILE='./archive_libs/logical/q_res/chips/chips.prt';

PART_NAME
 R666 'Q_RES_0201LF-49.9,1%,1/20W,CHIP,CS04991FE06':;

SECTION_NUMBER 1
 '@T6G_MB_LIB.T6G(SCH_1):PAGE385_I42@PURE_QUANTA.Q_RES(CHIPS)':
 C_PATH='@t6g_mb_lib.t6g(sch_1):page385_i42@pure_quanta.q_res(chips)',
 P_PATH='@t6g_mb_lib.t6g(sch_1):page276_i42@pure_quanta.q_res(chips)',
 PATH='I42',
 DRAWING='@T6G_MB_LIB.T6G(SCH_1):PAGE385',
 WATTAGE='1/20W',
 TOLERANCE='1%',
 MATERIAL='CHIP',
 PHYS_PAGE='276',
 XY='(-6325,1600)',
 ROT='0',
 VER='1',
 PACK_TYPE='0201LF',
 LOCATION='R666',
 CDS_LIB='pure_quanta',
 CDS_PART_NAME='Q_RES_0201LF-49.9,1%,1/20W,CHIP,CS04991FE06',
 PART_NUMBER='CS04991FE06',
 VALUE='49.9',
 PRIM_FILE='./archive_libs/logical/q_res/chips/chips.prt';

PART_NAME
 R667 'Q_RES_0201LF-49.9,1%,1/20W,CHIP,CS04991FE06':;

SECTION_NUMBER 1
 '@T6G_MB_LIB.T6G(SCH_1):PAGE385_I41@PURE_QUANTA.Q_RES(CHIPS)':
 C_PATH='@t6g_mb_lib.t6g(sch_1):page385_i41@pure_quanta.q_res(chips)',
 P_PATH='@t6g_mb_lib.t6g(sch_1):page276_i41@pure_quanta.q_res(chips)',
 PATH='I41',
 DRAWING='@T6G_MB_LIB.T6G(SCH_1):PAGE385',
 WATTAGE='1/20W',
 TOLERANCE='1%',
 MATERIAL='CHIP',
 PHYS_PAGE='276',
 XY='(-6325,1500)',
 ROT='0',
 VER='1',
 PACK_TYPE='0201LF',
 LOCATION='R667',
 CDS_LIB='pure_quanta',
 CDS_PART_NAME='Q_RES_0201LF-49.9,1%,1/20W,CHIP,CS04991FE06',
 PART_NUMBER='CS04991FE06',
 VALUE='49.9',
 PRIM_FILE='./archive_libs/logical/q_res/chips/chips.prt';

PART_NAME
 R668 'Q_RES_0201LF-33.2,1%,1/20W,CHIP,CS03321FE09':;

SECTION_NUMBER 1
 '@T6G_MB_LIB.T6G(SCH_1):PAGE387_I6@PURE_QUANTA.Q_RES(CHIPS)':
 C_PATH='@t6g_mb_lib.t6g(sch_1):page387_i6@pure_quanta.q_res(chips)',
 P_PATH='@t6g_mb_lib.t6g(sch_1):page278_i6@pure_quanta.q_res(chips)',
 PATH='I6',
 DRAWING='@T6G_MB_LIB.T6G(SCH_1):PAGE387',
 WATTAGE='1/20W',
 TOLERANCE='1%',
 MATERIAL='CHIP',
 PHYS_PAGE='278',
 XY='(-5850,4525)',
 ROT='0',
 VER='1',
 PACK_TYPE='0201LF',
 LOCATION='R668',
 CDS_LIB='pure_quanta',
 CDS_PART_NAME='Q_RES_0201LF-33.2,1%,1/20W,CHIP,CS03321FE09',
 PART_NUMBER='CS03321FE09',
 VALUE='33.2',
 PRIM_FILE='./archive_libs/logical/q_res/chips/chips.prt';

PART_NAME
 R669 'Q_RES_0201LF-33.2,1%,1/20W,CHIP,CS03321FE09':;

SECTION_NUMBER 1
 '@T6G_MB_LIB.T6G(SCH_1):PAGE387_I7@PURE_QUANTA.Q_RES(CHIPS)':
 C_PATH='@t6g_mb_lib.t6g(sch_1):page387_i7@pure_quanta.q_res(chips)',
 P_PATH='@t6g_mb_lib.t6g(sch_1):page278_i7@pure_quanta.q_res(chips)',
 PATH='I7',
 DRAWING='@T6G_MB_LIB.T6G(SCH_1):PAGE387',
 WATTAGE='1/20W',
 TOLERANCE='1%',
 MATERIAL='CHIP',
 PHYS_PAGE='278',
 XY='(-5850,4475)',
 ROT='0',
 VER='1',
 PACK_TYPE='0201LF',
 LOCATION='R669',
 CDS_LIB='pure_quanta',
 CDS_PART_NAME='Q_RES_0201LF-33.2,1%,1/20W,CHIP,CS03321FE09',
 PART_NUMBER='CS03321FE09',
 VALUE='33.2',
 PRIM_FILE='./archive_libs/logical/q_res/chips/chips.prt';

PART_NAME
 R670 'Q_RES_0201LF-49.9,1%,1/20W,CHIP,CS04991FE06':;

SECTION_NUMBER 1
 '@T6G_MB_LIB.T6G(SCH_1):PAGE392_I36@PURE_QUANTA.Q_RES(CHIPS)':
 C_PATH='@t6g_mb_lib.t6g(sch_1):page392_i36@pure_quanta.q_res(chips)',
 P_PATH='@t6g_mb_lib.t6g(sch_1):page331_i36@pure_quanta.q_res(chips)',
 PATH='I36',
 DRAWING='@T6G_MB_LIB.T6G(SCH_1):PAGE392',
 WATTAGE='1/20W',
 TOLERANCE='1%',
 MATERIAL='CHIP',
 PHYS_PAGE='331',
 XY='(-6175,1500)',
 ROT='0',
 VER='1',
 PACK_TYPE='0201LF',
 LOCATION='R670',
 CDS_LIB='pure_quanta',
 CDS_PART_NAME='Q_RES_0201LF-49.9,1%,1/20W,CHIP,CS04991FE06',
 PART_NUMBER='CS04991FE06',
 VALUE='49.9',
 PRIM_FILE='./archive_libs/logical/q_res/chips/chips.prt';

PART_NAME
 R671 'Q_RES_0201LF-49.9,1%,1/20W,CHIP,CS04991FE06':;

SECTION_NUMBER 1
 '@T6G_MB_LIB.T6G(SCH_1):PAGE392_I35@PURE_QUANTA.Q_RES(CHIPS)':
 C_PATH='@t6g_mb_lib.t6g(sch_1):page392_i35@pure_quanta.q_res(chips)',
 P_PATH='@t6g_mb_lib.t6g(sch_1):page331_i35@pure_quanta.q_res(chips)',
 PATH='I35',
 DRAWING='@T6G_MB_LIB.T6G(SCH_1):PAGE392',
 WATTAGE='1/20W',
 TOLERANCE='1%',
 MATERIAL='CHIP',
 PHYS_PAGE='331',
 XY='(-6175,1400)',
 ROT='0',
 VER='1',
 PACK_TYPE='0201LF',
 LOCATION='R671',
 CDS_LIB='pure_quanta',
 CDS_PART_NAME='Q_RES_0201LF-49.9,1%,1/20W,CHIP,CS04991FE06',
 PART_NUMBER='CS04991FE06',
 VALUE='49.9',
 PRIM_FILE='./archive_libs/logical/q_res/chips/chips.prt';

PART_NAME
 R672 'Q_RES_0201LF-33.2,1%,1/20W,CHIP,CS03321FE09':;

SECTION_NUMBER 1
 '@T6G_MB_LIB.T6G(SCH_1):PAGE399_I3@PURE_QUANTA.Q_RES(CHIPS)':
 C_PATH='@t6g_mb_lib.t6g(sch_1):page399_i3@pure_quanta.q_res(chips)',
 P_PATH='@t6g_mb_lib.t6g(sch_1):page322_i3@pure_quanta.q_res(chips)',
 PATH='I3',
 DRAWING='@T6G_MB_LIB.T6G(SCH_1):PAGE399',
 WATTAGE='1/20W',
 TOLERANCE='1%',
 MATERIAL='CHIP',
 PHYS_PAGE='322',
 XY='(-5450,5100)',
 ROT='0',
 VER='1',
 PACK_TYPE='0201LF',
 LOCATION='R672',
 CDS_LIB='pure_quanta',
 CDS_PART_NAME='Q_RES_0201LF-33.2,1%,1/20W,CHIP,CS03321FE09',
 PART_NUMBER='CS03321FE09',
 VALUE='33.2',
 PRIM_FILE='./archive_libs/logical/q_res/chips/chips.prt';

PART_NAME
 R673 'Q_RES_0201LF-33.2,1%,1/20W,CHIP,CS03321FE09':;

SECTION_NUMBER 1
 '@T6G_MB_LIB.T6G(SCH_1):PAGE399_I4@PURE_QUANTA.Q_RES(CHIPS)':
 C_PATH='@t6g_mb_lib.t6g(sch_1):page399_i4@pure_quanta.q_res(chips)',
 P_PATH='@t6g_mb_lib.t6g(sch_1):page322_i4@pure_quanta.q_res(chips)',
 PATH='I4',
 DRAWING='@T6G_MB_LIB.T6G(SCH_1):PAGE399',
 WATTAGE='1/20W',
 TOLERANCE='1%',
 MATERIAL='CHIP',
 PHYS_PAGE='322',
 XY='(-5450,5050)',
 ROT='0',
 VER='1',
 PACK_TYPE='0201LF',
 LOCATION='R673',
 CDS_LIB='pure_quanta',
 CDS_PART_NAME='Q_RES_0201LF-33.2,1%,1/20W,CHIP,CS03321FE09',
 PART_NUMBER='CS03321FE09',
 VALUE='33.2',
 PRIM_FILE='./archive_libs/logical/q_res/chips/chips.prt';

PART_NAME
 R674 'Q_RES_0201LF-22,1%,1/20W,CHIP,CS02201FE11':;

SECTION_NUMBER 1
 '@T6G_MB_LIB.T6G(SCH_1):PAGE401_I155@PURE_QUANTA.Q_RES(CHIPS)':
 C_PATH='@t6g_mb_lib.t6g(sch_1):page401_i155@pure_quanta.q_res(chips)',
 P_PATH='@t6g_mb_lib.t6g(sch_1):page320_i155@pure_quanta.q_res(chips)',
 PATH='I155',
 DRAWING='@T6G_MB_LIB.T6G(SCH_1):PAGE401',
 SEC_TYPE='0201LF',
 WATTAGE='1/20W',
 TOLERANCE='1%',
 MATERIAL='CHIP',
 PHYS_PAGE='320',
 XY='(-6325,1750)',
 ROT='0',
 VER='1',
 PACK_TYPE='0201LF',
 LOCATION='R674',
 SEC='1',
 CDS_LIB='pure_quanta',
 CDS_PART_NAME='Q_RES_0201LF-22,1%,1/20W,CHIP,CS02201FE11',
 PART_NUMBER='CS02201FE11',
 VALUE='22',
 PRIM_FILE='./archive_libs/logical/q_res/chips/chips.prt';

PART_NAME
 R675 'Q_RES_0201LF-49.9,1%,1/20W,CHIP,CS04991FE06':;

SECTION_NUMBER 1
 '@T6G_MB_LIB.T6G(SCH_1):PAGE401_I13@PURE_QUANTA.Q_RES(CHIPS)':
 C_PATH='@t6g_mb_lib.t6g(sch_1):page401_i13@pure_quanta.q_res(chips)',
 P_PATH='@t6g_mb_lib.t6g(sch_1):page320_i13@pure_quanta.q_res(chips)',
 PATH='I13',
 DRAWING='@T6G_MB_LIB.T6G(SCH_1):PAGE401',
 WATTAGE='1/20W',
 TOLERANCE='1%',
 MATERIAL='CHIP',
 PHYS_PAGE='320',
 XY='(-6325,1650)',
 ROT='0',
 VER='1',
 PACK_TYPE='0201LF',
 LOCATION='R675',
 CDS_LIB='pure_quanta',
 CDS_PART_NAME='Q_RES_0201LF-49.9,1%,1/20W,CHIP,CS04991FE06',
 PART_NUMBER='CS04991FE06',
 VALUE='49.9',
 PRIM_FILE='./archive_libs/logical/q_res/chips/chips.prt';

PART_NAME
 R676 'Q_RES_0201LF-49.9,1%,1/20W,CHIP,CS04991FE06':;

SECTION_NUMBER 1
 '@T6G_MB_LIB.T6G(SCH_1):PAGE408_I22@PURE_QUANTA.Q_RES(CHIPS)':
 C_PATH='@t6g_mb_lib.t6g(sch_1):page408_i22@pure_quanta.q_res(chips)',
 P_PATH='@t6g_mb_lib.t6g(sch_1):page287_i22@pure_quanta.q_res(chips)',
 PATH='I22',
 DRAWING='@T6G_MB_LIB.T6G(SCH_1):PAGE408',
 WATTAGE='1/20W',
 TOLERANCE='1%',
 MATERIAL='CHIP',
 PHYS_PAGE='287',
 XY='(-6325,1650)',
 ROT='0',
 VER='1',
 PACK_TYPE='0201LF',
 LOCATION='R676',
 CDS_LIB='pure_quanta',
 CDS_PART_NAME='Q_RES_0201LF-49.9,1%,1/20W,CHIP,CS04991FE06',
 PART_NUMBER='CS04991FE06',
 VALUE='49.9',
 PRIM_FILE='./archive_libs/logical/q_res/chips/chips.prt';

PART_NAME
 R677 'Q_RES_0201LF-49.9,1%,1/20W,CHIP,CS04991FE06':;

SECTION_NUMBER 1
 '@T6G_MB_LIB.T6G(SCH_1):PAGE408_I21@PURE_QUANTA.Q_RES(CHIPS)':
 C_PATH='@t6g_mb_lib.t6g(sch_1):page408_i21@pure_quanta.q_res(chips)',
 P_PATH='@t6g_mb_lib.t6g(sch_1):page287_i21@pure_quanta.q_res(chips)',
 PATH='I21',
 DRAWING='@T6G_MB_LIB.T6G(SCH_1):PAGE408',
 WATTAGE='1/20W',
 TOLERANCE='1%',
 MATERIAL='CHIP',
 PHYS_PAGE='287',
 XY='(-6325,1550)',
 ROT='0',
 VER='1',
 PACK_TYPE='0201LF',
 LOCATION='R677',
 CDS_LIB='pure_quanta',
 CDS_PART_NAME='Q_RES_0201LF-49.9,1%,1/20W,CHIP,CS04991FE06',
 PART_NUMBER='CS04991FE06',
 VALUE='49.9',
 PRIM_FILE='./archive_libs/logical/q_res/chips/chips.prt';

PART_NAME
 R678 'Q_RES_0201LF-33.2,1%,1/20W,CHIP,CS03321FE09':;

SECTION_NUMBER 1
 '@T6G_MB_LIB.T6G(SCH_1):PAGE410_I6@PURE_QUANTA.Q_RES(CHIPS)':
 C_PATH='@t6g_mb_lib.t6g(sch_1):page410_i6@pure_quanta.q_res(chips)',
 P_PATH='@t6g_mb_lib.t6g(sch_1):page289_i6@pure_quanta.q_res(chips)',
 PATH='I6',
 DRAWING='@T6G_MB_LIB.T6G(SCH_1):PAGE410',
 WATTAGE='1/20W',
 TOLERANCE='1%',
 MATERIAL='CHIP',
 PHYS_PAGE='289',
 XY='(-5175,5550)',
 ROT='0',
 VER='1',
 PACK_TYPE='0201LF',
 LOCATION='R678',
 CDS_LIB='pure_quanta',
 CDS_PART_NAME='Q_RES_0201LF-33.2,1%,1/20W,CHIP,CS03321FE09',
 PART_NUMBER='CS03321FE09',
 VALUE='33.2',
 PRIM_FILE='./archive_libs/logical/q_res/chips/chips.prt';

PART_NAME
 R679 'Q_RES_0201LF-33.2,1%,1/20W,CHIP,CS03321FE09':;

SECTION_NUMBER 1
 '@T6G_MB_LIB.T6G(SCH_1):PAGE410_I7@PURE_QUANTA.Q_RES(CHIPS)':
 C_PATH='@t6g_mb_lib.t6g(sch_1):page410_i7@pure_quanta.q_res(chips)',
 P_PATH='@t6g_mb_lib.t6g(sch_1):page289_i7@pure_quanta.q_res(chips)',
 PATH='I7',
 DRAWING='@T6G_MB_LIB.T6G(SCH_1):PAGE410',
 WATTAGE='1/20W',
 TOLERANCE='1%',
 MATERIAL='CHIP',
 PHYS_PAGE='289',
 XY='(-5175,5500)',
 ROT='0',
 VER='1',
 PACK_TYPE='0201LF',
 LOCATION='R679',
 CDS_LIB='pure_quanta',
 CDS_PART_NAME='Q_RES_0201LF-33.2,1%,1/20W,CHIP,CS03321FE09',
 PART_NUMBER='CS03321FE09',
 VALUE='33.2',
 PRIM_FILE='./archive_libs/logical/q_res/chips/chips.prt';

PART_NAME
 R680 'Q_RES_0201LF-49.9,1%,1/20W,CHIP,CS04991FE06':;

SECTION_NUMBER 1
 '@T6G_MB_LIB.T6G(SCH_1):PAGE419_I22@PURE_QUANTA.Q_RES(CHIPS)':
 C_PATH='@t6g_mb_lib.t6g(sch_1):page419_i22@pure_quanta.q_res(chips)',
 P_PATH='@t6g_mb_lib.t6g(sch_1):page298_i22@pure_quanta.q_res(chips)',
 PATH='I22',
 DRAWING='@T6G_MB_LIB.T6G(SCH_1):PAGE419',
 WATTAGE='1/20W',
 TOLERANCE='1%',
 MATERIAL='CHIP',
 PHYS_PAGE='298',
 XY='(-6350,1550)',
 ROT='0',
 VER='1',
 PACK_TYPE='0201LF',
 LOCATION='R680',
 CDS_LIB='pure_quanta',
 CDS_PART_NAME='Q_RES_0201LF-49.9,1%,1/20W,CHIP,CS04991FE06',
 PART_NUMBER='CS04991FE06',
 VALUE='49.9',
 PRIM_FILE='./archive_libs/logical/q_res/chips/chips.prt';

PART_NAME
 R681 'Q_RES_0201LF-49.9,1%,1/20W,CHIP,CS04991FE06':;

SECTION_NUMBER 1
 '@T6G_MB_LIB.T6G(SCH_1):PAGE419_I21@PURE_QUANTA.Q_RES(CHIPS)':
 C_PATH='@t6g_mb_lib.t6g(sch_1):page419_i21@pure_quanta.q_res(chips)',
 P_PATH='@t6g_mb_lib.t6g(sch_1):page298_i21@pure_quanta.q_res(chips)',
 PATH='I21',
 DRAWING='@T6G_MB_LIB.T6G(SCH_1):PAGE419',
 WATTAGE='1/20W',
 TOLERANCE='1%',
 MATERIAL='CHIP',
 PHYS_PAGE='298',
 XY='(-6350,1450)',
 ROT='0',
 VER='1',
 PACK_TYPE='0201LF',
 LOCATION='R681',
 CDS_LIB='pure_quanta',
 CDS_PART_NAME='Q_RES_0201LF-49.9,1%,1/20W,CHIP,CS04991FE06',
 PART_NUMBER='CS04991FE06',
 VALUE='49.9',
 PRIM_FILE='./archive_libs/logical/q_res/chips/chips.prt';

PART_NAME
 R682 'Q_RES_0201LF-33.2,1%,1/20W,CHIP,CS03321FE09':;

SECTION_NUMBER 1
 '@T6G_MB_LIB.T6G(SCH_1):PAGE421_I3@PURE_QUANTA.Q_RES(CHIPS)':
 C_PATH='@t6g_mb_lib.t6g(sch_1):page421_i3@pure_quanta.q_res(chips)',
 P_PATH='@t6g_mb_lib.t6g(sch_1):page300_i3@pure_quanta.q_res(chips)',
 PATH='I3',
 DRAWING='@T6G_MB_LIB.T6G(SCH_1):PAGE421',
 WATTAGE='1/20W',
 TOLERANCE='1%',
 MATERIAL='CHIP',
 PHYS_PAGE='300',
 XY='(-6200,5625)',
 ROT='0',
 VER='1',
 PACK_TYPE='0201LF',
 LOCATION='R682',
 CDS_LIB='pure_quanta',
 CDS_PART_NAME='Q_RES_0201LF-33.2,1%,1/20W,CHIP,CS03321FE09',
 PART_NUMBER='CS03321FE09',
 VALUE='33.2',
 PRIM_FILE='./archive_libs/logical/q_res/chips/chips.prt';

PART_NAME
 R683 'Q_RES_0201LF-33.2,1%,1/20W,CHIP,CS03321FE09':;

SECTION_NUMBER 1
 '@T6G_MB_LIB.T6G(SCH_1):PAGE421_I4@PURE_QUANTA.Q_RES(CHIPS)':
 C_PATH='@t6g_mb_lib.t6g(sch_1):page421_i4@pure_quanta.q_res(chips)',
 P_PATH='@t6g_mb_lib.t6g(sch_1):page300_i4@pure_quanta.q_res(chips)',
 PATH='I4',
 DRAWING='@T6G_MB_LIB.T6G(SCH_1):PAGE421',
 WATTAGE='1/20W',
 TOLERANCE='1%',
 MATERIAL='CHIP',
 PHYS_PAGE='300',
 XY='(-6200,5575)',
 ROT='0',
 VER='1',
 PACK_TYPE='0201LF',
 LOCATION='R683',
 CDS_LIB='pure_quanta',
 CDS_PART_NAME='Q_RES_0201LF-33.2,1%,1/20W,CHIP,CS03321FE09',
 PART_NUMBER='CS03321FE09',
 VALUE='33.2',
 PRIM_FILE='./archive_libs/logical/q_res/chips/chips.prt';

PART_NAME
 R684 'Q_RES_0201LF-49.9,1%,1/20W,CHIP,CS04991FE06':;

SECTION_NUMBER 1
 '@T6G_MB_LIB.T6G(SCH_1):PAGE430_I22@PURE_QUANTA.Q_RES(CHIPS)':
 C_PATH='@t6g_mb_lib.t6g(sch_1):page430_i22@pure_quanta.q_res(chips)',
 P_PATH='@t6g_mb_lib.t6g(sch_1):page309_i22@pure_quanta.q_res(chips)',
 PATH='I22',
 DRAWING='@T6G_MB_LIB.T6G(SCH_1):PAGE430',
 WATTAGE='1/20W',
 TOLERANCE='1%',
 MATERIAL='CHIP',
 PHYS_PAGE='309',
 XY='(-6325,1650)',
 ROT='0',
 VER='1',
 PACK_TYPE='0201LF',
 LOCATION='R684',
 CDS_LIB='pure_quanta',
 CDS_PART_NAME='Q_RES_0201LF-49.9,1%,1/20W,CHIP,CS04991FE06',
 PART_NUMBER='CS04991FE06',
 VALUE='49.9',
 PRIM_FILE='./archive_libs/logical/q_res/chips/chips.prt';

PART_NAME
 R685 'Q_RES_0402LF-33,5%,1/16W,CHIP,CS03302JB10':;

SECTION_NUMBER 1
 '@T6G_MB_LIB.T6G(SCH_1):PAGE80_I131@PURE_QUANTA.Q_RES(CHIPS)':
 C_PATH='@t6g_mb_lib.t6g(sch_1):page80_i131@pure_quanta.q_res(chips)',
 P_PATH='@t6g_mb_lib.t6g(sch_1):page81_i131@pure_quanta.q_res(chips)',
 PATH='I131',
 DRAWING='@T6G_MB_LIB.T6G(SCH_1):PAGE80',
 BOM_COST='MEM',
 WATTAGE='1/16W',
 TOLERANCE='5%',
 MATERIAL='CHIP',
 PHYS_PAGE='81',
 XY='(-2300,2725)',
 ROT='0',
 VER='1',
 PACK_TYPE='0402LF',
 LOCATION='R685',
 CDS_LIB='pure_quanta',
 CDS_PART_NAME='Q_RES_0402LF-33,5%,1/16W,CHIP,CS03302JB10',
 PART_NUMBER='CS03302JB10',
 VALUE='33',
 PRIM_FILE='./archive_libs/logical/q_res/chips/chips.prt';

PART_NAME
 R686 'Q_RES_0201LF-49.9,1%,1/20W,CHIP,CS04991FE06':;

SECTION_NUMBER 1
 '@T6G_MB_LIB.T6G(SCH_1):PAGE430_I21@PURE_QUANTA.Q_RES(CHIPS)':
 C_PATH='@t6g_mb_lib.t6g(sch_1):page430_i21@pure_quanta.q_res(chips)',
 P_PATH='@t6g_mb_lib.t6g(sch_1):page309_i21@pure_quanta.q_res(chips)',
 PATH='I21',
 DRAWING='@T6G_MB_LIB.T6G(SCH_1):PAGE430',
 WATTAGE='1/20W',
 TOLERANCE='1%',
 MATERIAL='CHIP',
 PHYS_PAGE='309',
 XY='(-6325,1550)',
 ROT='0',
 VER='1',
 PACK_TYPE='0201LF',
 LOCATION='R686',
 CDS_LIB='pure_quanta',
 CDS_PART_NAME='Q_RES_0201LF-49.9,1%,1/20W,CHIP,CS04991FE06',
 PART_NUMBER='CS04991FE06',
 VALUE='49.9',
 PRIM_FILE='./archive_libs/logical/q_res/chips/chips.prt';

PART_NAME
 R687 'Q_RES_0201LF-33.2,1%,1/20W,CHIP,CS03321FE09':;

SECTION_NUMBER 1
 '@T6G_MB_LIB.T6G(SCH_1):PAGE432_I3@PURE_QUANTA.Q_RES(CHIPS)':
 C_PATH='@t6g_mb_lib.t6g(sch_1):page432_i3@pure_quanta.q_res(chips)',
 P_PATH='@t6g_mb_lib.t6g(sch_1):page311_i3@pure_quanta.q_res(chips)',
 PATH='I3',
 DRAWING='@T6G_MB_LIB.T6G(SCH_1):PAGE432',
 WATTAGE='1/20W',
 TOLERANCE='1%',
 MATERIAL='CHIP',
 PHYS_PAGE='311',
 XY='(-6275,5600)',
 ROT='0',
 VER='1',
 PACK_TYPE='0201LF',
 LOCATION='R687',
 CDS_LIB='pure_quanta',
 CDS_PART_NAME='Q_RES_0201LF-33.2,1%,1/20W,CHIP,CS03321FE09',
 PART_NUMBER='CS03321FE09',
 VALUE='33.2',
 PRIM_FILE='./archive_libs/logical/q_res/chips/chips.prt';

PART_NAME
 R688 'Q_RES_0201LF-33.2,1%,1/20W,CHIP,CS03321FE09':;

SECTION_NUMBER 1
 '@T6G_MB_LIB.T6G(SCH_1):PAGE432_I4@PURE_QUANTA.Q_RES(CHIPS)':
 C_PATH='@t6g_mb_lib.t6g(sch_1):page432_i4@pure_quanta.q_res(chips)',
 P_PATH='@t6g_mb_lib.t6g(sch_1):page311_i4@pure_quanta.q_res(chips)',
 PATH='I4',
 DRAWING='@T6G_MB_LIB.T6G(SCH_1):PAGE432',
 WATTAGE='1/20W',
 TOLERANCE='1%',
 MATERIAL='CHIP',
 PHYS_PAGE='311',
 XY='(-6275,5550)',
 ROT='0',
 VER='1',
 PACK_TYPE='0201LF',
 LOCATION='R688',
 CDS_LIB='pure_quanta',
 CDS_PART_NAME='Q_RES_0201LF-33.2,1%,1/20W,CHIP,CS03321FE09',
 PART_NUMBER='CS03321FE09',
 VALUE='33.2',
 PRIM_FILE='./archive_libs/logical/q_res/chips/chips.prt';

PART_NAME
 R689 'Q_RES_0201LF-33.2,1%,1/20W,CHIP,CS03321FE09':;

SECTION_NUMBER 1
 '@T6G_MB_LIB.T6G(SCH_1):PAGE442_I4@PURE_QUANTA.Q_RES(CHIPS)':
 C_PATH='@t6g_mb_lib.t6g(sch_1):page442_i4@pure_quanta.q_res(chips)',
 P_PATH='@t6g_mb_lib.t6g(sch_1):page333_i4@pure_quanta.q_res(chips)',
 PATH='I4',
 DRAWING='@T6G_MB_LIB.T6G(SCH_1):PAGE442',
 WATTAGE='1/20W',
 TOLERANCE='1%',
 MATERIAL='CHIP',
 PHYS_PAGE='333',
 XY='(-5275,5075)',
 ROT='0',
 VER='1',
 PACK_TYPE='0201LF',
 LOCATION='R689',
 CDS_LIB='pure_quanta',
 CDS_PART_NAME='Q_RES_0201LF-33.2,1%,1/20W,CHIP,CS03321FE09',
 PART_NUMBER='CS03321FE09',
 VALUE='33.2',
 PRIM_FILE='./archive_libs/logical/q_res/chips/chips.prt';

PART_NAME
 R690 'Q_RES_0201LF-33.2,1%,1/20W,CHIP,CS03321FE09':;

SECTION_NUMBER 1
 '@T6G_MB_LIB.T6G(SCH_1):PAGE442_I3@PURE_QUANTA.Q_RES(CHIPS)':
 C_PATH='@t6g_mb_lib.t6g(sch_1):page442_i3@pure_quanta.q_res(chips)',
 P_PATH='@t6g_mb_lib.t6g(sch_1):page333_i3@pure_quanta.q_res(chips)',
 PATH='I3',
 DRAWING='@T6G_MB_LIB.T6G(SCH_1):PAGE442',
 WATTAGE='1/20W',
 TOLERANCE='1%',
 MATERIAL='CHIP',
 PHYS_PAGE='333',
 XY='(-5275,5025)',
 ROT='0',
 VER='1',
 PACK_TYPE='0201LF',
 LOCATION='R690',
 CDS_LIB='pure_quanta',
 CDS_PART_NAME='Q_RES_0201LF-33.2,1%,1/20W,CHIP,CS03321FE09',
 PART_NUMBER='CS03321FE09',
 VALUE='33.2',
 PRIM_FILE='./archive_libs/logical/q_res/chips/chips.prt';

PART_NAME
 R691 'Q_RES_0201LF-49.9,1%,1/20W,CHIP,CS04991FE06':;

SECTION_NUMBER 1
 '@T6G_MB_LIB.T6G(SCH_1):PAGE451_I30@PURE_QUANTA.Q_RES(CHIPS)':
 C_PATH='@t6g_mb_lib.t6g(sch_1):page451_i30@pure_quanta.q_res(chips)',
 P_PATH='@t6g_mb_lib.t6g(sch_1):page342_i30@pure_quanta.q_res(chips)',
 PATH='I30',
 DRAWING='@T6G_MB_LIB.T6G(SCH_1):PAGE451',
 WATTAGE='1/20W',
 TOLERANCE='1%',
 MATERIAL='CHIP',
 PHYS_PAGE='342',
 XY='(-6300,1625)',
 ROT='0',
 VER='1',
 PACK_TYPE='0201LF',
 LOCATION='R691',
 CDS_LIB='pure_quanta',
 CDS_PART_NAME='Q_RES_0201LF-49.9,1%,1/20W,CHIP,CS04991FE06',
 PART_NUMBER='CS04991FE06',
 VALUE='49.9',
 PRIM_FILE='./archive_libs/logical/q_res/chips/chips.prt';

PART_NAME
 R692 'Q_RES_0201LF-49.9,1%,1/20W,CHIP,CS04991FE06':;

SECTION_NUMBER 1
 '@T6G_MB_LIB.T6G(SCH_1):PAGE451_I29@PURE_QUANTA.Q_RES(CHIPS)':
 C_PATH='@t6g_mb_lib.t6g(sch_1):page451_i29@pure_quanta.q_res(chips)',
 P_PATH='@t6g_mb_lib.t6g(sch_1):page342_i29@pure_quanta.q_res(chips)',
 PATH='I29',
 DRAWING='@T6G_MB_LIB.T6G(SCH_1):PAGE451',
 WATTAGE='1/20W',
 TOLERANCE='1%',
 MATERIAL='CHIP',
 PHYS_PAGE='342',
 XY='(-6300,1525)',
 ROT='0',
 VER='1',
 PACK_TYPE='0201LF',
 LOCATION='R692',
 CDS_LIB='pure_quanta',
 CDS_PART_NAME='Q_RES_0201LF-49.9,1%,1/20W,CHIP,CS04991FE06',
 PART_NUMBER='CS04991FE06',
 VALUE='49.9',
 PRIM_FILE='./archive_libs/logical/q_res/chips/chips.prt';

PART_NAME
 R693 'Q_RES_0201LF-33.2,1%,1/20W,CHIP,CS03321FE09':;

SECTION_NUMBER 1
 '@T6G_MB_LIB.T6G(SCH_1):PAGE453_I4@PURE_QUANTA.Q_RES(CHIPS)':
 C_PATH='@t6g_mb_lib.t6g(sch_1):page453_i4@pure_quanta.q_res(chips)',
 P_PATH='@t6g_mb_lib.t6g(sch_1):page344_i4@pure_quanta.q_res(chips)',
 PATH='I4',
 DRAWING='@T6G_MB_LIB.T6G(SCH_1):PAGE453',
 WATTAGE='1/20W',
 TOLERANCE='1%',
 MATERIAL='CHIP',
 PHYS_PAGE='344',
 XY='(-6300,5575)',
 ROT='0',
 VER='1',
 PACK_TYPE='0201LF',
 LOCATION='R693',
 CDS_LIB='pure_quanta',
 CDS_PART_NAME='Q_RES_0201LF-33.2,1%,1/20W,CHIP,CS03321FE09',
 PART_NUMBER='CS03321FE09',
 VALUE='33.2',
 PRIM_FILE='./archive_libs/logical/q_res/chips/chips.prt';

PART_NAME
 R694 'Q_RES_0201LF-33.2,1%,1/20W,CHIP,CS03321FE09':;

SECTION_NUMBER 1
 '@T6G_MB_LIB.T6G(SCH_1):PAGE453_I3@PURE_QUANTA.Q_RES(CHIPS)':
 C_PATH='@t6g_mb_lib.t6g(sch_1):page453_i3@pure_quanta.q_res(chips)',
 P_PATH='@t6g_mb_lib.t6g(sch_1):page344_i3@pure_quanta.q_res(chips)',
 PATH='I3',
 DRAWING='@T6G_MB_LIB.T6G(SCH_1):PAGE453',
 WATTAGE='1/20W',
 TOLERANCE='1%',
 MATERIAL='CHIP',
 PHYS_PAGE='344',
 XY='(-6300,5525)',
 ROT='0',
 VER='1',
 PACK_TYPE='0201LF',
 LOCATION='R694',
 CDS_LIB='pure_quanta',
 CDS_PART_NAME='Q_RES_0201LF-33.2,1%,1/20W,CHIP,CS03321FE09',
 PART_NUMBER='CS03321FE09',
 VALUE='33.2',
 PRIM_FILE='./archive_libs/logical/q_res/chips/chips.prt';

PART_NAME
 R695 'Q_RES_0201LF-22,1%,1/20W,CHIP,CS02201FE11':;

SECTION_NUMBER 1
 '@T6G_MB_LIB.T6G(SCH_1):PAGE462_I146@PURE_QUANTA.Q_RES(CHIPS)':
 C_PATH='@t6g_mb_lib.t6g(sch_1):page462_i146@pure_quanta.q_res(chips)',
 P_PATH='@t6g_mb_lib.t6g(sch_1):page353_i146@pure_quanta.q_res(chips)',
 PATH='I146',
 DRAWING='@T6G_MB_LIB.T6G(SCH_1):PAGE462',
 SEC_TYPE='0201LF',
 WATTAGE='1/20W',
 TOLERANCE='1%',
 MATERIAL='CHIP',
 PHYS_PAGE='353',
 XY='(-6375,1650)',
 ROT='0',
 VER='1',
 PACK_TYPE='0201LF',
 LOCATION='R695',
 SEC='1',
 CDS_LIB='pure_quanta',
 CDS_PART_NAME='Q_RES_0201LF-22,1%,1/20W,CHIP,CS02201FE11',
 PART_NUMBER='CS02201FE11',
 VALUE='22',
 PRIM_FILE='./archive_libs/logical/q_res/chips/chips.prt';

PART_NAME
 R696 'Q_RES_0201LF-49.9,1%,1/20W,CHIP,CS04991FE06':;

SECTION_NUMBER 1
 '@T6G_MB_LIB.T6G(SCH_1):PAGE462_I33@PURE_QUANTA.Q_RES(CHIPS)':
 C_PATH='@t6g_mb_lib.t6g(sch_1):page462_i33@pure_quanta.q_res(chips)',
 P_PATH='@t6g_mb_lib.t6g(sch_1):page353_i33@pure_quanta.q_res(chips)',
 PATH='I33',
 DRAWING='@T6G_MB_LIB.T6G(SCH_1):PAGE462',
 WATTAGE='1/20W',
 TOLERANCE='1%',
 MATERIAL='CHIP',
 PHYS_PAGE='353',
 XY='(-6375,1550)',
 ROT='0',
 VER='1',
 PACK_TYPE='0201LF',
 LOCATION='R696',
 CDS_LIB='pure_quanta',
 CDS_PART_NAME='Q_RES_0201LF-49.9,1%,1/20W,CHIP,CS04991FE06',
 PART_NUMBER='CS04991FE06',
 VALUE='49.9',
 PRIM_FILE='./archive_libs/logical/q_res/chips/chips.prt';

PART_NAME
 R697 'Q_RES_0201LF-0,5%,1/20W,CHIP,CS00001JE10':;

SECTION_NUMBER 1
 '@T6G_MB_LIB.T6G(SCH_1):PAGE464_I25@PURE_QUANTA.Q_RES(CHIPS)':
 C_PATH='@t6g_mb_lib.t6g(sch_1):page464_i25@pure_quanta.q_res(chips)',
 P_PATH='@t6g_mb_lib.t6g(sch_1):page355_i25@pure_quanta.q_res(chips)',
 PATH='I25',
 DRAWING='@T6G_MB_LIB.T6G(SCH_1):PAGE464',
 SEC_TYPE='0201LF',
 WATTAGE='1/20W',
 TOLERANCE='5%',
 MATERIAL='CHIP',
 PHYS_PAGE='355',
 XY='(-5650,5400)',
 ROT='0',
 VER='1',
 PACK_TYPE='0201LF',
 LOCATION='R697',
 SEC='1',
 CDS_LIB='pure_quanta',
 CDS_PART_NAME='Q_RES_0201LF-0,5%,1/20W,CHIP,CS00001JE10',
 PART_NUMBER='CS00001JE10',
 VALUE='0',
 PRIM_FILE='./archive_libs/logical/q_res/chips/chips.prt';

PART_NAME
 R698 'Q_RES_0201LF-33.2,1%,1/20W,CHIP,CS03321FE09':;

SECTION_NUMBER 1
 '@T6G_MB_LIB.T6G(SCH_1):PAGE464_I4@PURE_QUANTA.Q_RES(CHIPS)':
 C_PATH='@t6g_mb_lib.t6g(sch_1):page464_i4@pure_quanta.q_res(chips)',
 P_PATH='@t6g_mb_lib.t6g(sch_1):page355_i4@pure_quanta.q_res(chips)',
 PATH='I4',
 DRAWING='@T6G_MB_LIB.T6G(SCH_1):PAGE464',
 WATTAGE='1/20W',
 TOLERANCE='1%',
 MATERIAL='CHIP',
 PHYS_PAGE='355',
 XY='(-5650,5350)',
 ROT='0',
 VER='1',
 PACK_TYPE='0201LF',
 LOCATION='R698',
 CDS_LIB='pure_quanta',
 CDS_PART_NAME='Q_RES_0201LF-33.2,1%,1/20W,CHIP,CS03321FE09',
 PART_NUMBER='CS03321FE09',
 VALUE='33.2',
 PRIM_FILE='./archive_libs/logical/q_res/chips/chips.prt';

PART_NAME
 R699 'Q_RES_0201LF-1K,1%,1/20W,EMPTY,CS21001FE07':;

SECTION_NUMBER 1
 '@T6G_MB_LIB.T6G(SCH_1):PAGE400_I106@PURE_QUANTA.Q_RES(CHIPS)':
 C_PATH='@t6g_mb_lib.t6g(sch_1):page400_i106@pure_quanta.q_res(chips)',
 P_PATH='@t6g_mb_lib.t6g(sch_1):page321_i106@pure_quanta.q_res(chips)',
 PATH='I106',
 DRAWING='@T6G_MB_LIB.T6G(SCH_1):PAGE400',
 WATTAGE='1/20W',
 TOLERANCE='1%',
 MATERIAL='EMPTY',
 PHYS_PAGE='321',
 XY='(-8100,4200)',
 ROT='0',
 VER='2',
 PACK_TYPE='0201LF',
 LOCATION='R699',
 CDS_LIB='pure_quanta',
 CDS_PART_NAME='Q_RES_0201LF-1K,1%,1/20W,EMPTY,CS21001FE07',
 PART_NUMBER='CS21001FE07',
 VALUE='1K',
 PRIM_FILE='./archive_libs/logical/q_res/chips/chips.prt';

PART_NAME
 R700 'Q_RES_0402LF-30K,1%,1/16W,EMPTY,CS33002FB02':;

SECTION_NUMBER 1
 '@T6G_MB_LIB.T6G(SCH_1):PAGE146_I2@PURE_QUANTA.Q_RES(CHIPS)':
 C_PATH='@t6g_mb_lib.t6g(sch_1):page146_i2@pure_quanta.q_res(chips)',
 P_PATH='@t6g_mb_lib.t6g(sch_1):page169_i2@pure_quanta.q_res(chips)',
 PATH='I2',
 DRAWING='@T6G_MB_LIB.T6G(SCH_1):PAGE146',
 WATTAGE='1/16W',
 TOLERANCE='1%',
 MATERIAL='EMPTY',
 PHYS_PAGE='169',
 XY='(-9175,5050)',
 ROT='0',
 VER='2',
 PACK_TYPE='0402LF',
 LOCATION='R700',
 CDS_LIB='pure_quanta',
 CDS_PART_NAME='Q_RES_0402LF-30K,1%,1/16W,EMPTY,CS33002FB02',
 PART_NUMBER='CS33002FB02',
 VALUE='30K',
 PRIM_FILE='./archive_libs/logical/q_res/chips/chips.prt';

PART_NAME
 R701 'Q_RES_0201LF-200,1%,1/20W,CHIP,CS12001FE12':;

SECTION_NUMBER 1
 '@T6G_MB_LIB.T6G(SCH_1):PAGE400_I105@PURE_QUANTA.Q_RES(CHIPS)':
 C_PATH='@t6g_mb_lib.t6g(sch_1):page400_i105@pure_quanta.q_res(chips)',
 P_PATH='@t6g_mb_lib.t6g(sch_1):page321_i105@pure_quanta.q_res(chips)',
 PATH='I105',
 DRAWING='@T6G_MB_LIB.T6G(SCH_1):PAGE400',
 WATTAGE='1/20W',
 TOLERANCE='1%',
 MATERIAL='CHIP',
 PHYS_PAGE='321',
 XY='(-7075,3650)',
 ROT='0',
 VER='2',
 PACK_TYPE='0201LF',
 LOCATION='R701',
 CDS_LIB='pure_quanta',
 CDS_PART_NAME='Q_RES_0201LF-200,1%,1/20W,CHIP,CS12001FE12',
 PART_NUMBER='CS12001FE12',
 VALUE='200',
 PRIM_FILE='./archive_libs/logical/q_res/chips/chips.prt';

PART_NAME
 R702 'Q_RES_0402LF-10K,5%,1/16W,EMPTY,CS31002JB08':;

SECTION_NUMBER 1
 '@T6G_MB_LIB.T6G(SCH_1):PAGE77_I1@PURE_QUANTA.Q_RES(CHIPS)':
 C_PATH='@t6g_mb_lib.t6g(sch_1):page77_i1@pure_quanta.q_res(chips)',
 P_PATH='@t6g_mb_lib.t6g(sch_1):page78_i1@pure_quanta.q_res(chips)',
 PATH='I1',
 DRAWING='@T6G_MB_LIB.T6G(SCH_1):PAGE77',
 WATTAGE='1/16W',
 TOLERANCE='5%',
 MATERIAL='EMPTY',
 PHYS_PAGE='78',
 XY='(-5900,3950)',
 ROT='2',
 VER='2',
 PACK_TYPE='0402LF',
 LOCATION='R702',
 CDS_LIB='pure_quanta',
 CDS_PART_NAME='Q_RES_0402LF-10K,5%,1/16W,EMPTY,CS31002JB08',
 PART_NUMBER='CS31002JB08',
 VALUE='10K',
 PRIM_FILE='./archive_libs/logical/q_res/chips/chips.prt';

PART_NAME
 R703 'Q_RES_0402LF-10K,5%,1/16W,EMPTY,CS31002JB08':;

SECTION_NUMBER 1
 '@T6G_MB_LIB.T6G(SCH_1):PAGE77_I5@PURE_QUANTA.Q_RES(CHIPS)':
 C_PATH='@t6g_mb_lib.t6g(sch_1):page77_i5@pure_quanta.q_res(chips)',
 P_PATH='@t6g_mb_lib.t6g(sch_1):page78_i5@pure_quanta.q_res(chips)',
 PATH='I5',
 DRAWING='@T6G_MB_LIB.T6G(SCH_1):PAGE77',
 WATTAGE='1/16W',
 TOLERANCE='5%',
 MATERIAL='EMPTY',
 PHYS_PAGE='78',
 XY='(-5850,2175)',
 ROT='2',
 VER='2',
 PACK_TYPE='0402LF',
 LOCATION='R703',
 CDS_LIB='pure_quanta',
 CDS_PART_NAME='Q_RES_0402LF-10K,5%,1/16W,EMPTY,CS31002JB08',
 PART_NUMBER='CS31002JB08',
 VALUE='10K',
 PRIM_FILE='./archive_libs/logical/q_res/chips/chips.prt';

PART_NAME
 R704 'Q_RES_0402LF-0,5%,1/16W,EMPTY,CS00002JB13':;

SECTION_NUMBER 1
 '@T6G_MB_LIB.T6G(SCH_1):PAGE443_I89@PURE_QUANTA.Q_RES(CHIPS)':
 C_PATH='@t6g_mb_lib.t6g(sch_1):page443_i89@pure_quanta.q_res(chips)',
 P_PATH='@t6g_mb_lib.t6g(sch_1):page334_i89@pure_quanta.q_res(chips)',
 PATH='I89',
 DRAWING='@T6G_MB_LIB.T6G(SCH_1):PAGE443',
 WATTAGE='1/16W',
 TOLERANCE='5%',
 MATERIAL='EMPTY',
 PHYS_PAGE='334',
 XY='(-8125,3900)',
 ROT='0',
 VER='2',
 PACK_TYPE='0402LF',
 LOCATION='R704',
 CDS_LIB='pure_quanta',
 CDS_PART_NAME='Q_RES_0402LF-0,5%,1/16W,EMPTY,CS00002JB13',
 PART_NUMBER='CS00002JB13',
 VALUE='0',
 PRIM_FILE='./archive_libs/logical/q_res/chips/chips.prt';

PART_NAME
 R705 'Q_RES_0603LF-0,5%,1/4W,EMPTY,CS00006J900':;

SECTION_NUMBER 1
 '@T6G_MB_LIB.T6G(SCH_1):PAGE443_I10@PURE_QUANTA.Q_RES(CHIPS)':
 C_PATH='@t6g_mb_lib.t6g(sch_1):page443_i10@pure_quanta.q_res(chips)',
 P_PATH='@t6g_mb_lib.t6g(sch_1):page334_i10@pure_quanta.q_res(chips)',
 PATH='I10',
 DRAWING='@T6G_MB_LIB.T6G(SCH_1):PAGE443',
 WATTAGE='1/4W',
 TOLERANCE='5%',
 MATERIAL='EMPTY',
 PHYS_PAGE='334',
 XY='(-4325,2575)',
 ROT='2',
 VER='2',
 PACK_TYPE='0603LF',
 LOCATION='R705',
 CDS_LIB='pure_quanta',
 CDS_PART_NAME='Q_RES_0603LF-0,5%,1/4W,EMPTY,CS00006J900',
 PART_NUMBER='CS00006J900',
 VALUE='0',
 PRIM_FILE='./archive_libs/logical/q_res/chips/chips.prt';

PART_NAME
 R706 'Q_RES_0201LF-4.7K,5%,1/20W,EMPTY,CS24701JE04':;

SECTION_NUMBER 1
 '@T6G_MB_LIB.T6G(SCH_1):PAGE401_I29@PURE_QUANTA.Q_RES(CHIPS)':
 C_PATH='@t6g_mb_lib.t6g(sch_1):page401_i29@pure_quanta.q_res(chips)',
 P_PATH='@t6g_mb_lib.t6g(sch_1):page320_i29@pure_quanta.q_res(chips)',
 PATH='I29',
 DRAWING='@T6G_MB_LIB.T6G(SCH_1):PAGE401',
 WATTAGE='1/20W',
 TOLERANCE='5%',
 MATERIAL='EMPTY',
 PHYS_PAGE='320',
 XY='(-8950,6100)',
 ROT='0',
 VER='2',
 PACK_TYPE='0201LF',
 LOCATION='R706',
 CDS_LIB='pure_quanta',
 CDS_PART_NAME='Q_RES_0201LF-4.7K,5%,1/20W,EMPTY,CS24701JE04',
 PART_NUMBER='CS24701JE04',
 VALUE='4.7K',
 PRIM_FILE='./archive_libs/logical/q_res/chips/chips.prt';

PART_NAME
 R707 'Q_RES_0201LF-10K,1%,1/20W,CHIP,CS31001FE17':;

SECTION_NUMBER 1
 '@T6G_MB_LIB.T6G(SCH_1):PAGE401_I36@PURE_QUANTA.Q_RES(CHIPS)':
 C_PATH='@t6g_mb_lib.t6g(sch_1):page401_i36@pure_quanta.q_res(chips)',
 P_PATH='@t6g_mb_lib.t6g(sch_1):page320_i36@pure_quanta.q_res(chips)',
 PATH='I36',
 DRAWING='@T6G_MB_LIB.T6G(SCH_1):PAGE401',
 WATTAGE='1/20W',
 TOLERANCE='1%',
 MATERIAL='CHIP',
 PHYS_PAGE='320',
 XY='(-8950,5150)',
 ROT='0',
 VER='2',
 PACK_TYPE='0201LF',
 LOCATION='R707',
 CDS_LIB='pure_quanta',
 CDS_PART_NAME='Q_RES_0201LF-10K,1%,1/20W,CHIP,CS31001FE17',
 PART_NUMBER='CS31001FE17',
 VALUE='10K',
 PRIM_FILE='./archive_libs/logical/q_res/chips/chips.prt';

PART_NAME
 R708 'Q_RES_0402LF-33,5%,1/16W,CHIP,CS03302JB10':;

SECTION_NUMBER 1
 '@T6G_MB_LIB.T6G(SCH_1):PAGE80_I168@PURE_QUANTA.Q_RES(CHIPS)':
 C_PATH='@t6g_mb_lib.t6g(sch_1):page80_i168@pure_quanta.q_res(chips)',
 P_PATH='@t6g_mb_lib.t6g(sch_1):page81_i168@pure_quanta.q_res(chips)',
 PATH='I168',
 DRAWING='@T6G_MB_LIB.T6G(SCH_1):PAGE80',
 BOM_COST='MEM',
 WATTAGE='1/16W',
 TOLERANCE='5%',
 MATERIAL='CHIP',
 PHYS_PAGE='81',
 XY='(-3225,5125)',
 ROT='0',
 VER='1',
 PACK_TYPE='0402LF',
 LOCATION='R708',
 CDS_LIB='pure_quanta',
 CDS_PART_NAME='Q_RES_0402LF-33,5%,1/16W,CHIP,CS03302JB10',
 PART_NUMBER='CS03302JB10',
 VALUE='33',
 PRIM_FILE='./archive_libs/logical/q_res/chips/chips.prt';

PART_NAME
 R709 'Q_RES_0201LF-0,5%,1/20W,CHIP,CS00001JE10':;

SECTION_NUMBER 1
 '@T6G_MB_LIB.T6G(SCH_1):PAGE400_I103@PURE_QUANTA.Q_RES(CHIPS)':
 C_PATH='@t6g_mb_lib.t6g(sch_1):page400_i103@pure_quanta.q_res(chips)',
 P_PATH='@t6g_mb_lib.t6g(sch_1):page321_i103@pure_quanta.q_res(chips)',
 PATH='I103',
 DRAWING='@T6G_MB_LIB.T6G(SCH_1):PAGE400',
 WATTAGE='1/20W',
 TOLERANCE='5%',
 MATERIAL='CHIP',
 PHYS_PAGE='321',
 XY='(-875,1550)',
 ROT='0',
 VER='2',
 PACK_TYPE='0201LF',
 LOCATION='R709',
 CDS_LIB='pure_quanta',
 CDS_PART_NAME='Q_RES_0201LF-0,5%,1/20W,CHIP,CS00001JE10',
 PART_NUMBER='CS00001JE10',
 VALUE='0',
 PRIM_FILE='./archive_libs/logical/q_res/chips/chips.prt';

PART_NAME
 R710 'Q_RES_0402LF-1K,1%,1/16W,CHIP,CS21002FB06':;

SECTION_NUMBER 1
 '@T6G_MB_LIB.T6G(SCH_1):PAGE361_I57@PURE_QUANTA.Q_RES(CHIPS)':
 C_PATH='@t6g_mb_lib.t6g(sch_1):page361_i57@pure_quanta.q_res(chips)',
 P_PATH='@t6g_mb_lib.t6g(sch_1):page238_i57@pure_quanta.q_res(chips)',
 PATH='I57',
 DRAWING='@T6G_MB_LIB.T6G(SCH_1):PAGE361',
 WATTAGE='1/16W',
 TOLERANCE='1%',
 MATERIAL='CHIP',
 PHYS_PAGE='238',
 XY='(-1325,3075)',
 ROT='0',
 VER='2',
 PACK_TYPE='0402LF',
 LOCATION='R710',
 CDS_LIB='pure_quanta',
 CDS_PART_NAME='Q_RES_0402LF-1K,1%,1/16W,CHIP,CS21002FB06',
 PART_NUMBER='CS21002FB06',
 VALUE='1K',
 PRIM_FILE='./archive_libs/logical/q_res/chips/chips.prt';

PART_NAME
 R711 'Q_RES_0201LF-0,5%,1/20W,CHIP,CS00001JE10':;

SECTION_NUMBER 1
 '@T6G_MB_LIB.T6G(SCH_1):PAGE400_I102@PURE_QUANTA.Q_RES(CHIPS)':
 C_PATH='@t6g_mb_lib.t6g(sch_1):page400_i102@pure_quanta.q_res(chips)',
 P_PATH='@t6g_mb_lib.t6g(sch_1):page321_i102@pure_quanta.q_res(chips)',
 PATH='I102',
 DRAWING='@T6G_MB_LIB.T6G(SCH_1):PAGE400',
 WATTAGE='1/20W',
 TOLERANCE='5%',
 MATERIAL='CHIP',
 PHYS_PAGE='321',
 XY='(-725,2100)',
 ROT='0',
 VER='2',
 PACK_TYPE='0201LF',
 LOCATION='R711',
 CDS_LIB='pure_quanta',
 CDS_PART_NAME='Q_RES_0201LF-0,5%,1/20W,CHIP,CS00001JE10',
 PART_NUMBER='CS00001JE10',
 VALUE='0',
 PRIM_FILE='./archive_libs/logical/q_res/chips/chips.prt';

PART_NAME
 R712 'Q_RES_0603LF-0,5%,1/4W,CHIP,CS00006J900':;

SECTION_NUMBER 1
 '@T6G_MB_LIB.T6G(SCH_1):PAGE443_I11@PURE_QUANTA.Q_RES(CHIPS)':
 C_PATH='@t6g_mb_lib.t6g(sch_1):page443_i11@pure_quanta.q_res(chips)',
 P_PATH='@t6g_mb_lib.t6g(sch_1):page334_i11@pure_quanta.q_res(chips)',
 PATH='I11',
 DRAWING='@T6G_MB_LIB.T6G(SCH_1):PAGE443',
 WATTAGE='1/4W',
 TOLERANCE='5%',
 MATERIAL='CHIP',
 PHYS_PAGE='334',
 XY='(-3950,2300)',
 ROT='0',
 VER='1',
 PACK_TYPE='0603LF',
 LOCATION='R712',
 CDS_LIB='pure_quanta',
 CDS_PART_NAME='Q_RES_0603LF-0,5%,1/4W,CHIP,CS00006J900',
 PART_NUMBER='CS00006J900',
 VALUE='0',
 PRIM_FILE='./archive_libs/logical/q_res/chips/chips.prt';

PART_NAME
 R713 'Q_RES_0402LF-10K,1%,1/16W,EMPTY,CS31002FB08':;

SECTION_NUMBER 1
 '@T6G_MB_LIB.T6G(SCH_1):PAGE361_I47@PURE_QUANTA.Q_RES(CHIPS)':
 C_PATH='@t6g_mb_lib.t6g(sch_1):page361_i47@pure_quanta.q_res(chips)',
 P_PATH='@t6g_mb_lib.t6g(sch_1):page238_i47@pure_quanta.q_res(chips)',
 PATH='I47',
 DRAWING='@T6G_MB_LIB.T6G(SCH_1):PAGE361',
 WATTAGE='1/16W',
 TOLERANCE='1%',
 MATERIAL='EMPTY',
 PHYS_PAGE='238',
 XY='(1500,3675)',
 ROT='0',
 VER='2',
 PACK_TYPE='0402LF',
 LOCATION='R713',
 CDS_LIB='pure_quanta',
 CDS_PART_NAME='Q_RES_0402LF-10K,1%,1/16W,EMPTY,CS31002FB08',
 PART_NUMBER='CS31002FB08',
 VALUE='10K',
 PRIM_FILE='./archive_libs/logical/q_res/chips/chips.prt';

PART_NAME
 R714 'Q_RES_0402LF-1K,1%,1/16W,CHIP,CS21002FB06':;

SECTION_NUMBER 1
 '@T6G_MB_LIB.T6G(SCH_1):PAGE361_I52@PURE_QUANTA.Q_RES(CHIPS)':
 C_PATH='@t6g_mb_lib.t6g(sch_1):page361_i52@pure_quanta.q_res(chips)',
 P_PATH='@t6g_mb_lib.t6g(sch_1):page238_i52@pure_quanta.q_res(chips)',
 PATH='I52',
 DRAWING='@T6G_MB_LIB.T6G(SCH_1):PAGE361',
 WATTAGE='1/16W',
 TOLERANCE='1%',
 MATERIAL='CHIP',
 PHYS_PAGE='238',
 XY='(1500,3125)',
 ROT='0',
 VER='2',
 PACK_TYPE='0402LF',
 LOCATION='R714',
 CDS_LIB='pure_quanta',
 CDS_PART_NAME='Q_RES_0402LF-1K,1%,1/16W,CHIP,CS21002FB06',
 PART_NUMBER='CS21002FB06',
 VALUE='1K',
 PRIM_FILE='./archive_libs/logical/q_res/chips/chips.prt';

PART_NAME
 R715 'Q_RES_0201LF-10K,1%,1/20W,CHIP,CS31001FE17':;

SECTION_NUMBER 1
 '@T6G_MB_LIB.T6G(SCH_1):PAGE401_I35@PURE_QUANTA.Q_RES(CHIPS)':
 C_PATH='@t6g_mb_lib.t6g(sch_1):page401_i35@pure_quanta.q_res(chips)',
 P_PATH='@t6g_mb_lib.t6g(sch_1):page320_i35@pure_quanta.q_res(chips)',
 PATH='I35',
 DRAWING='@T6G_MB_LIB.T6G(SCH_1):PAGE401',
 WATTAGE='1/20W',
 TOLERANCE='1%',
 MATERIAL='CHIP',
 PHYS_PAGE='320',
 XY='(-8650,5150)',
 ROT='0',
 VER='2',
 PACK_TYPE='0201LF',
 LOCATION='R715',
 CDS_LIB='pure_quanta',
 CDS_PART_NAME='Q_RES_0201LF-10K,1%,1/20W,CHIP,CS31001FE17',
 PART_NUMBER='CS31001FE17',
 VALUE='10K',
 PRIM_FILE='./archive_libs/logical/q_res/chips/chips.prt';

PART_NAME
 R716 'Q_RES_0201LF-4.7K,5%,1/20W,EMPTY,CS24701JE04':;

SECTION_NUMBER 1
 '@T6G_MB_LIB.T6G(SCH_1):PAGE401_I27@PURE_QUANTA.Q_RES(CHIPS)':
 C_PATH='@t6g_mb_lib.t6g(sch_1):page401_i27@pure_quanta.q_res(chips)',
 P_PATH='@t6g_mb_lib.t6g(sch_1):page320_i27@pure_quanta.q_res(chips)',
 PATH='I27',
 DRAWING='@T6G_MB_LIB.T6G(SCH_1):PAGE401',
 WATTAGE='1/20W',
 TOLERANCE='5%',
 MATERIAL='EMPTY',
 PHYS_PAGE='320',
 XY='(-8325,6100)',
 ROT='0',
 VER='2',
 PACK_TYPE='0201LF',
 LOCATION='R716',
 CDS_LIB='pure_quanta',
 CDS_PART_NAME='Q_RES_0201LF-4.7K,5%,1/20W,EMPTY,CS24701JE04',
 PART_NUMBER='CS24701JE04',
 VALUE='4.7K',
 PRIM_FILE='./archive_libs/logical/q_res/chips/chips.prt';

PART_NAME
 R717 'Q_RES_0402LF-10K,1%,1/16W,EMPTY,CS31002FB08':;

SECTION_NUMBER 1
 '@T6G_MB_LIB.T6G(SCH_1):PAGE361_I45@PURE_QUANTA.Q_RES(CHIPS)':
 C_PATH='@t6g_mb_lib.t6g(sch_1):page361_i45@pure_quanta.q_res(chips)',
 P_PATH='@t6g_mb_lib.t6g(sch_1):page238_i45@pure_quanta.q_res(chips)',
 PATH='I45',
 DRAWING='@T6G_MB_LIB.T6G(SCH_1):PAGE361',
 WATTAGE='1/16W',
 TOLERANCE='1%',
 MATERIAL='EMPTY',
 PHYS_PAGE='238',
 XY='(1775,3675)',
 ROT='0',
 VER='2',
 PACK_TYPE='0402LF',
 LOCATION='R717',
 CDS_LIB='pure_quanta',
 CDS_PART_NAME='Q_RES_0402LF-10K,1%,1/16W,EMPTY,CS31002FB08',
 PART_NUMBER='CS31002FB08',
 VALUE='10K',
 PRIM_FILE='./archive_libs/logical/q_res/chips/chips.prt';

PART_NAME
 R718 'Q_RES_0402LF-1K,1%,1/16W,CHIP,CS21002FB06':;

SECTION_NUMBER 1
 '@T6G_MB_LIB.T6G(SCH_1):PAGE361_I50@PURE_QUANTA.Q_RES(CHIPS)':
 C_PATH='@t6g_mb_lib.t6g(sch_1):page361_i50@pure_quanta.q_res(chips)',
 P_PATH='@t6g_mb_lib.t6g(sch_1):page238_i50@pure_quanta.q_res(chips)',
 PATH='I50',
 DRAWING='@T6G_MB_LIB.T6G(SCH_1):PAGE361',
 WATTAGE='1/16W',
 TOLERANCE='1%',
 MATERIAL='CHIP',
 PHYS_PAGE='238',
 XY='(1775,3125)',
 ROT='0',
 VER='2',
 PACK_TYPE='0402LF',
 LOCATION='R718',
 CDS_LIB='pure_quanta',
 CDS_PART_NAME='Q_RES_0402LF-1K,1%,1/16W,CHIP,CS21002FB06',
 PART_NUMBER='CS21002FB06',
 VALUE='1K',
 PRIM_FILE='./archive_libs/logical/q_res/chips/chips.prt';

PART_NAME
 R719 'Q_RES_0201LF-4.7K,5%,1/20W,CHIP,CS24701JE04':;

SECTION_NUMBER 1
 '@T6G_MB_LIB.T6G(SCH_1):PAGE401_I34@PURE_QUANTA.Q_RES(CHIPS)':
 C_PATH='@t6g_mb_lib.t6g(sch_1):page401_i34@pure_quanta.q_res(chips)',
 P_PATH='@t6g_mb_lib.t6g(sch_1):page320_i34@pure_quanta.q_res(chips)',
 PATH='I34',
 DRAWING='@T6G_MB_LIB.T6G(SCH_1):PAGE401',
 WATTAGE='1/20W',
 TOLERANCE='5%',
 MATERIAL='CHIP',
 PHYS_PAGE='320',
 XY='(-8325,5150)',
 ROT='0',
 VER='2',
 PACK_TYPE='0201LF',
 LOCATION='R719',
 CDS_LIB='pure_quanta',
 CDS_PART_NAME='Q_RES_0201LF-4.7K,5%,1/20W,CHIP,CS24701JE04',
 PART_NUMBER='CS24701JE04',
 VALUE='4.7K',
 PRIM_FILE='./archive_libs/logical/q_res/chips/chips.prt';

PART_NAME
 R720 'Q_RES_0201LF-4.7K,5%,1/20W,EMPTY,CS24701JE04':;

SECTION_NUMBER 1
 '@T6G_MB_LIB.T6G(SCH_1):PAGE401_I26@PURE_QUANTA.Q_RES(CHIPS)':
 C_PATH='@t6g_mb_lib.t6g(sch_1):page401_i26@pure_quanta.q_res(chips)',
 P_PATH='@t6g_mb_lib.t6g(sch_1):page320_i26@pure_quanta.q_res(chips)',
 PATH='I26',
 DRAWING='@T6G_MB_LIB.T6G(SCH_1):PAGE401',
 WATTAGE='1/20W',
 TOLERANCE='5%',
 MATERIAL='EMPTY',
 PHYS_PAGE='320',
 XY='(-8025,6050)',
 ROT='0',
 VER='2',
 PACK_TYPE='0201LF',
 LOCATION='R720',
 CDS_LIB='pure_quanta',
 CDS_PART_NAME='Q_RES_0201LF-4.7K,5%,1/20W,EMPTY,CS24701JE04',
 PART_NUMBER='CS24701JE04',
 VALUE='4.7K',
 PRIM_FILE='./archive_libs/logical/q_res/chips/chips.prt';

PART_NAME
 R721 'Q_RES_0402LF-10K,1%,1/16W,CHIP,CS31002FB08':;

SECTION_NUMBER 1
 '@T6G_MB_LIB.T6G(SCH_1):PAGE361_I62@PURE_QUANTA.Q_RES(CHIPS)':
 C_PATH='@t6g_mb_lib.t6g(sch_1):page361_i62@pure_quanta.q_res(chips)',
 P_PATH='@t6g_mb_lib.t6g(sch_1):page238_i62@pure_quanta.q_res(chips)',
 PATH='I62',
 DRAWING='@T6G_MB_LIB.T6G(SCH_1):PAGE361',
 WATTAGE='1/16W',
 TOLERANCE='1%',
 MATERIAL='CHIP',
 PHYS_PAGE='238',
 XY='(2050,3675)',
 ROT='0',
 VER='2',
 PACK_TYPE='0402LF',
 LOCATION='R721',
 CDS_LIB='pure_quanta',
 CDS_PART_NAME='Q_RES_0402LF-10K,1%,1/16W,CHIP,CS31002FB08',
 PART_NUMBER='CS31002FB08',
 VALUE='10K',
 PRIM_FILE='./archive_libs/logical/q_res/chips/chips.prt';

PART_NAME
 R722 'Q_RES_0402LF-1K,1%,1/16W,EMPTY,CS21002FB06':;

SECTION_NUMBER 1
 '@T6G_MB_LIB.T6G(SCH_1):PAGE361_I61@PURE_QUANTA.Q_RES(CHIPS)':
 C_PATH='@t6g_mb_lib.t6g(sch_1):page361_i61@pure_quanta.q_res(chips)',
 P_PATH='@t6g_mb_lib.t6g(sch_1):page238_i61@pure_quanta.q_res(chips)',
 PATH='I61',
 DRAWING='@T6G_MB_LIB.T6G(SCH_1):PAGE361',
 WATTAGE='1/16W',
 TOLERANCE='1%',
 MATERIAL='EMPTY',
 PHYS_PAGE='238',
 XY='(2050,3125)',
 ROT='0',
 VER='2',
 PACK_TYPE='0402LF',
 LOCATION='R722',
 CDS_LIB='pure_quanta',
 CDS_PART_NAME='Q_RES_0402LF-1K,1%,1/16W,EMPTY,CS21002FB06',
 PART_NUMBER='CS21002FB06',
 VALUE='1K',
 PRIM_FILE='./archive_libs/logical/q_res/chips/chips.prt';

PART_NAME
 R723 'Q_RES_0201LF-4.7K,5%,1/20W,CHIP,CS24701JE04':;

SECTION_NUMBER 1
 '@T6G_MB_LIB.T6G(SCH_1):PAGE401_I33@PURE_QUANTA.Q_RES(CHIPS)':
 C_PATH='@t6g_mb_lib.t6g(sch_1):page401_i33@pure_quanta.q_res(chips)',
 P_PATH='@t6g_mb_lib.t6g(sch_1):page320_i33@pure_quanta.q_res(chips)',
 PATH='I33',
 DRAWING='@T6G_MB_LIB.T6G(SCH_1):PAGE401',
 WATTAGE='1/20W',
 TOLERANCE='5%',
 MATERIAL='CHIP',
 PHYS_PAGE='320',
 XY='(-8025,5125)',
 ROT='0',
 VER='2',
 PACK_TYPE='0201LF',
 LOCATION='R723',
 CDS_LIB='pure_quanta',
 CDS_PART_NAME='Q_RES_0201LF-4.7K,5%,1/20W,CHIP,CS24701JE04',
 PART_NUMBER='CS24701JE04',
 VALUE='4.7K',
 PRIM_FILE='./archive_libs/logical/q_res/chips/chips.prt';

PART_NAME
 R724 'Q_RES_0201LF-4.7K,5%,1/20W,EMPTY,CS24701JE04':;

SECTION_NUMBER 1
 '@T6G_MB_LIB.T6G(SCH_1):PAGE401_I25@PURE_QUANTA.Q_RES(CHIPS)':
 C_PATH='@t6g_mb_lib.t6g(sch_1):page401_i25@pure_quanta.q_res(chips)',
 P_PATH='@t6g_mb_lib.t6g(sch_1):page320_i25@pure_quanta.q_res(chips)',
 PATH='I25',
 DRAWING='@T6G_MB_LIB.T6G(SCH_1):PAGE401',
 WATTAGE='1/20W',
 TOLERANCE='5%',
 MATERIAL='EMPTY',
 PHYS_PAGE='320',
 XY='(-7725,6075)',
 ROT='0',
 VER='2',
 PACK_TYPE='0201LF',
 LOCATION='R724',
 CDS_LIB='pure_quanta',
 CDS_PART_NAME='Q_RES_0201LF-4.7K,5%,1/20W,EMPTY,CS24701JE04',
 PART_NUMBER='CS24701JE04',
 VALUE='4.7K',
 PRIM_FILE='./archive_libs/logical/q_res/chips/chips.prt';

PART_NAME
 R725 'Q_RES_0201LF-4.7K,5%,1/20W,CHIP,CS24701JE04':;

SECTION_NUMBER 1
 '@T6G_MB_LIB.T6G(SCH_1):PAGE401_I32@PURE_QUANTA.Q_RES(CHIPS)':
 C_PATH='@t6g_mb_lib.t6g(sch_1):page401_i32@pure_quanta.q_res(chips)',
 P_PATH='@t6g_mb_lib.t6g(sch_1):page320_i32@pure_quanta.q_res(chips)',
 PATH='I32',
 DRAWING='@T6G_MB_LIB.T6G(SCH_1):PAGE401',
 WATTAGE='1/20W',
 TOLERANCE='5%',
 MATERIAL='CHIP',
 PHYS_PAGE='320',
 XY='(-7725,5125)',
 ROT='0',
 VER='2',
 PACK_TYPE='0201LF',
 LOCATION='R725',
 CDS_LIB='pure_quanta',
 CDS_PART_NAME='Q_RES_0201LF-4.7K,5%,1/20W,CHIP,CS24701JE04',
 PART_NUMBER='CS24701JE04',
 VALUE='4.7K',
 PRIM_FILE='./archive_libs/logical/q_res/chips/chips.prt';

PART_NAME
 R726 'Q_RES_0201LF-4.7K,5%,1/20W,CHIP,CS24701JE04':;

SECTION_NUMBER 1
 '@T6G_MB_LIB.T6G(SCH_1):PAGE401_I90@PURE_QUANTA.Q_RES(CHIPS)':
 C_PATH='@t6g_mb_lib.t6g(sch_1):page401_i90@pure_quanta.q_res(chips)',
 P_PATH='@t6g_mb_lib.t6g(sch_1):page320_i90@pure_quanta.q_res(chips)',
 PATH='I90',
 DRAWING='@T6G_MB_LIB.T6G(SCH_1):PAGE401',
 WATTAGE='1/20W',
 TOLERANCE='5%',
 MATERIAL='CHIP',
 PHYS_PAGE='320',
 XY='(-7425,5100)',
 ROT='0',
 VER='2',
 PACK_TYPE='0201LF',
 LOCATION='R726',
 CDS_LIB='pure_quanta',
 CDS_PART_NAME='Q_RES_0201LF-4.7K,5%,1/20W,CHIP,CS24701JE04',
 PART_NUMBER='CS24701JE04',
 VALUE='4.7K',
 PRIM_FILE='./archive_libs/logical/q_res/chips/chips.prt';

PART_NAME
 R727 'Q_RES_0201LF-4.7K,5%,1/20W,CHIP,CS24701JE04':;

SECTION_NUMBER 1
 '@T6G_MB_LIB.T6G(SCH_1):PAGE401_I54@PURE_QUANTA.Q_RES(CHIPS)':
 C_PATH='@t6g_mb_lib.t6g(sch_1):page401_i54@pure_quanta.q_res(chips)',
 P_PATH='@t6g_mb_lib.t6g(sch_1):page320_i54@pure_quanta.q_res(chips)',
 PATH='I54',
 DRAWING='@T6G_MB_LIB.T6G(SCH_1):PAGE401',
 WATTAGE='1/20W',
 TOLERANCE='5%',
 MATERIAL='CHIP',
 PHYS_PAGE='320',
 XY='(-5025,6175)',
 ROT='0',
 VER='2',
 PACK_TYPE='0201LF',
 LOCATION='R727',
 CDS_LIB='pure_quanta',
 CDS_PART_NAME='Q_RES_0201LF-4.7K,5%,1/20W,CHIP,CS24701JE04',
 PART_NUMBER='CS24701JE04',
 VALUE='4.7K',
 PRIM_FILE='./archive_libs/logical/q_res/chips/chips.prt';

PART_NAME
 R728 'Q_RES_0201LF-4.7K,5%,1/20W,EMPTY,CS24701JE04':;

SECTION_NUMBER 1
 '@T6G_MB_LIB.T6G(SCH_1):PAGE401_I55@PURE_QUANTA.Q_RES(CHIPS)':
 C_PATH='@t6g_mb_lib.t6g(sch_1):page401_i55@pure_quanta.q_res(chips)',
 P_PATH='@t6g_mb_lib.t6g(sch_1):page320_i55@pure_quanta.q_res(chips)',
 PATH='I55',
 DRAWING='@T6G_MB_LIB.T6G(SCH_1):PAGE401',
 WATTAGE='1/20W',
 TOLERANCE='5%',
 MATERIAL='EMPTY',
 PHYS_PAGE='320',
 XY='(-5025,5650)',
 ROT='0',
 VER='2',
 PACK_TYPE='0201LF',
 LOCATION='R728',
 CDS_LIB='pure_quanta',
 CDS_PART_NAME='Q_RES_0201LF-4.7K,5%,1/20W,EMPTY,CS24701JE04',
 PART_NUMBER='CS24701JE04',
 VALUE='4.7K',
 PRIM_FILE='./archive_libs/logical/q_res/chips/chips.prt';

PART_NAME
 R729 'Q_RES_0402LF-10K,5%,1/16W,EMPTY,CS31002JB08':;

SECTION_NUMBER 1
 '@T6G_MB_LIB.T6G(SCH_1):PAGE75_I41@PURE_QUANTA.Q_RES(CHIPS)':
 C_PATH='@t6g_mb_lib.t6g(sch_1):page75_i41@pure_quanta.q_res(chips)',
 P_PATH='@t6g_mb_lib.t6g(sch_1):page76_i41@pure_quanta.q_res(chips)',
 PATH='I41',
 DRAWING='@T6G_MB_LIB.T6G(SCH_1):PAGE75',
 WATTAGE='1/16W',
 TOLERANCE='5%',
 MATERIAL='EMPTY',
 PHYS_PAGE='76',
 XY='(-8650,5450)',
 ROT='0',
 VER='1',
 PACK_TYPE='0402LF',
 LOCATION='R729',
 CDS_LIB='pure_quanta',
 CDS_PART_NAME='Q_RES_0402LF-10K,5%,1/16W,EMPTY,CS31002JB08',
 PART_NUMBER='CS31002JB08',
 VALUE='10K',
 PRIM_FILE='./archive_libs/logical/q_res/chips/chips.prt';

PART_NAME
 R730 'Q_RES_0402LF-10K,5%,1/16W,CHIP,CS31002JB08':;

SECTION_NUMBER 1
 '@T6G_MB_LIB.T6G(SCH_1):PAGE75_I87@PURE_QUANTA.Q_RES(CHIPS)':
 C_PATH='@t6g_mb_lib.t6g(sch_1):page75_i87@pure_quanta.q_res(chips)',
 P_PATH='@t6g_mb_lib.t6g(sch_1):page76_i87@pure_quanta.q_res(chips)',
 PATH='I87',
 DRAWING='@T6G_MB_LIB.T6G(SCH_1):PAGE75',
 WATTAGE='1/16W',
 TOLERANCE='5%',
 MATERIAL='CHIP',
 PHYS_PAGE='76',
 XY='(-3950,5550)',
 ROT='0',
 VER='1',
 PACK_TYPE='0402LF',
 LOCATION='R730',
 CDS_LIB='pure_quanta',
 CDS_PART_NAME='Q_RES_0402LF-10K,5%,1/16W,CHIP,CS31002JB08',
 PART_NUMBER='CS31002JB08',
 VALUE='10K',
 PRIM_FILE='./archive_libs/logical/q_res/chips/chips.prt';

PART_NAME
 R731 'Q_RES_0201LF-0,5%,1/20W,CHIP,CS00001JE10':;

SECTION_NUMBER 1
 '@T6G_MB_LIB.T6G(SCH_1):PAGE392_I70@PURE_QUANTA.Q_RES(CHIPS)':
 C_PATH='@t6g_mb_lib.t6g(sch_1):page392_i70@pure_quanta.q_res(chips)',
 P_PATH='@t6g_mb_lib.t6g(sch_1):page331_i70@pure_quanta.q_res(chips)',
 PATH='I70',
 DRAWING='@T6G_MB_LIB.T6G(SCH_1):PAGE392',
 SEC_TYPE='0201LF',
 WATTAGE='1/20W',
 TOLERANCE='5%',
 MATERIAL='CHIP',
 PHYS_PAGE='331',
 XY='(-2425,2050)',
 ROT='0',
 VER='1',
 PACK_TYPE='0201LF',
 LOCATION='R731',
 SEC='1',
 CDS_LIB='pure_quanta',
 CDS_PART_NAME='Q_RES_0201LF-0,5%,1/20W,CHIP,CS00001JE10',
 PART_NUMBER='CS00001JE10',
 VALUE='0',
 PRIM_FILE='./archive_libs/logical/q_res/chips/chips.prt';

PART_NAME
 R732 'Q_RES_0201LF-0,5%,1/20W,CHIP,CS00001JE10':;

SECTION_NUMBER 1
 '@T6G_MB_LIB.T6G(SCH_1):PAGE392_I71@PURE_QUANTA.Q_RES(CHIPS)':
 C_PATH='@t6g_mb_lib.t6g(sch_1):page392_i71@pure_quanta.q_res(chips)',
 P_PATH='@t6g_mb_lib.t6g(sch_1):page331_i71@pure_quanta.q_res(chips)',
 PATH='I71',
 DRAWING='@T6G_MB_LIB.T6G(SCH_1):PAGE392',
 WATTAGE='1/20W',
 TOLERANCE='5%',
 MATERIAL='CHIP',
 PHYS_PAGE='331',
 XY='(-2425,1950)',
 ROT='0',
 VER='1',
 PACK_TYPE='0201LF',
 LOCATION='R732',
 CDS_LIB='pure_quanta',
 CDS_PART_NAME='Q_RES_0201LF-0,5%,1/20W,CHIP,CS00001JE10',
 PART_NUMBER='CS00001JE10',
 VALUE='0',
 PRIM_FILE='./archive_libs/logical/q_res/chips/chips.prt';

PART_NAME
 R733 'Q_RES_0402LF-100,1%,1/16W,EMPTY,CS11002FB07':;

SECTION_NUMBER 1
 '@T6G_MB_LIB.T6G(SCH_1):PAGE144_I50@PURE_QUANTA.Q_RES(CHIPS)':
 C_PATH='@t6g_mb_lib.t6g(sch_1):page144_i50@pure_quanta.q_res(chips)',
 P_PATH='@t6g_mb_lib.t6g(sch_1):page167_i50@pure_quanta.q_res(chips)',
 PATH='I50',
 DRAWING='@T6G_MB_LIB.T6G(SCH_1):PAGE144',
 WATTAGE='1/16W',
 TOLERANCE='1%',
 MATERIAL='EMPTY',
 PHYS_PAGE='167',
 XY='(-4800,4250)',
 ROT='0',
 VER='2',
 PACK_TYPE='0402LF',
 LOCATION='R733',
 CDS_LIB='pure_quanta',
 CDS_PART_NAME='Q_RES_0402LF-100,1%,1/16W,EMPTY,CS11002FB07',
 PART_NUMBER='CS11002FB07',
 VALUE='100',
 PRIM_FILE='./archive_libs/logical/q_res/chips/chips.prt';

PART_NAME
 R734 'Q_RES_0402LF-0,5%,1/16W,CHIP,CS00002JB13':;

SECTION_NUMBER 1
 '@T6G_MB_LIB.T6G(SCH_1):PAGE144_I19@PURE_QUANTA.Q_RES(CHIPS)':
 C_PATH='@t6g_mb_lib.t6g(sch_1):page144_i19@pure_quanta.q_res(chips)',
 P_PATH='@t6g_mb_lib.t6g(sch_1):page167_i19@pure_quanta.q_res(chips)',
 PATH='I19',
 DRAWING='@T6G_MB_LIB.T6G(SCH_1):PAGE144',
 BOM_COST='MEM',
 WATTAGE='1/16W',
 TOLERANCE='5%',
 MATERIAL='CHIP',
 PHYS_PAGE='167',
 XY='(-7600,525)',
 ROT='0',
 VER='1',
 PACK_TYPE='0402LF',
 LOCATION='R734',
 CDS_LIB='pure_quanta',
 CDS_PART_NAME='Q_RES_0402LF-0,5%,1/16W,CHIP,CS00002JB13',
 PART_NUMBER='CS00002JB13',
 VALUE='0',
 PRIM_FILE='./archive_libs/logical/q_res/chips/chips.prt';

PART_NAME
 R735 'Q_RES_0201LF-1K,1%,1/20W,CHIP,CS21001FE07':;

SECTION_NUMBER 1
 '@T6G_MB_LIB.T6G(SCH_1):PAGE392_I103@PURE_QUANTA.Q_RES(CHIPS)':
 C_PATH='@t6g_mb_lib.t6g(sch_1):page392_i103@pure_quanta.q_res(chips)',
 P_PATH='@t6g_mb_lib.t6g(sch_1):page331_i103@pure_quanta.q_res(chips)',
 PATH='I103',
 DRAWING='@T6G_MB_LIB.T6G(SCH_1):PAGE392',
 WATTAGE='1/20W',
 TOLERANCE='1%',
 MATERIAL='CHIP',
 PHYS_PAGE='331',
 XY='(-3475,5950)',
 ROT='0',
 VER='2',
 PACK_TYPE='0201LF',
 LOCATION='R735',
 CDS_LIB='pure_quanta',
 CDS_PART_NAME='Q_RES_0201LF-1K,1%,1/20W,CHIP,CS21001FE07',
 PART_NUMBER='CS21001FE07',
 VALUE='1K',
 PRIM_FILE='./archive_libs/logical/q_res/chips/chips.prt';

PART_NAME
 R736 'Q_RES_0402LF-10K,5%,1/16W,EMPTY,CS31002JB08':;

SECTION_NUMBER 1
 '@T6G_MB_LIB.T6G(SCH_1):PAGE75_I89@PURE_QUANTA.Q_RES(CHIPS)':
 C_PATH='@t6g_mb_lib.t6g(sch_1):page75_i89@pure_quanta.q_res(chips)',
 P_PATH='@t6g_mb_lib.t6g(sch_1):page76_i89@pure_quanta.q_res(chips)',
 PATH='I89',
 DRAWING='@T6G_MB_LIB.T6G(SCH_1):PAGE75',
 WATTAGE='1/16W',
 TOLERANCE='5%',
 MATERIAL='EMPTY',
 PHYS_PAGE='76',
 XY='(-3975,5275)',
 ROT='0',
 VER='1',
 PACK_TYPE='0402LF',
 LOCATION='R736',
 CDS_LIB='pure_quanta',
 CDS_PART_NAME='Q_RES_0402LF-10K,5%,1/16W,EMPTY,CS31002JB08',
 PART_NUMBER='CS31002JB08',
 VALUE='10K',
 PRIM_FILE='./archive_libs/logical/q_res/chips/chips.prt';

PART_NAME
 R737 'Q_RES_0402LF-10K,5%,1/16W,CHIP,CS31002JB08':;

SECTION_NUMBER 1
 '@T6G_MB_LIB.T6G(SCH_1):PAGE75_I43@PURE_QUANTA.Q_RES(CHIPS)':
 C_PATH='@t6g_mb_lib.t6g(sch_1):page75_i43@pure_quanta.q_res(chips)',
 P_PATH='@t6g_mb_lib.t6g(sch_1):page76_i43@pure_quanta.q_res(chips)',
 PATH='I43',
 DRAWING='@T6G_MB_LIB.T6G(SCH_1):PAGE75',
 WATTAGE='1/16W',
 TOLERANCE='5%',
 MATERIAL='CHIP',
 PHYS_PAGE='76',
 XY='(-8625,5175)',
 ROT='0',
 VER='1',
 PACK_TYPE='0402LF',
 LOCATION='R737',
 CDS_LIB='pure_quanta',
 CDS_PART_NAME='Q_RES_0402LF-10K,5%,1/16W,CHIP,CS31002JB08',
 PART_NUMBER='CS31002JB08',
 VALUE='10K',
 PRIM_FILE='./archive_libs/logical/q_res/chips/chips.prt';

PART_NAME
 R738 'Q_RES_0402LF-33,5%,1/16W,CHIP,CS03302JB10':;

SECTION_NUMBER 1
 '@T6G_MB_LIB.T6G(SCH_1):PAGE56_I11@PURE_QUANTA.Q_RES(CHIPS)':
 C_PATH='@t6g_mb_lib.t6g(sch_1):page56_i11@pure_quanta.q_res(chips)',
 P_PATH='@t6g_mb_lib.t6g(sch_1):page56_i11@pure_quanta.q_res(chips)',
 PATH='I11',
 DRAWING='@T6G_MB_LIB.T6G(SCH_1):PAGE56',
 WATTAGE='1/16W',
 TOLERANCE='5%',
 MATERIAL='CHIP',
 PHYS_PAGE='56',
 XY='(-6800,5500)',
 ROT='0',
 VER='1',
 PACK_TYPE='0402LF',
 LOCATION='R738',
 CDS_LIB='pure_quanta',
 CDS_PART_NAME='Q_RES_0402LF-33,5%,1/16W,CHIP,CS03302JB10',
 PART_NUMBER='CS03302JB10',
 VALUE='33',
 PRIM_FILE='./archive_libs/logical/q_res/chips/chips.prt';

PART_NAME
 R739 'Q_RES_0402LF-10K,5%,1/16W,EMPTY,CS31002JB08':;

SECTION_NUMBER 1
 '@T6G_MB_LIB.T6G(SCH_1):PAGE75_I45@PURE_QUANTA.Q_RES(CHIPS)':
 C_PATH='@t6g_mb_lib.t6g(sch_1):page75_i45@pure_quanta.q_res(chips)',
 P_PATH='@t6g_mb_lib.t6g(sch_1):page76_i45@pure_quanta.q_res(chips)',
 PATH='I45',
 DRAWING='@T6G_MB_LIB.T6G(SCH_1):PAGE75',
 WATTAGE='1/16W',
 TOLERANCE='5%',
 MATERIAL='EMPTY',
 PHYS_PAGE='76',
 XY='(-8625,4925)',
 ROT='0',
 VER='1',
 PACK_TYPE='0402LF',
 LOCATION='R739',
 CDS_LIB='pure_quanta',
 CDS_PART_NAME='Q_RES_0402LF-10K,5%,1/16W,EMPTY,CS31002JB08',
 PART_NUMBER='CS31002JB08',
 VALUE='10K',
 PRIM_FILE='./archive_libs/logical/q_res/chips/chips.prt';

PART_NAME
 R740 'Q_RES_0402LF-10K,5%,1/16W,EMPTY,CS31002JB08':;

SECTION_NUMBER 1
 '@T6G_MB_LIB.T6G(SCH_1):PAGE75_I44@PURE_QUANTA.Q_RES(CHIPS)':
 C_PATH='@t6g_mb_lib.t6g(sch_1):page75_i44@pure_quanta.q_res(chips)',
 P_PATH='@t6g_mb_lib.t6g(sch_1):page76_i44@pure_quanta.q_res(chips)',
 PATH='I44',
 DRAWING='@T6G_MB_LIB.T6G(SCH_1):PAGE75',
 WATTAGE='1/16W',
 TOLERANCE='5%',
 MATERIAL='EMPTY',
 PHYS_PAGE='76',
 XY='(-8625,4800)',
 ROT='0',
 VER='1',
 PACK_TYPE='0402LF',
 LOCATION='R740',
 CDS_LIB='pure_quanta',
 CDS_PART_NAME='Q_RES_0402LF-10K,5%,1/16W,EMPTY,CS31002JB08',
 PART_NUMBER='CS31002JB08',
 VALUE='10K',
 PRIM_FILE='./archive_libs/logical/q_res/chips/chips.prt';

PART_NAME
 R741 'Q_RES_0201LF-1K,1%,1/20W,EMPTY,CS21001FE07':;

SECTION_NUMBER 1
 '@T6G_MB_LIB.T6G(SCH_1):PAGE392_I101@PURE_QUANTA.Q_RES(CHIPS)':
 C_PATH='@t6g_mb_lib.t6g(sch_1):page392_i101@pure_quanta.q_res(chips)',
 P_PATH='@t6g_mb_lib.t6g(sch_1):page331_i101@pure_quanta.q_res(chips)',
 PATH='I101',
 DRAWING='@T6G_MB_LIB.T6G(SCH_1):PAGE392',
 WATTAGE='1/20W',
 TOLERANCE='1%',
 MATERIAL='EMPTY',
 PHYS_PAGE='331',
 XY='(-3475,5175)',
 ROT='0',
 VER='2',
 PACK_TYPE='0201LF',
 LOCATION='R741',
 CDS_LIB='pure_quanta',
 CDS_PART_NAME='Q_RES_0201LF-1K,1%,1/20W,EMPTY,CS21001FE07',
 PART_NUMBER='CS21001FE07',
 VALUE='1K',
 PRIM_FILE='./archive_libs/logical/q_res/chips/chips.prt';

PART_NAME
 R742 'Q_RES_0402LF-10K,5%,1/16W,EMPTY,CS31002JB08':;

SECTION_NUMBER 1
 '@T6G_MB_LIB.T6G(SCH_1):PAGE75_I46@PURE_QUANTA.Q_RES(CHIPS)':
 C_PATH='@t6g_mb_lib.t6g(sch_1):page75_i46@pure_quanta.q_res(chips)',
 P_PATH='@t6g_mb_lib.t6g(sch_1):page76_i46@pure_quanta.q_res(chips)',
 PATH='I46',
 DRAWING='@T6G_MB_LIB.T6G(SCH_1):PAGE75',
 WATTAGE='1/16W',
 TOLERANCE='5%',
 MATERIAL='EMPTY',
 PHYS_PAGE='76',
 XY='(-8625,4550)',
 ROT='0',
 VER='1',
 PACK_TYPE='0402LF',
 LOCATION='R742',
 CDS_LIB='pure_quanta',
 CDS_PART_NAME='Q_RES_0402LF-10K,5%,1/16W,EMPTY,CS31002JB08',
 PART_NUMBER='CS31002JB08',
 VALUE='10K',
 PRIM_FILE='./archive_libs/logical/q_res/chips/chips.prt';

PART_NAME
 R743 'Q_RES_0402LF-10K,5%,1/16W,CHIP,CS31002JB08':;

SECTION_NUMBER 1
 '@T6G_MB_LIB.T6G(SCH_1):PAGE75_I97@PURE_QUANTA.Q_RES(CHIPS)':
 C_PATH='@t6g_mb_lib.t6g(sch_1):page75_i97@pure_quanta.q_res(chips)',
 P_PATH='@t6g_mb_lib.t6g(sch_1):page76_i97@pure_quanta.q_res(chips)',
 PATH='I97',
 DRAWING='@T6G_MB_LIB.T6G(SCH_1):PAGE75',
 WATTAGE='1/16W',
 TOLERANCE='5%',
 MATERIAL='CHIP',
 PHYS_PAGE='76',
 XY='(-8625,5725)',
 ROT='0',
 VER='1',
 PACK_TYPE='0402LF',
 LOCATION='R743',
 CDS_LIB='pure_quanta',
 CDS_PART_NAME='Q_RES_0402LF-10K,5%,1/16W,CHIP,CS31002JB08',
 PART_NUMBER='CS31002JB08',
 VALUE='10K',
 PRIM_FILE='./archive_libs/logical/q_res/chips/chips.prt';

PART_NAME
 R744 'Q_RES_0402LF-0,5%,1/16W,CHIP,CS00002JB13':;

SECTION_NUMBER 1
 '@T6G_MB_LIB.T6G(SCH_1):PAGE144_I17@PURE_QUANTA.Q_RES(CHIPS)':
 C_PATH='@t6g_mb_lib.t6g(sch_1):page144_i17@pure_quanta.q_res(chips)',
 P_PATH='@t6g_mb_lib.t6g(sch_1):page167_i17@pure_quanta.q_res(chips)',
 PATH='I17',
 DRAWING='@T6G_MB_LIB.T6G(SCH_1):PAGE144',
 BOM_COST='MEM',
 WATTAGE='1/16W',
 TOLERANCE='5%',
 MATERIAL='CHIP',
 PHYS_PAGE='167',
 XY='(-7600,300)',
 ROT='0',
 VER='1',
 PACK_TYPE='0402LF',
 LOCATION='R744',
 CDS_LIB='pure_quanta',
 CDS_PART_NAME='Q_RES_0402LF-0,5%,1/16W,CHIP,CS00002JB13',
 PART_NUMBER='CS00002JB13',
 VALUE='0',
 PRIM_FILE='./archive_libs/logical/q_res/chips/chips.prt';

PART_NAME
 R745 'Q_RES_0201LF-1K,1%,1/20W,EMPTY,CS21001FE07':;

SECTION_NUMBER 1
 '@T6G_MB_LIB.T6G(SCH_1):PAGE392_I104@PURE_QUANTA.Q_RES(CHIPS)':
 C_PATH='@t6g_mb_lib.t6g(sch_1):page392_i104@pure_quanta.q_res(chips)',
 P_PATH='@t6g_mb_lib.t6g(sch_1):page331_i104@pure_quanta.q_res(chips)',
 PATH='I104',
 DRAWING='@T6G_MB_LIB.T6G(SCH_1):PAGE392',
 WATTAGE='1/20W',
 TOLERANCE='1%',
 MATERIAL='EMPTY',
 PHYS_PAGE='331',
 XY='(-3175,5950)',
 ROT='0',
 VER='2',
 PACK_TYPE='0201LF',
 LOCATION='R745',
 CDS_LIB='pure_quanta',
 CDS_PART_NAME='Q_RES_0201LF-1K,1%,1/20W,EMPTY,CS21001FE07',
 PART_NUMBER='CS21001FE07',
 VALUE='1K',
 PRIM_FILE='./archive_libs/logical/q_res/chips/chips.prt';

PART_NAME
 R746 'Q_RES_0201LF-20K,1%,1/20W,CHIP,CS32001FE00':;

SECTION_NUMBER 1
 '@T6G_MB_LIB.T6G(SCH_1):PAGE392_I102@PURE_QUANTA.Q_RES(CHIPS)':
 C_PATH='@t6g_mb_lib.t6g(sch_1):page392_i102@pure_quanta.q_res(chips)',
 P_PATH='@t6g_mb_lib.t6g(sch_1):page331_i102@pure_quanta.q_res(chips)',
 PATH='I102',
 DRAWING='@T6G_MB_LIB.T6G(SCH_1):PAGE392',
 WATTAGE='1/20W',
 TOLERANCE='1%',
 MATERIAL='CHIP',
 PHYS_PAGE='331',
 XY='(-3175,5175)',
 ROT='0',
 VER='2',
 PACK_TYPE='0201LF',
 LOCATION='R746',
 CDS_LIB='pure_quanta',
 CDS_PART_NAME='Q_RES_0201LF-20K,1%,1/20W,CHIP,CS32001FE00',
 PART_NUMBER='CS32001FE00',
 VALUE='20K',
 PRIM_FILE='./archive_libs/logical/q_res/chips/chips.prt';

PART_NAME
 R747 'Q_RES_0402LF-1K,1%,1/16W,CHIP,CS21002FB06':;

SECTION_NUMBER 1
 '@T6G_MB_LIB.T6G(SCH_1):PAGE75_I8@PURE_QUANTA.Q_RES(CHIPS)':
 C_PATH='@t6g_mb_lib.t6g(sch_1):page75_i8@pure_quanta.q_res(chips)',
 P_PATH='@t6g_mb_lib.t6g(sch_1):page76_i8@pure_quanta.q_res(chips)',
 PATH='I8',
 DRAWING='@T6G_MB_LIB.T6G(SCH_1):PAGE75',
 WATTAGE='1/16W',
 TOLERANCE='1%',
 MATERIAL='CHIP',
 PHYS_PAGE='76',
 XY='(-8650,4250)',
 ROT='0',
 VER='1',
 PACK_TYPE='0402LF',
 LOCATION='R747',
 CDS_LIB='pure_quanta',
 CDS_PART_NAME='Q_RES_0402LF-1K,1%,1/16W,CHIP,CS21002FB06',
 PART_NUMBER='CS21002FB06',
 VALUE='1K',
 PRIM_FILE='./archive_libs/logical/q_res/chips/chips.prt';

PART_NAME
 R748 'Q_RES_0402LF-10K,5%,1/16W,EMPTY,CS31002JB08':;

SECTION_NUMBER 1
 '@T6G_MB_LIB.T6G(SCH_1):PAGE75_I9@PURE_QUANTA.Q_RES(CHIPS)':
 C_PATH='@t6g_mb_lib.t6g(sch_1):page75_i9@pure_quanta.q_res(chips)',
 P_PATH='@t6g_mb_lib.t6g(sch_1):page76_i9@pure_quanta.q_res(chips)',
 PATH='I9',
 DRAWING='@T6G_MB_LIB.T6G(SCH_1):PAGE75',
 WATTAGE='1/16W',
 TOLERANCE='5%',
 MATERIAL='EMPTY',
 PHYS_PAGE='76',
 XY='(-8650,3975)',
 ROT='0',
 VER='1',
 PACK_TYPE='0402LF',
 LOCATION='R748',
 CDS_LIB='pure_quanta',
 CDS_PART_NAME='Q_RES_0402LF-10K,5%,1/16W,EMPTY,CS31002JB08',
 PART_NUMBER='CS31002JB08',
 VALUE='10K',
 PRIM_FILE='./archive_libs/logical/q_res/chips/chips.prt';

PART_NAME
 R749 'Q_RES_0201LF-10K,1%,1/20W,CHIP,CS31001FE17':;

SECTION_NUMBER 1
 '@T6G_MB_LIB.T6G(SCH_1):PAGE392_I93@PURE_QUANTA.Q_RES(CHIPS)':
 C_PATH='@t6g_mb_lib.t6g(sch_1):page392_i93@pure_quanta.q_res(chips)',
 P_PATH='@t6g_mb_lib.t6g(sch_1):page331_i93@pure_quanta.q_res(chips)',
 PATH='I93',
 DRAWING='@T6G_MB_LIB.T6G(SCH_1):PAGE392',
 WATTAGE='1/20W',
 TOLERANCE='1%',
 MATERIAL='CHIP',
 PHYS_PAGE='331',
 XY='(-1150,5075)',
 ROT='0',
 VER='2',
 PACK_TYPE='0201LF',
 LOCATION='R749',
 CDS_LIB='pure_quanta',
 CDS_PART_NAME='Q_RES_0201LF-10K,1%,1/20W,CHIP,CS31001FE17',
 PART_NUMBER='CS31001FE17',
 VALUE='10K',
 PRIM_FILE='./archive_libs/logical/q_res/chips/chips.prt';

PART_NAME
 R750 'Q_RES_0402LF-30K,1%,1/16W,CHIP,CS33002FB02':;

SECTION_NUMBER 1
 '@T6G_MB_LIB.T6G(SCH_1):PAGE75_I74@PURE_QUANTA.Q_RES(CHIPS)':
 C_PATH='@t6g_mb_lib.t6g(sch_1):page75_i74@pure_quanta.q_res(chips)',
 P_PATH='@t6g_mb_lib.t6g(sch_1):page76_i74@pure_quanta.q_res(chips)',
 PATH='I74',
 DRAWING='@T6G_MB_LIB.T6G(SCH_1):PAGE75',
 WATTAGE='1/16W',
 TOLERANCE='1%',
 MATERIAL='CHIP',
 PHYS_PAGE='76',
 XY='(-8650,3725)',
 ROT='0',
 VER='1',
 PACK_TYPE='0402LF',
 LOCATION='R750',
 CDS_LIB='pure_quanta',
 CDS_PART_NAME='Q_RES_0402LF-30K,1%,1/16W,CHIP,CS33002FB02',
 PART_NUMBER='CS33002FB02',
 VALUE='30K',
 PRIM_FILE='./archive_libs/logical/q_res/chips/chips.prt';

PART_NAME
 R751 'Q_RES_0402LF-10K,5%,1/16W,CHIP,CS31002JB08':;

SECTION_NUMBER 1
 '@T6G_MB_LIB.T6G(SCH_1):PAGE75_I12@PURE_QUANTA.Q_RES(CHIPS)':
 C_PATH='@t6g_mb_lib.t6g(sch_1):page75_i12@pure_quanta.q_res(chips)',
 P_PATH='@t6g_mb_lib.t6g(sch_1):page76_i12@pure_quanta.q_res(chips)',
 PATH='I12',
 DRAWING='@T6G_MB_LIB.T6G(SCH_1):PAGE75',
 WATTAGE='1/16W',
 TOLERANCE='5%',
 MATERIAL='CHIP',
 PHYS_PAGE='76',
 XY='(-8650,3600)',
 ROT='0',
 VER='1',
 PACK_TYPE='0402LF',
 LOCATION='R751',
 CDS_LIB='pure_quanta',
 CDS_PART_NAME='Q_RES_0402LF-10K,5%,1/16W,CHIP,CS31002JB08',
 PART_NUMBER='CS31002JB08',
 VALUE='10K',
 PRIM_FILE='./archive_libs/logical/q_res/chips/chips.prt';

PART_NAME
 R752 'Q_RES_0201LF-10K,1%,1/20W,CHIP,CS31001FE17':;

SECTION_NUMBER 1
 '@T6G_MB_LIB.T6G(SCH_1):PAGE392_I92@PURE_QUANTA.Q_RES(CHIPS)':
 C_PATH='@t6g_mb_lib.t6g(sch_1):page392_i92@pure_quanta.q_res(chips)',
 P_PATH='@t6g_mb_lib.t6g(sch_1):page331_i92@pure_quanta.q_res(chips)',
 PATH='I92',
 DRAWING='@T6G_MB_LIB.T6G(SCH_1):PAGE392',
 WATTAGE='1/20W',
 TOLERANCE='1%',
 MATERIAL='CHIP',
 PHYS_PAGE='331',
 XY='(-1325,5075)',
 ROT='2',
 VER='2',
 PACK_TYPE='0201LF',
 LOCATION='R752',
 CDS_LIB='pure_quanta',
 CDS_PART_NAME='Q_RES_0201LF-10K,1%,1/20W,CHIP,CS31001FE17',
 PART_NUMBER='CS31001FE17',
 VALUE='10K',
 PRIM_FILE='./archive_libs/logical/q_res/chips/chips.prt';

PART_NAME
 R753 'Q_RES_0402LF-10K,5%,1/16W,CHIP,CS31002JB08':;

SECTION_NUMBER 1
 '@T6G_MB_LIB.T6G(SCH_1):PAGE75_I75@PURE_QUANTA.Q_RES(CHIPS)':
 C_PATH='@t6g_mb_lib.t6g(sch_1):page75_i75@pure_quanta.q_res(chips)',
 P_PATH='@t6g_mb_lib.t6g(sch_1):page76_i75@pure_quanta.q_res(chips)',
 PATH='I75',
 DRAWING='@T6G_MB_LIB.T6G(SCH_1):PAGE75',
 WATTAGE='1/16W',
 TOLERANCE='5%',
 MATERIAL='CHIP',
 PHYS_PAGE='76',
 XY='(-8650,3350)',
 ROT='0',
 VER='1',
 PACK_TYPE='0402LF',
 LOCATION='R753',
 CDS_LIB='pure_quanta',
 CDS_PART_NAME='Q_RES_0402LF-10K,5%,1/16W,CHIP,CS31002JB08',
 PART_NUMBER='CS31002JB08',
 VALUE='10K',
 PRIM_FILE='./archive_libs/logical/q_res/chips/chips.prt';

PART_NAME
 R754 'Q_RES_0402LF-10K,5%,1/16W,EMPTY,CS31002JB08':;

SECTION_NUMBER 1
 '@T6G_MB_LIB.T6G(SCH_1):PAGE75_I91@PURE_QUANTA.Q_RES(CHIPS)':
 C_PATH='@t6g_mb_lib.t6g(sch_1):page75_i91@pure_quanta.q_res(chips)',
 P_PATH='@t6g_mb_lib.t6g(sch_1):page76_i91@pure_quanta.q_res(chips)',
 PATH='I91',
 DRAWING='@T6G_MB_LIB.T6G(SCH_1):PAGE75',
 WATTAGE='1/16W',
 TOLERANCE='5%',
 MATERIAL='EMPTY',
 PHYS_PAGE='76',
 XY='(-3925,4650)',
 ROT='0',
 VER='1',
 PACK_TYPE='0402LF',
 LOCATION='R754',
 CDS_LIB='pure_quanta',
 CDS_PART_NAME='Q_RES_0402LF-10K,5%,1/16W,EMPTY,CS31002JB08',
 PART_NUMBER='CS31002JB08',
 VALUE='10K',
 PRIM_FILE='./archive_libs/logical/q_res/chips/chips.prt';

PART_NAME
 R755 'Q_RES_0201LF-4.7K,5%,1/20W,EMPTY,CS24701JE04':;

SECTION_NUMBER 1
 '@T6G_MB_LIB.T6G(SCH_1):PAGE392_I19@PURE_QUANTA.Q_RES(CHIPS)':
 C_PATH='@t6g_mb_lib.t6g(sch_1):page392_i19@pure_quanta.q_res(chips)',
 P_PATH='@t6g_mb_lib.t6g(sch_1):page331_i19@pure_quanta.q_res(chips)',
 PATH='I19',
 DRAWING='@T6G_MB_LIB.T6G(SCH_1):PAGE392',
 WATTAGE='1/20W',
 TOLERANCE='5%',
 MATERIAL='EMPTY',
 PHYS_PAGE='331',
 XY='(-8825,3975)',
 ROT='0',
 VER='2',
 PACK_TYPE='0201LF',
 LOCATION='R755',
 CDS_LIB='pure_quanta',
 CDS_PART_NAME='Q_RES_0201LF-4.7K,5%,1/20W,EMPTY,CS24701JE04',
 PART_NUMBER='CS24701JE04',
 VALUE='4.7K',
 PRIM_FILE='./archive_libs/logical/q_res/chips/chips.prt';

PART_NAME
 R756 'Q_RES_0201LF-200,1%,1/20W,CHIP,CS12001FE12':;

SECTION_NUMBER 1
 '@T6G_MB_LIB.T6G(SCH_1):PAGE392_I132@PURE_QUANTA.Q_RES(CHIPS)':
 C_PATH='@t6g_mb_lib.t6g(sch_1):page392_i132@pure_quanta.q_res(chips)',
 P_PATH='@t6g_mb_lib.t6g(sch_1):page331_i132@pure_quanta.q_res(chips)',
 PATH='I132',
 DRAWING='@T6G_MB_LIB.T6G(SCH_1):PAGE392',
 WATTAGE='1/20W',
 TOLERANCE='1%',
 MATERIAL='CHIP',
 PHYS_PAGE='331',
 XY='(-8825,3300)',
 ROT='0',
 VER='2',
 PACK_TYPE='0201LF',
 LOCATION='R756',
 CDS_LIB='pure_quanta',
 CDS_PART_NAME='Q_RES_0201LF-200,1%,1/20W,CHIP,CS12001FE12',
 PART_NUMBER='CS12001FE12',
 VALUE='200',
 PRIM_FILE='./archive_libs/logical/q_res/chips/chips.prt';

PART_NAME
 R757 'Q_RES_0402LF-4.7K,5%,1/16W,EMPTY,CS24702JB10':;

SECTION_NUMBER 1
 '@T6G_MB_LIB.T6G(SCH_1):PAGE82_I41@PURE_QUANTA.Q_RES(CHIPS)':
 C_PATH='@t6g_mb_lib.t6g(sch_1):page82_i41@pure_quanta.q_res(chips)',
 P_PATH='@t6g_mb_lib.t6g(sch_1):page83_i41@pure_quanta.q_res(chips)',
 PATH='I41',
 DRAWING='@T6G_MB_LIB.T6G(SCH_1):PAGE82',
 WATTAGE='1/16W',
 TOLERANCE='5%',
 MATERIAL='EMPTY',
 PHYS_PAGE='83',
 XY='(-7050,3950)',
 ROT='0',
 VER='1',
 PACK_TYPE='0402LF',
 LOCATION='R757',
 CDS_LIB='pure_quanta',
 CDS_PART_NAME='Q_RES_0402LF-4.7K,5%,1/16W,EMPTY,CS24702JB10',
 PART_NUMBER='CS24702JB10',
 VALUE='4.7K',
 PRIM_FILE='./archive_libs/logical/q_res/chips/chips.prt';

PART_NAME
 R758 'Q_RES_0201LF-4.7K,5%,1/20W,EMPTY,CS24701JE04':;

SECTION_NUMBER 1
 '@T6G_MB_LIB.T6G(SCH_1):PAGE392_I94@PURE_QUANTA.Q_RES(CHIPS)':
 C_PATH='@t6g_mb_lib.t6g(sch_1):page392_i94@pure_quanta.q_res(chips)',
 P_PATH='@t6g_mb_lib.t6g(sch_1):page331_i94@pure_quanta.q_res(chips)',
 PATH='I94',
 DRAWING='@T6G_MB_LIB.T6G(SCH_1):PAGE392',
 WATTAGE='1/20W',
 TOLERANCE='5%',
 MATERIAL='EMPTY',
 PHYS_PAGE='331',
 XY='(-1325,5900)',
 ROT='2',
 VER='2',
 PACK_TYPE='0201LF',
 LOCATION='R758',
 CDS_LIB='pure_quanta',
 CDS_PART_NAME='Q_RES_0201LF-4.7K,5%,1/20W,EMPTY,CS24701JE04',
 PART_NUMBER='CS24701JE04',
 VALUE='4.7K',
 PRIM_FILE='./archive_libs/logical/q_res/chips/chips.prt';

PART_NAME
 R759 'Q_RES_0201LF-4.7K,5%,1/20W,EMPTY,CS24701JE04':;

SECTION_NUMBER 1
 '@T6G_MB_LIB.T6G(SCH_1):PAGE392_I57@PURE_QUANTA.Q_RES(CHIPS)':
 C_PATH='@t6g_mb_lib.t6g(sch_1):page392_i57@pure_quanta.q_res(chips)',
 P_PATH='@t6g_mb_lib.t6g(sch_1):page331_i57@pure_quanta.q_res(chips)',
 PATH='I57',
 DRAWING='@T6G_MB_LIB.T6G(SCH_1):PAGE392',
 WATTAGE='1/20W',
 TOLERANCE='5%',
 MATERIAL='EMPTY',
 PHYS_PAGE='331',
 XY='(-7275,5850)',
 ROT='0',
 VER='2',
 PACK_TYPE='0201LF',
 LOCATION='R759',
 CDS_LIB='pure_quanta',
 CDS_PART_NAME='Q_RES_0201LF-4.7K,5%,1/20W,EMPTY,CS24701JE04',
 PART_NUMBER='CS24701JE04',
 VALUE='4.7K',
 PRIM_FILE='./archive_libs/logical/q_res/chips/chips.prt';

PART_NAME
 R760 'Q_RES_0402LF-10K,5%,1/16W,CHIP,CS31002JB08':;

SECTION_NUMBER 1
 '@T6G_MB_LIB.T6G(SCH_1):PAGE75_I92@PURE_QUANTA.Q_RES(CHIPS)':
 C_PATH='@t6g_mb_lib.t6g(sch_1):page75_i92@pure_quanta.q_res(chips)',
 P_PATH='@t6g_mb_lib.t6g(sch_1):page76_i92@pure_quanta.q_res(chips)',
 PATH='I92',
 DRAWING='@T6G_MB_LIB.T6G(SCH_1):PAGE75',
 WATTAGE='1/16W',
 TOLERANCE='5%',
 MATERIAL='CHIP',
 PHYS_PAGE='76',
 XY='(-3950,4375)',
 ROT='0',
 VER='1',
 PACK_TYPE='0402LF',
 LOCATION='R760',
 CDS_LIB='pure_quanta',
 CDS_PART_NAME='Q_RES_0402LF-10K,5%,1/16W,CHIP,CS31002JB08',
 PART_NUMBER='CS31002JB08',
 VALUE='10K',
 PRIM_FILE='./archive_libs/logical/q_res/chips/chips.prt';

PART_NAME
 R761 'Q_RES_0402LF-15.4K,1%,1/16W,CHIP,CS31542FB02':;

SECTION_NUMBER 1
 '@T6G_MB_LIB.T6G(SCH_1):PAGE86_I349@PURE_QUANTA.Q_RES(CHIPS)':
 C_PATH='@t6g_mb_lib.t6g(sch_1):page86_i349@pure_quanta.q_res(chips)',
 P_PATH='@t6g_mb_lib.t6g(sch_1):page87_i349@pure_quanta.q_res(chips)',
 PATH='I349',
 DRAWING='@T6G_MB_LIB.T6G(SCH_1):PAGE86',
 WATTAGE='1/16W',
 TOLERANCE='1%',
 MATERIAL='CHIP',
 PHYS_PAGE='87',
 XY='(-6650,1400)',
 ROT='0',
 VER='2',
 PACK_TYPE='0402LF',
 LOCATION='R761',
 CDS_LIB='pure_quanta',
 CDS_PART_NAME='Q_RES_0402LF-15.4K,1%,1/16W,CHIP,CS31542FB02',
 PART_NUMBER='CS31542FB02',
 VALUE='15.4K',
 PRIM_FILE='./archive_libs/logical/q_res/chips/chips.prt';

PART_NAME
 R762 'Q_RES_0402LF-23.2K,1%,1/16W,CHIP,CS32322FB03':;

SECTION_NUMBER 1
 '@T6G_MB_LIB.T6G(SCH_1):PAGE87_I349@PURE_QUANTA.Q_RES(CHIPS)':
 C_PATH='@t6g_mb_lib.t6g(sch_1):page87_i349@pure_quanta.q_res(chips)',
 P_PATH='@t6g_mb_lib.t6g(sch_1):page88_i349@pure_quanta.q_res(chips)',
 PATH='I349',
 DRAWING='@T6G_MB_LIB.T6G(SCH_1):PAGE87',
 WATTAGE='1/16W',
 TOLERANCE='1%',
 MATERIAL='CHIP',
 PHYS_PAGE='88',
 XY='(-6625,1575)',
 ROT='0',
 VER='2',
 PACK_TYPE='0402LF',
 LOCATION='R762',
 CDS_LIB='pure_quanta',
 CDS_PART_NAME='Q_RES_0402LF-23.2K,1%,1/16W,CHIP,CS32322FB03',
 PART_NUMBER='CS32322FB03',
 VALUE='23.2K',
 PRIM_FILE='./archive_libs/logical/q_res/chips/chips.prt';

PART_NAME
 R763 'Q_RES_0402LF-35.7K,1%,1/16W,CHIP,CS33572FB01':;

SECTION_NUMBER 1
 '@T6G_MB_LIB.T6G(SCH_1):PAGE88_I349@PURE_QUANTA.Q_RES(CHIPS)':
 C_PATH='@t6g_mb_lib.t6g(sch_1):page88_i349@pure_quanta.q_res(chips)',
 P_PATH='@t6g_mb_lib.t6g(sch_1):page89_i349@pure_quanta.q_res(chips)',
 PATH='I349',
 DRAWING='@T6G_MB_LIB.T6G(SCH_1):PAGE88',
 WATTAGE='1/16W',
 TOLERANCE='1%',
 MATERIAL='CHIP',
 PHYS_PAGE='89',
 XY='(-6450,1425)',
 ROT='0',
 VER='2',
 PACK_TYPE='0402LF',
 LOCATION='R763',
 CDS_LIB='pure_quanta',
 CDS_PART_NAME='Q_RES_0402LF-35.7K,1%,1/16W,CHIP,CS33572FB01',
 PART_NUMBER='CS33572FB01',
 VALUE='35.7K',
 PRIM_FILE='./archive_libs/logical/q_res/chips/chips.prt';

PART_NAME
 R764 'Q_RES_0402LF-84.5K,1%,1/16W,CHIP,CS38452FB05':;

SECTION_NUMBER 1
 '@T6G_MB_LIB.T6G(SCH_1):PAGE90_I349@PURE_QUANTA.Q_RES(CHIPS)':
 C_PATH='@t6g_mb_lib.t6g(sch_1):page90_i349@pure_quanta.q_res(chips)',
 P_PATH='@t6g_mb_lib.t6g(sch_1):page91_i349@pure_quanta.q_res(chips)',
 PATH='I349',
 DRAWING='@T6G_MB_LIB.T6G(SCH_1):PAGE90',
 WATTAGE='1/16W',
 TOLERANCE='1%',
 MATERIAL='CHIP',
 PHYS_PAGE='91',
 XY='(-6400,1600)',
 ROT='0',
 VER='2',
 PACK_TYPE='0402LF',
 LOCATION='R764',
 CDS_LIB='pure_quanta',
 CDS_PART_NAME='Q_RES_0402LF-84.5K,1%,1/16W,CHIP,CS38452FB05',
 PART_NUMBER='CS38452FB05',
 VALUE='84.5K',
 PRIM_FILE='./archive_libs/logical/q_res/chips/chips.prt';

PART_NAME
 R765 'Q_RES_0402LF-15.4K,1%,1/16W,CHIP,CS31542FB02':;

SECTION_NUMBER 1
 '@T6G_MB_LIB.T6G(SCH_1):PAGE92_I129@PURE_QUANTA.Q_RES(CHIPS)':
 C_PATH='@t6g_mb_lib.t6g(sch_1):page92_i129@pure_quanta.q_res(chips)',
 P_PATH='@t6g_mb_lib.t6g(sch_1):page93_i129@pure_quanta.q_res(chips)',
 PATH='I129',
 DRAWING='@T6G_MB_LIB.T6G(SCH_1):PAGE92',
 WATTAGE='1/16W',
 TOLERANCE='1%',
 MATERIAL='CHIP',
 PHYS_PAGE='93',
 XY='(-6425,1175)',
 ROT='0',
 VER='2',
 PACK_TYPE='0402LF',
 LOCATION='R765',
 CDS_LIB='pure_quanta',
 CDS_PART_NAME='Q_RES_0402LF-15.4K,1%,1/16W,CHIP,CS31542FB02',
 PART_NUMBER='CS31542FB02',
 VALUE='15.4K',
 PRIM_FILE='./archive_libs/logical/q_res/chips/chips.prt';

PART_NAME
 R766 'Q_RES_0402LF-23.2K,1%,1/16W,CHIP,CS32322FB03':;

SECTION_NUMBER 1
 '@T6G_MB_LIB.T6G(SCH_1):PAGE93_I128@PURE_QUANTA.Q_RES(CHIPS)':
 C_PATH='@t6g_mb_lib.t6g(sch_1):page93_i128@pure_quanta.q_res(chips)',
 P_PATH='@t6g_mb_lib.t6g(sch_1):page94_i128@pure_quanta.q_res(chips)',
 PATH='I128',
 DRAWING='@T6G_MB_LIB.T6G(SCH_1):PAGE93',
 WATTAGE='1/16W',
 TOLERANCE='1%',
 MATERIAL='CHIP',
 PHYS_PAGE='94',
 XY='(-6425,1300)',
 ROT='0',
 VER='2',
 PACK_TYPE='0402LF',
 LOCATION='R766',
 CDS_LIB='pure_quanta',
 CDS_PART_NAME='Q_RES_0402LF-23.2K,1%,1/16W,CHIP,CS32322FB03',
 PART_NUMBER='CS32322FB03',
 VALUE='23.2K',
 PRIM_FILE='./archive_libs/logical/q_res/chips/chips.prt';

PART_NAME
 R767 'Q_RES_0402LF-35.7K,1%,1/16W,CHIP,CS33572FB01':;

SECTION_NUMBER 1
 '@T6G_MB_LIB.T6G(SCH_1):PAGE94_I129@PURE_QUANTA.Q_RES(CHIPS)':
 C_PATH='@t6g_mb_lib.t6g(sch_1):page94_i129@pure_quanta.q_res(chips)',
 P_PATH='@t6g_mb_lib.t6g(sch_1):page95_i129@pure_quanta.q_res(chips)',
 PATH='I129',
 DRAWING='@T6G_MB_LIB.T6G(SCH_1):PAGE94',
 WATTAGE='1/16W',
 TOLERANCE='1%',
 MATERIAL='CHIP',
 PHYS_PAGE='95',
 XY='(-6350,1175)',
 ROT='0',
 VER='2',
 PACK_TYPE='0402LF',
 LOCATION='R767',
 CDS_LIB='pure_quanta',
 CDS_PART_NAME='Q_RES_0402LF-35.7K,1%,1/16W,CHIP,CS33572FB01',
 PART_NUMBER='CS33572FB01',
 VALUE='35.7K',
 PRIM_FILE='./archive_libs/logical/q_res/chips/chips.prt';

PART_NAME
 R768 'Q_RES_0402LF-54.9K,1%,1/16W,CHIP,CS35492FB03':;

SECTION_NUMBER 1
 '@T6G_MB_LIB.T6G(SCH_1):PAGE95_I129@PURE_QUANTA.Q_RES(CHIPS)':
 C_PATH='@t6g_mb_lib.t6g(sch_1):page95_i129@pure_quanta.q_res(chips)',
 P_PATH='@t6g_mb_lib.t6g(sch_1):page96_i129@pure_quanta.q_res(chips)',
 PATH='I129',
 DRAWING='@T6G_MB_LIB.T6G(SCH_1):PAGE95',
 WATTAGE='1/16W',
 TOLERANCE='1%',
 MATERIAL='CHIP',
 PHYS_PAGE='96',
 XY='(-6425,1275)',
 ROT='0',
 VER='2',
 PACK_TYPE='0402LF',
 LOCATION='R768',
 CDS_LIB='pure_quanta',
 CDS_PART_NAME='Q_RES_0402LF-54.9K,1%,1/16W,CHIP,CS35492FB03',
 PART_NUMBER='CS35492FB03',
 VALUE='54.9K',
 PRIM_FILE='./archive_libs/logical/q_res/chips/chips.prt';

PART_NAME
 R769 'Q_RES_0402LF-84.5K,1%,1/16W,CHIP,CS38452FB05':;

SECTION_NUMBER 1
 '@T6G_MB_LIB.T6G(SCH_1):PAGE96_I127@PURE_QUANTA.Q_RES(CHIPS)':
 C_PATH='@t6g_mb_lib.t6g(sch_1):page96_i127@pure_quanta.q_res(chips)',
 P_PATH='@t6g_mb_lib.t6g(sch_1):page97_i127@pure_quanta.q_res(chips)',
 PATH='I127',
 DRAWING='@T6G_MB_LIB.T6G(SCH_1):PAGE96',
 WATTAGE='1/16W',
 TOLERANCE='1%',
 MATERIAL='CHIP',
 PHYS_PAGE='97',
 XY='(-6450,925)',
 ROT='0',
 VER='2',
 PACK_TYPE='0402LF',
 LOCATION='R769',
 CDS_LIB='pure_quanta',
 CDS_PART_NAME='Q_RES_0402LF-84.5K,1%,1/16W,CHIP,CS38452FB05',
 PART_NUMBER='CS38452FB05',
 VALUE='84.5K',
 PRIM_FILE='./archive_libs/logical/q_res/chips/chips.prt';

PART_NAME
 R770 'Q_RES_0402LF-15.4K,1%,1/16W,CHIP,CS31542FB02':;

SECTION_NUMBER 1
 '@T6G_MB_LIB.T6G(SCH_1):PAGE98_I127@PURE_QUANTA.Q_RES(CHIPS)':
 C_PATH='@t6g_mb_lib.t6g(sch_1):page98_i127@pure_quanta.q_res(chips)',
 P_PATH='@t6g_mb_lib.t6g(sch_1):page99_i127@pure_quanta.q_res(chips)',
 PATH='I127',
 DRAWING='@T6G_MB_LIB.T6G(SCH_1):PAGE98',
 WATTAGE='1/16W',
 TOLERANCE='1%',
 MATERIAL='CHIP',
 PHYS_PAGE='99',
 XY='(-6475,1450)',
 ROT='0',
 VER='2',
 PACK_TYPE='0402LF',
 LOCATION='R770',
 CDS_LIB='pure_quanta',
 CDS_PART_NAME='Q_RES_0402LF-15.4K,1%,1/16W,CHIP,CS31542FB02',
 PART_NUMBER='CS31542FB02',
 VALUE='15.4K',
 PRIM_FILE='./archive_libs/logical/q_res/chips/chips.prt';

PART_NAME
 R771 'Q_RES_0402LF-23.2K,1%,1/16W,CHIP,CS32322FB03':;

SECTION_NUMBER 1
 '@T6G_MB_LIB.T6G(SCH_1):PAGE99_I148@PURE_QUANTA.Q_RES(CHIPS)':
 C_PATH='@t6g_mb_lib.t6g(sch_1):page99_i148@pure_quanta.q_res(chips)',
 P_PATH='@t6g_mb_lib.t6g(sch_1):page100_i148@pure_quanta.q_res(chips)',
 PATH='I148',
 DRAWING='@T6G_MB_LIB.T6G(SCH_1):PAGE99',
 WATTAGE='1/16W',
 TOLERANCE='1%',
 MATERIAL='CHIP',
 PHYS_PAGE='100',
 XY='(-6600,1250)',
 ROT='0',
 VER='2',
 PACK_TYPE='0402LF',
 LOCATION='R771',
 CDS_LIB='pure_quanta',
 CDS_PART_NAME='Q_RES_0402LF-23.2K,1%,1/16W,CHIP,CS32322FB03',
 PART_NUMBER='CS32322FB03',
 VALUE='23.2K',
 PRIM_FILE='./archive_libs/logical/q_res/chips/chips.prt';

PART_NAME
 R772 'Q_RES_0402LF-35.7K,1%,1/16W,CHIP,CS33572FB01':;

SECTION_NUMBER 1
 '@T6G_MB_LIB.T6G(SCH_1):PAGE100_I146@PURE_QUANTA.Q_RES(CHIPS)':
 C_PATH='@t6g_mb_lib.t6g(sch_1):page100_i146@pure_quanta.q_res(chips)',
 P_PATH='@t6g_mb_lib.t6g(sch_1):page101_i146@pure_quanta.q_res(chips)',
 PATH='I146',
 DRAWING='@T6G_MB_LIB.T6G(SCH_1):PAGE100',
 WATTAGE='1/16W',
 TOLERANCE='1%',
 MATERIAL='CHIP',
 PHYS_PAGE='101',
 XY='(-6525,1425)',
 ROT='0',
 VER='2',
 PACK_TYPE='0402LF',
 LOCATION='R772',
 CDS_LIB='pure_quanta',
 CDS_PART_NAME='Q_RES_0402LF-35.7K,1%,1/16W,CHIP,CS33572FB01',
 PART_NUMBER='CS33572FB01',
 VALUE='35.7K',
 PRIM_FILE='./archive_libs/logical/q_res/chips/chips.prt';

PART_NAME
 R773 'Q_RES_0402LF-84.5K,1%,1/16W,CHIP,CS38452FB05':;

SECTION_NUMBER 1
 '@T6G_MB_LIB.T6G(SCH_1):PAGE102_I129@PURE_QUANTA.Q_RES(CHIPS)':
 C_PATH='@t6g_mb_lib.t6g(sch_1):page102_i129@pure_quanta.q_res(chips)',
 P_PATH='@t6g_mb_lib.t6g(sch_1):page103_i129@pure_quanta.q_res(chips)',
 PATH='I129',
 DRAWING='@T6G_MB_LIB.T6G(SCH_1):PAGE102',
 WATTAGE='1/16W',
 TOLERANCE='1%',
 MATERIAL='CHIP',
 PHYS_PAGE='103',
 XY='(-6550,1275)',
 ROT='0',
 VER='2',
 PACK_TYPE='0402LF',
 LOCATION='R773',
 CDS_LIB='pure_quanta',
 CDS_PART_NAME='Q_RES_0402LF-84.5K,1%,1/16W,CHIP,CS38452FB05',
 PART_NUMBER='CS38452FB05',
 VALUE='84.5K',
 PRIM_FILE='./archive_libs/logical/q_res/chips/chips.prt';

PART_NAME
 R774 'Q_RES_0402LF-15.4K,1%,1/16W,CHIP,CS31542FB02':;

SECTION_NUMBER 1
 '@T6G_MB_LIB.T6G(SCH_1):PAGE104_I128@PURE_QUANTA.Q_RES(CHIPS)':
 C_PATH='@t6g_mb_lib.t6g(sch_1):page104_i128@pure_quanta.q_res(chips)',
 P_PATH='@t6g_mb_lib.t6g(sch_1):page105_i128@pure_quanta.q_res(chips)',
 PATH='I128',
 DRAWING='@T6G_MB_LIB.T6G(SCH_1):PAGE104',
 WATTAGE='1/16W',
 TOLERANCE='1%',
 MATERIAL='CHIP',
 PHYS_PAGE='105',
 XY='(-6375,1075)',
 ROT='0',
 VER='2',
 PACK_TYPE='0402LF',
 LOCATION='R774',
 CDS_LIB='pure_quanta',
 CDS_PART_NAME='Q_RES_0402LF-15.4K,1%,1/16W,CHIP,CS31542FB02',
 PART_NUMBER='CS31542FB02',
 VALUE='15.4K',
 PRIM_FILE='./archive_libs/logical/q_res/chips/chips.prt';

PART_NAME
 R775 'Q_RES_0402LF-23.2K,1%,1/16W,CHIP,CS32322FB03':;

SECTION_NUMBER 1
 '@T6G_MB_LIB.T6G(SCH_1):PAGE105_I128@PURE_QUANTA.Q_RES(CHIPS)':
 C_PATH='@t6g_mb_lib.t6g(sch_1):page105_i128@pure_quanta.q_res(chips)',
 P_PATH='@t6g_mb_lib.t6g(sch_1):page106_i128@pure_quanta.q_res(chips)',
 PATH='I128',
 DRAWING='@T6G_MB_LIB.T6G(SCH_1):PAGE105',
 WATTAGE='1/16W',
 TOLERANCE='1%',
 MATERIAL='CHIP',
 PHYS_PAGE='106',
 XY='(-6375,1150)',
 ROT='0',
 VER='2',
 PACK_TYPE='0402LF',
 LOCATION='R775',
 CDS_LIB='pure_quanta',
 CDS_PART_NAME='Q_RES_0402LF-23.2K,1%,1/16W,CHIP,CS32322FB03',
 PART_NUMBER='CS32322FB03',
 VALUE='23.2K',
 PRIM_FILE='./archive_libs/logical/q_res/chips/chips.prt';

PART_NAME
 R776 'Q_RES_0402LF-35.7K,1%,1/16W,CHIP,CS33572FB01':;

SECTION_NUMBER 1
 '@T6G_MB_LIB.T6G(SCH_1):PAGE106_I127@PURE_QUANTA.Q_RES(CHIPS)':
 C_PATH='@t6g_mb_lib.t6g(sch_1):page106_i127@pure_quanta.q_res(chips)',
 P_PATH='@t6g_mb_lib.t6g(sch_1):page107_i127@pure_quanta.q_res(chips)',
 PATH='I127',
 DRAWING='@T6G_MB_LIB.T6G(SCH_1):PAGE106',
 WATTAGE='1/16W',
 TOLERANCE='1%',
 MATERIAL='CHIP',
 PHYS_PAGE='107',
 XY='(-6250,1175)',
 ROT='0',
 VER='2',
 PACK_TYPE='0402LF',
 LOCATION='R776',
 CDS_LIB='pure_quanta',
 CDS_PART_NAME='Q_RES_0402LF-35.7K,1%,1/16W,CHIP,CS33572FB01',
 PART_NUMBER='CS33572FB01',
 VALUE='35.7K',
 PRIM_FILE='./archive_libs/logical/q_res/chips/chips.prt';

PART_NAME
 R777 'Q_RES_0402LF-54.9K,1%,1/16W,CHIP,CS35492FB03':;

SECTION_NUMBER 1
 '@T6G_MB_LIB.T6G(SCH_1):PAGE107_I136@PURE_QUANTA.Q_RES(CHIPS)':
 C_PATH='@t6g_mb_lib.t6g(sch_1):page107_i136@pure_quanta.q_res(chips)',
 P_PATH='@t6g_mb_lib.t6g(sch_1):page108_i136@pure_quanta.q_res(chips)',
 PATH='I136',
 DRAWING='@T6G_MB_LIB.T6G(SCH_1):PAGE107',
 WATTAGE='1/16W',
 TOLERANCE='1%',
 MATERIAL='CHIP',
 PHYS_PAGE='108',
 XY='(-6400,1100)',
 ROT='0',
 VER='2',
 PACK_TYPE='0402LF',
 LOCATION='R777',
 CDS_LIB='pure_quanta',
 CDS_PART_NAME='Q_RES_0402LF-54.9K,1%,1/16W,CHIP,CS35492FB03',
 PART_NUMBER='CS35492FB03',
 VALUE='54.9K',
 PRIM_FILE='./archive_libs/logical/q_res/chips/chips.prt';

PART_NAME
 R778 'Q_RES_0402LF-84.5K,1%,1/16W,CHIP,CS38452FB05':;

SECTION_NUMBER 1
 '@T6G_MB_LIB.T6G(SCH_1):PAGE108_I136@PURE_QUANTA.Q_RES(CHIPS)':
 C_PATH='@t6g_mb_lib.t6g(sch_1):page108_i136@pure_quanta.q_res(chips)',
 P_PATH='@t6g_mb_lib.t6g(sch_1):page109_i136@pure_quanta.q_res(chips)',
 PATH='I136',
 DRAWING='@T6G_MB_LIB.T6G(SCH_1):PAGE108',
 WATTAGE='1/16W',
 TOLERANCE='1%',
 MATERIAL='CHIP',
 PHYS_PAGE='109',
 XY='(-6350,1125)',
 ROT='0',
 VER='2',
 PACK_TYPE='0402LF',
 LOCATION='R778',
 CDS_LIB='pure_quanta',
 CDS_PART_NAME='Q_RES_0402LF-84.5K,1%,1/16W,CHIP,CS38452FB05',
 PART_NUMBER='CS38452FB05',
 VALUE='84.5K',
 PRIM_FILE='./archive_libs/logical/q_res/chips/chips.prt';

PART_NAME
 R779 'Q_RES_0201LF-0,5%,1/20W,CHIP,CS00001JE10':;

SECTION_NUMBER 1
 '@T6G_MB_LIB.T6G(SCH_1):PAGE392_I44@PURE_QUANTA.Q_RES(CHIPS)':
 C_PATH='@t6g_mb_lib.t6g(sch_1):page392_i44@pure_quanta.q_res(chips)',
 P_PATH='@t6g_mb_lib.t6g(sch_1):page331_i44@pure_quanta.q_res(chips)',
 PATH='I44',
 DRAWING='@T6G_MB_LIB.T6G(SCH_1):PAGE392',
 WATTAGE='1/20W',
 TOLERANCE='5%',
 MATERIAL='CHIP',
 PHYS_PAGE='331',
 XY='(-6200,2750)',
 ROT='0',
 VER='1',
 PACK_TYPE='0201LF',
 LOCATION='R779',
 CDS_LIB='pure_quanta',
 CDS_PART_NAME='Q_RES_0201LF-0,5%,1/20W,CHIP,CS00001JE10',
 PART_NUMBER='CS00001JE10',
 VALUE='0',
 PRIM_FILE='./archive_libs/logical/q_res/chips/chips.prt';

PART_NAME
 R780 'Q_RES_0201LF-0,5%,1/20W,CHIP,CS00001JE10':;

SECTION_NUMBER 1
 '@T6G_MB_LIB.T6G(SCH_1):PAGE392_I43@PURE_QUANTA.Q_RES(CHIPS)':
 C_PATH='@t6g_mb_lib.t6g(sch_1):page392_i43@pure_quanta.q_res(chips)',
 P_PATH='@t6g_mb_lib.t6g(sch_1):page331_i43@pure_quanta.q_res(chips)',
 PATH='I43',
 DRAWING='@T6G_MB_LIB.T6G(SCH_1):PAGE392',
 WATTAGE='1/20W',
 TOLERANCE='5%',
 MATERIAL='CHIP',
 PHYS_PAGE='331',
 XY='(-6200,2650)',
 ROT='0',
 VER='1',
 PACK_TYPE='0201LF',
 LOCATION='R780',
 CDS_LIB='pure_quanta',
 CDS_PART_NAME='Q_RES_0201LF-0,5%,1/20W,CHIP,CS00001JE10',
 PART_NUMBER='CS00001JE10',
 VALUE='0',
 PRIM_FILE='./archive_libs/logical/q_res/chips/chips.prt';

PART_NAME
 R781 'Q_RES_0201LF-4.7K,5%,1/20W,EMPTY,CS24701JE04':;

SECTION_NUMBER 1
 '@T6G_MB_LIB.T6G(SCH_1):PAGE392_I24@PURE_QUANTA.Q_RES(CHIPS)':
 C_PATH='@t6g_mb_lib.t6g(sch_1):page392_i24@pure_quanta.q_res(chips)',
 P_PATH='@t6g_mb_lib.t6g(sch_1):page331_i24@pure_quanta.q_res(chips)',
 PATH='I24',
 DRAWING='@T6G_MB_LIB.T6G(SCH_1):PAGE392',
 WATTAGE='1/20W',
 TOLERANCE='5%',
 MATERIAL='EMPTY',
 PHYS_PAGE='331',
 XY='(-8800,5850)',
 ROT='0',
 VER='2',
 PACK_TYPE='0201LF',
 LOCATION='R781',
 CDS_LIB='pure_quanta',
 CDS_PART_NAME='Q_RES_0201LF-4.7K,5%,1/20W,EMPTY,CS24701JE04',
 PART_NUMBER='CS24701JE04',
 VALUE='4.7K',
 PRIM_FILE='./archive_libs/logical/q_res/chips/chips.prt';

PART_NAME
 R782 'Q_RES_0201LF-10K,1%,1/20W,CHIP,CS31001FE17':;

SECTION_NUMBER 1
 '@T6G_MB_LIB.T6G(SCH_1):PAGE392_I21@PURE_QUANTA.Q_RES(CHIPS)':
 C_PATH='@t6g_mb_lib.t6g(sch_1):page392_i21@pure_quanta.q_res(chips)',
 P_PATH='@t6g_mb_lib.t6g(sch_1):page331_i21@pure_quanta.q_res(chips)',
 PATH='I21',
 DRAWING='@T6G_MB_LIB.T6G(SCH_1):PAGE392',
 WATTAGE='1/20W',
 TOLERANCE='1%',
 MATERIAL='CHIP',
 PHYS_PAGE='331',
 XY='(-8800,4900)',
 ROT='0',
 VER='2',
 PACK_TYPE='0201LF',
 LOCATION='R782',
 CDS_LIB='pure_quanta',
 CDS_PART_NAME='Q_RES_0201LF-10K,1%,1/20W,CHIP,CS31001FE17',
 PART_NUMBER='CS31001FE17',
 VALUE='10K',
 PRIM_FILE='./archive_libs/logical/q_res/chips/chips.prt';

PART_NAME
 R783 'Q_RES_0201LF-10K,1%,1/20W,CHIP,CS31001FE17':;

SECTION_NUMBER 1
 '@T6G_MB_LIB.T6G(SCH_1):PAGE392_I22@PURE_QUANTA.Q_RES(CHIPS)':
 C_PATH='@t6g_mb_lib.t6g(sch_1):page392_i22@pure_quanta.q_res(chips)',
 P_PATH='@t6g_mb_lib.t6g(sch_1):page331_i22@pure_quanta.q_res(chips)',
 PATH='I22',
 DRAWING='@T6G_MB_LIB.T6G(SCH_1):PAGE392',
 WATTAGE='1/20W',
 TOLERANCE='1%',
 MATERIAL='CHIP',
 PHYS_PAGE='331',
 XY='(-8500,4900)',
 ROT='0',
 VER='2',
 PACK_TYPE='0201LF',
 LOCATION='R783',
 CDS_LIB='pure_quanta',
 CDS_PART_NAME='Q_RES_0201LF-10K,1%,1/20W,CHIP,CS31001FE17',
 PART_NUMBER='CS31001FE17',
 VALUE='10K',
 PRIM_FILE='./archive_libs/logical/q_res/chips/chips.prt';

PART_NAME
 R784 'Q_RES_0201LF-4.7K,5%,1/20W,EMPTY,CS24701JE04':;

SECTION_NUMBER 1
 '@T6G_MB_LIB.T6G(SCH_1):PAGE392_I25@PURE_QUANTA.Q_RES(CHIPS)':
 C_PATH='@t6g_mb_lib.t6g(sch_1):page392_i25@pure_quanta.q_res(chips)',
 P_PATH='@t6g_mb_lib.t6g(sch_1):page331_i25@pure_quanta.q_res(chips)',
 PATH='I25',
 DRAWING='@T6G_MB_LIB.T6G(SCH_1):PAGE392',
 WATTAGE='1/20W',
 TOLERANCE='5%',
 MATERIAL='EMPTY',
 PHYS_PAGE='331',
 XY='(-8175,5850)',
 ROT='0',
 VER='2',
 PACK_TYPE='0201LF',
 LOCATION='R784',
 CDS_LIB='pure_quanta',
 CDS_PART_NAME='Q_RES_0201LF-4.7K,5%,1/20W,EMPTY,CS24701JE04',
 PART_NUMBER='CS24701JE04',
 VALUE='4.7K',
 PRIM_FILE='./archive_libs/logical/q_res/chips/chips.prt';

PART_NAME
 R785 'Q_RES_0201LF-4.7K,5%,1/20W,CHIP,CS24701JE04':;

SECTION_NUMBER 1
 '@T6G_MB_LIB.T6G(SCH_1):PAGE392_I23@PURE_QUANTA.Q_RES(CHIPS)':
 C_PATH='@t6g_mb_lib.t6g(sch_1):page392_i23@pure_quanta.q_res(chips)',
 P_PATH='@t6g_mb_lib.t6g(sch_1):page331_i23@pure_quanta.q_res(chips)',
 PATH='I23',
 DRAWING='@T6G_MB_LIB.T6G(SCH_1):PAGE392',
 WATTAGE='1/20W',
 TOLERANCE='5%',
 MATERIAL='CHIP',
 PHYS_PAGE='331',
 XY='(-8175,4900)',
 ROT='0',
 VER='2',
 PACK_TYPE='0201LF',
 LOCATION='R785',
 CDS_LIB='pure_quanta',
 CDS_PART_NAME='Q_RES_0201LF-4.7K,5%,1/20W,CHIP,CS24701JE04',
 PART_NUMBER='CS24701JE04',
 VALUE='4.7K',
 PRIM_FILE='./archive_libs/logical/q_res/chips/chips.prt';

PART_NAME
 R786 'Q_RES_0201LF-4.7K,5%,1/20W,EMPTY,CS24701JE04':;

SECTION_NUMBER 1
 '@T6G_MB_LIB.T6G(SCH_1):PAGE392_I55@PURE_QUANTA.Q_RES(CHIPS)':
 C_PATH='@t6g_mb_lib.t6g(sch_1):page392_i55@pure_quanta.q_res(chips)',
 P_PATH='@t6g_mb_lib.t6g(sch_1):page331_i55@pure_quanta.q_res(chips)',
 PATH='I55',
 DRAWING='@T6G_MB_LIB.T6G(SCH_1):PAGE392',
 WATTAGE='1/20W',
 TOLERANCE='5%',
 MATERIAL='EMPTY',
 PHYS_PAGE='331',
 XY='(-7875,5800)',
 ROT='0',
 VER='2',
 PACK_TYPE='0201LF',
 LOCATION='R786',
 CDS_LIB='pure_quanta',
 CDS_PART_NAME='Q_RES_0201LF-4.7K,5%,1/20W,EMPTY,CS24701JE04',
 PART_NUMBER='CS24701JE04',
 VALUE='4.7K',
 PRIM_FILE='./archive_libs/logical/q_res/chips/chips.prt';

PART_NAME
 R787 'Q_RES_0201LF-4.7K,5%,1/20W,CHIP,CS24701JE04':;

SECTION_NUMBER 1
 '@T6G_MB_LIB.T6G(SCH_1):PAGE392_I51@PURE_QUANTA.Q_RES(CHIPS)':
 C_PATH='@t6g_mb_lib.t6g(sch_1):page392_i51@pure_quanta.q_res(chips)',
 P_PATH='@t6g_mb_lib.t6g(sch_1):page331_i51@pure_quanta.q_res(chips)',
 PATH='I51',
 DRAWING='@T6G_MB_LIB.T6G(SCH_1):PAGE392',
 WATTAGE='1/20W',
 TOLERANCE='5%',
 MATERIAL='CHIP',
 PHYS_PAGE='331',
 XY='(-7875,4875)',
 ROT='0',
 VER='2',
 PACK_TYPE='0201LF',
 LOCATION='R787',
 CDS_LIB='pure_quanta',
 CDS_PART_NAME='Q_RES_0201LF-4.7K,5%,1/20W,CHIP,CS24701JE04',
 PART_NUMBER='CS24701JE04',
 VALUE='4.7K',
 PRIM_FILE='./archive_libs/logical/q_res/chips/chips.prt';

PART_NAME
 R788 'Q_RES_0201LF-4.7K,5%,1/20W,EMPTY,CS24701JE04':;

SECTION_NUMBER 1
 '@T6G_MB_LIB.T6G(SCH_1):PAGE392_I56@PURE_QUANTA.Q_RES(CHIPS)':
 C_PATH='@t6g_mb_lib.t6g(sch_1):page392_i56@pure_quanta.q_res(chips)',
 P_PATH='@t6g_mb_lib.t6g(sch_1):page331_i56@pure_quanta.q_res(chips)',
 PATH='I56',
 DRAWING='@T6G_MB_LIB.T6G(SCH_1):PAGE392',
 WATTAGE='1/20W',
 TOLERANCE='5%',
 MATERIAL='EMPTY',
 PHYS_PAGE='331',
 XY='(-7575,5825)',
 ROT='0',
 VER='2',
 PACK_TYPE='0201LF',
 LOCATION='R788',
 CDS_LIB='pure_quanta',
 CDS_PART_NAME='Q_RES_0201LF-4.7K,5%,1/20W,EMPTY,CS24701JE04',
 PART_NUMBER='CS24701JE04',
 VALUE='4.7K',
 PRIM_FILE='./archive_libs/logical/q_res/chips/chips.prt';

PART_NAME
 R789 'Q_RES_0402LF-0,5%,1/16W,EMPTY,CS00002JB13':;

SECTION_NUMBER 1
 '@T6G_MB_LIB.T6G(SCH_1):PAGE137_I96@PURE_QUANTA.Q_RES(CHIPS)':
 C_PATH='@t6g_mb_lib.t6g(sch_1):page137_i96@pure_quanta.q_res(chips)',
 P_PATH='@t6g_mb_lib.t6g(sch_1):page160_i96@pure_quanta.q_res(chips)',
 PATH='I96',
 DRAWING='@T6G_MB_LIB.T6G(SCH_1):PAGE137',
 WATTAGE='1/16W',
 TOLERANCE='5%',
 MATERIAL='EMPTY',
 PHYS_PAGE='160',
 XY='(-5975,3375)',
 ROT='0',
 VER='1',
 PACK_TYPE='0402LF',
 LOCATION='R789',
 CDS_LIB='pure_quanta',
 CDS_PART_NAME='Q_RES_0402LF-0,5%,1/16W,EMPTY,CS00002JB13',
 PART_NUMBER='CS00002JB13',
 VALUE='0',
 PRIM_FILE='./archive_libs/logical/q_res/chips/chips.prt';

PART_NAME
 R790 'Q_RES_0402LF-0,5%,1/16W,EMPTY,CS00002JB13':;

SECTION_NUMBER 1
 '@T6G_MB_LIB.T6G(SCH_1):PAGE137_I95@PURE_QUANTA.Q_RES(CHIPS)':
 C_PATH='@t6g_mb_lib.t6g(sch_1):page137_i95@pure_quanta.q_res(chips)',
 P_PATH='@t6g_mb_lib.t6g(sch_1):page160_i95@pure_quanta.q_res(chips)',
 PATH='I95',
 DRAWING='@T6G_MB_LIB.T6G(SCH_1):PAGE137',
 WATTAGE='1/16W',
 TOLERANCE='5%',
 MATERIAL='EMPTY',
 PHYS_PAGE='160',
 XY='(-5975,3325)',
 ROT='0',
 VER='1',
 PACK_TYPE='0402LF',
 LOCATION='R790',
 CDS_LIB='pure_quanta',
 CDS_PART_NAME='Q_RES_0402LF-0,5%,1/16W,EMPTY,CS00002JB13',
 PART_NUMBER='CS00002JB13',
 VALUE='0',
 PRIM_FILE='./archive_libs/logical/q_res/chips/chips.prt';

PART_NAME
 R791 'Q_RES_0201LF-4.7K,5%,1/20W,CHIP,CS24701JE04':;

SECTION_NUMBER 1
 '@T6G_MB_LIB.T6G(SCH_1):PAGE392_I52@PURE_QUANTA.Q_RES(CHIPS)':
 C_PATH='@t6g_mb_lib.t6g(sch_1):page392_i52@pure_quanta.q_res(chips)',
 P_PATH='@t6g_mb_lib.t6g(sch_1):page331_i52@pure_quanta.q_res(chips)',
 PATH='I52',
 DRAWING='@T6G_MB_LIB.T6G(SCH_1):PAGE392',
 WATTAGE='1/20W',
 TOLERANCE='5%',
 MATERIAL='CHIP',
 PHYS_PAGE='331',
 XY='(-7575,4875)',
 ROT='0',
 VER='2',
 PACK_TYPE='0201LF',
 LOCATION='R791',
 CDS_LIB='pure_quanta',
 CDS_PART_NAME='Q_RES_0201LF-4.7K,5%,1/20W,CHIP,CS24701JE04',
 PART_NUMBER='CS24701JE04',
 VALUE='4.7K',
 PRIM_FILE='./archive_libs/logical/q_res/chips/chips.prt';

PART_NAME
 R792 'Q_RES_0201LF-4.7K,5%,1/20W,CHIP,CS24701JE04':;

SECTION_NUMBER 1
 '@T6G_MB_LIB.T6G(SCH_1):PAGE392_I54@PURE_QUANTA.Q_RES(CHIPS)':
 C_PATH='@t6g_mb_lib.t6g(sch_1):page392_i54@pure_quanta.q_res(chips)',
 P_PATH='@t6g_mb_lib.t6g(sch_1):page331_i54@pure_quanta.q_res(chips)',
 PATH='I54',
 DRAWING='@T6G_MB_LIB.T6G(SCH_1):PAGE392',
 WATTAGE='1/20W',
 TOLERANCE='5%',
 MATERIAL='CHIP',
 PHYS_PAGE='331',
 XY='(-7275,4850)',
 ROT='0',
 VER='2',
 PACK_TYPE='0201LF',
 LOCATION='R792',
 CDS_LIB='pure_quanta',
 CDS_PART_NAME='Q_RES_0201LF-4.7K,5%,1/20W,CHIP,CS24701JE04',
 PART_NUMBER='CS24701JE04',
 VALUE='4.7K',
 PRIM_FILE='./archive_libs/logical/q_res/chips/chips.prt';

PART_NAME
 R793 'Q_RES_0201LF-4.7K,5%,1/20W,CHIP,CS24701JE04':;

SECTION_NUMBER 1
 '@T6G_MB_LIB.T6G(SCH_1):PAGE392_I66@PURE_QUANTA.Q_RES(CHIPS)':
 C_PATH='@t6g_mb_lib.t6g(sch_1):page392_i66@pure_quanta.q_res(chips)',
 P_PATH='@t6g_mb_lib.t6g(sch_1):page331_i66@pure_quanta.q_res(chips)',
 PATH='I66',
 DRAWING='@T6G_MB_LIB.T6G(SCH_1):PAGE392',
 WATTAGE='1/20W',
 TOLERANCE='5%',
 MATERIAL='CHIP',
 PHYS_PAGE='331',
 XY='(-4875,5925)',
 ROT='0',
 VER='2',
 PACK_TYPE='0201LF',
 LOCATION='R793',
 CDS_LIB='pure_quanta',
 CDS_PART_NAME='Q_RES_0201LF-4.7K,5%,1/20W,CHIP,CS24701JE04',
 PART_NUMBER='CS24701JE04',
 VALUE='4.7K',
 PRIM_FILE='./archive_libs/logical/q_res/chips/chips.prt';

PART_NAME
 R794 'Q_RES_0201LF-4.7K,5%,1/20W,EMPTY,CS24701JE04':;

SECTION_NUMBER 1
 '@T6G_MB_LIB.T6G(SCH_1):PAGE392_I65@PURE_QUANTA.Q_RES(CHIPS)':
 C_PATH='@t6g_mb_lib.t6g(sch_1):page392_i65@pure_quanta.q_res(chips)',
 P_PATH='@t6g_mb_lib.t6g(sch_1):page331_i65@pure_quanta.q_res(chips)',
 PATH='I65',
 DRAWING='@T6G_MB_LIB.T6G(SCH_1):PAGE392',
 WATTAGE='1/20W',
 TOLERANCE='5%',
 MATERIAL='EMPTY',
 PHYS_PAGE='331',
 XY='(-4875,5400)',
 ROT='0',
 VER='2',
 PACK_TYPE='0201LF',
 LOCATION='R794',
 CDS_LIB='pure_quanta',
 CDS_PART_NAME='Q_RES_0201LF-4.7K,5%,1/20W,EMPTY,CS24701JE04',
 PART_NUMBER='CS24701JE04',
 VALUE='4.7K',
 PRIM_FILE='./archive_libs/logical/q_res/chips/chips.prt';

PART_NAME
 R795 'Q_RES_0201LF-1K,1%,1/20W,EMPTY,CS21001FE07':;

SECTION_NUMBER 1
 '@T6G_MB_LIB.T6G(SCH_1):PAGE392_I110@PURE_QUANTA.Q_RES(CHIPS)':
 C_PATH='@t6g_mb_lib.t6g(sch_1):page392_i110@pure_quanta.q_res(chips)',
 P_PATH='@t6g_mb_lib.t6g(sch_1):page331_i110@pure_quanta.q_res(chips)',
 PATH='I110',
 DRAWING='@T6G_MB_LIB.T6G(SCH_1):PAGE392',
 WATTAGE='1/20W',
 TOLERANCE='1%',
 MATERIAL='EMPTY',
 PHYS_PAGE='331',
 XY='(-2825,5925)',
 ROT='0',
 VER='2',
 PACK_TYPE='0201LF',
 LOCATION='R795',
 CDS_LIB='pure_quanta',
 CDS_PART_NAME='Q_RES_0201LF-1K,1%,1/20W,EMPTY,CS21001FE07',
 PART_NUMBER='CS21001FE07',
 VALUE='1K',
 PRIM_FILE='./archive_libs/logical/q_res/chips/chips.prt';

PART_NAME
 R796 'Q_RES_0201LF-1K,1%,1/20W,CHIP,CS21001FE07':;

SECTION_NUMBER 1
 '@T6G_MB_LIB.T6G(SCH_1):PAGE392_I105@PURE_QUANTA.Q_RES(CHIPS)':
 C_PATH='@t6g_mb_lib.t6g(sch_1):page392_i105@pure_quanta.q_res(chips)',
 P_PATH='@t6g_mb_lib.t6g(sch_1):page331_i105@pure_quanta.q_res(chips)',
 PATH='I105',
 DRAWING='@T6G_MB_LIB.T6G(SCH_1):PAGE392',
 WATTAGE='1/20W',
 TOLERANCE='1%',
 MATERIAL='CHIP',
 PHYS_PAGE='331',
 XY='(-2825,5175)',
 ROT='0',
 VER='2',
 PACK_TYPE='0201LF',
 LOCATION='R796',
 CDS_LIB='pure_quanta',
 CDS_PART_NAME='Q_RES_0201LF-1K,1%,1/20W,CHIP,CS21001FE07',
 PART_NUMBER='CS21001FE07',
 VALUE='1K',
 PRIM_FILE='./archive_libs/logical/q_res/chips/chips.prt';

PART_NAME
 R797 'Q_RES_0201LF-0,5%,1/20W,CHIP,CS00001JE10':;

SECTION_NUMBER 1
 '@T6G_MB_LIB.T6G(SCH_1):PAGE377_I80@PURE_QUANTA.Q_RES(CHIPS)':
 C_PATH='@t6g_mb_lib.t6g(sch_1):page377_i80@pure_quanta.q_res(chips)',
 P_PATH='@t6g_mb_lib.t6g(sch_1):page185_i80@pure_quanta.q_res(chips)',
 PATH='I80',
 DRAWING='@T6G_MB_LIB.T6G(SCH_1):PAGE377',
 SEC_TYPE='0201LF',
 WATTAGE='1/20W',
 TOLERANCE='5%',
 MATERIAL='CHIP',
 PHYS_PAGE='185',
 XY='(-2775,5450)',
 ROT='0',
 VER='1',
 PACK_TYPE='0201LF',
 LOCATION='R797',
 SEC='1',
 CDS_LIB='pure_quanta',
 CDS_PART_NAME='Q_RES_0201LF-0,5%,1/20W,CHIP,CS00001JE10',
 PART_NUMBER='CS00001JE10',
 VALUE='0',
 PRIM_FILE='./archive_libs/logical/q_res/chips/chips.prt';

PART_NAME
 R798 'Q_RES_0402LF-33,5%,1/16W,CHIP,CS03302JB10':;

SECTION_NUMBER 1
 '@T6G_MB_LIB.T6G(SCH_1):PAGE80_I125@PURE_QUANTA.Q_RES(CHIPS)':
 C_PATH='@t6g_mb_lib.t6g(sch_1):page80_i125@pure_quanta.q_res(chips)',
 P_PATH='@t6g_mb_lib.t6g(sch_1):page81_i125@pure_quanta.q_res(chips)',
 PATH='I125',
 DRAWING='@T6G_MB_LIB.T6G(SCH_1):PAGE80',
 BOM_COST='MEM',
 WATTAGE='1/16W',
 TOLERANCE='5%',
 MATERIAL='CHIP',
 PHYS_PAGE='81',
 XY='(-2300,1625)',
 ROT='0',
 VER='1',
 PACK_TYPE='0402LF',
 LOCATION='R798',
 CDS_LIB='pure_quanta',
 CDS_PART_NAME='Q_RES_0402LF-33,5%,1/16W,CHIP,CS03302JB10',
 PART_NUMBER='CS03302JB10',
 VALUE='33',
 PRIM_FILE='./archive_libs/logical/q_res/chips/chips.prt';

PART_NAME
 R799 'Q_RES_0201LF-0,5%,1/20W,CHIP,CS00001JE10':;

SECTION_NUMBER 1
 '@T6G_MB_LIB.T6G(SCH_1):PAGE377_I79@PURE_QUANTA.Q_RES(CHIPS)':
 C_PATH='@t6g_mb_lib.t6g(sch_1):page377_i79@pure_quanta.q_res(chips)',
 P_PATH='@t6g_mb_lib.t6g(sch_1):page185_i79@pure_quanta.q_res(chips)',
 PATH='I79',
 DRAWING='@T6G_MB_LIB.T6G(SCH_1):PAGE377',
 SEC_TYPE='0201LF',
 WATTAGE='1/20W',
 TOLERANCE='5%',
 MATERIAL='CHIP',
 PHYS_PAGE='185',
 XY='(-2775,5400)',
 ROT='0',
 VER='1',
 PACK_TYPE='0201LF',
 LOCATION='R799',
 SEC='1',
 CDS_LIB='pure_quanta',
 CDS_PART_NAME='Q_RES_0201LF-0,5%,1/20W,CHIP,CS00001JE10',
 PART_NUMBER='CS00001JE10',
 VALUE='0',
 PRIM_FILE='./archive_libs/logical/q_res/chips/chips.prt';

PART_NAME
 R800 'Q_RES_0402LF-10K,1%,1/16W,CHIP,CS31002FB08':;

SECTION_NUMBER 1
 '@T6G_MB_LIB.T6G(SCH_1):PAGE82_I118@PURE_QUANTA.Q_RES(CHIPS)':
 C_PATH='@t6g_mb_lib.t6g(sch_1):page82_i118@pure_quanta.q_res(chips)',
 P_PATH='@t6g_mb_lib.t6g(sch_1):page83_i118@pure_quanta.q_res(chips)',
 PATH='I118',
 DRAWING='@T6G_MB_LIB.T6G(SCH_1):PAGE82',
 BOM_COST='MEM',
 WATTAGE='1/16W',
 TOLERANCE='1%',
 MATERIAL='CHIP',
 PHYS_PAGE='83',
 XY='(-3625,4475)',
 ROT='0',
 VER='2',
 PACK_TYPE='0402LF',
 LOCATION='R800',
 CDS_LIB='pure_quanta',
 CDS_PART_NAME='Q_RES_0402LF-10K,1%,1/16W,CHIP,CS31002FB08',
 PART_NUMBER='CS31002FB08',
 VALUE='10K',
 PRIM_FILE='./archive_libs/logical/q_res/chips/chips.prt';

PART_NAME
 R801 'Q_RES_0201LF-0,5%,1/20W,CHIP,CS00001JE10':;

SECTION_NUMBER 1
 '@T6G_MB_LIB.T6G(SCH_1):PAGE377_I49@PURE_QUANTA.Q_RES(CHIPS)':
 C_PATH='@t6g_mb_lib.t6g(sch_1):page377_i49@pure_quanta.q_res(chips)',
 P_PATH='@t6g_mb_lib.t6g(sch_1):page185_i49@pure_quanta.q_res(chips)',
 PATH='I49',
 DRAWING='@T6G_MB_LIB.T6G(SCH_1):PAGE377',
 SEC_TYPE='0201LF',
 WATTAGE='1/20W',
 TOLERANCE='5%',
 MATERIAL='CHIP',
 PHYS_PAGE='185',
 XY='(-6425,5450)',
 ROT='0',
 VER='1',
 PACK_TYPE='0201LF',
 LOCATION='R801',
 SEC='1',
 CDS_LIB='pure_quanta',
 CDS_PART_NAME='Q_RES_0201LF-0,5%,1/20W,CHIP,CS00001JE10',
 PART_NUMBER='CS00001JE10',
 VALUE='0',
 PRIM_FILE='./archive_libs/logical/q_res/chips/chips.prt';

PART_NAME
 R802 'Q_RES_0201LF-0,5%,1/20W,CHIP,CS00001JE10':;

SECTION_NUMBER 1
 '@T6G_MB_LIB.T6G(SCH_1):PAGE377_I50@PURE_QUANTA.Q_RES(CHIPS)':
 C_PATH='@t6g_mb_lib.t6g(sch_1):page377_i50@pure_quanta.q_res(chips)',
 P_PATH='@t6g_mb_lib.t6g(sch_1):page185_i50@pure_quanta.q_res(chips)',
 PATH='I50',
 DRAWING='@T6G_MB_LIB.T6G(SCH_1):PAGE377',
 SEC_TYPE='0201LF',
 WATTAGE='1/20W',
 TOLERANCE='5%',
 MATERIAL='CHIP',
 PHYS_PAGE='185',
 XY='(-6425,5400)',
 ROT='0',
 VER='1',
 PACK_TYPE='0201LF',
 LOCATION='R802',
 SEC='1',
 CDS_LIB='pure_quanta',
 CDS_PART_NAME='Q_RES_0201LF-0,5%,1/20W,CHIP,CS00001JE10',
 PART_NUMBER='CS00001JE10',
 VALUE='0',
 PRIM_FILE='./archive_libs/logical/q_res/chips/chips.prt';

PART_NAME
 R803 'Q_RES_0201LF-0,5%,1/20W,CHIP,CS00001JE10':;

SECTION_NUMBER 1
 '@T6G_MB_LIB.T6G(SCH_1):PAGE377_I48@PURE_QUANTA.Q_RES(CHIPS)':
 C_PATH='@t6g_mb_lib.t6g(sch_1):page377_i48@pure_quanta.q_res(chips)',
 P_PATH='@t6g_mb_lib.t6g(sch_1):page185_i48@pure_quanta.q_res(chips)',
 PATH='I48',
 DRAWING='@T6G_MB_LIB.T6G(SCH_1):PAGE377',
 WATTAGE='1/20W',
 TOLERANCE='5%',
 MATERIAL='CHIP',
 PHYS_PAGE='185',
 XY='(-6425,5350)',
 ROT='0',
 VER='1',
 PACK_TYPE='0201LF',
 LOCATION='R803',
 CDS_LIB='pure_quanta',
 CDS_PART_NAME='Q_RES_0201LF-0,5%,1/20W,CHIP,CS00001JE10',
 PART_NUMBER='CS00001JE10',
 VALUE='0',
 PRIM_FILE='./archive_libs/logical/q_res/chips/chips.prt';

PART_NAME
 R804 'Q_RES_0402LF-10K,1%,1/16W,CHIP,CS31002FB08':;

SECTION_NUMBER 1
 '@T6G_MB_LIB.T6G(SCH_1):PAGE82_I120@PURE_QUANTA.Q_RES(CHIPS)':
 C_PATH='@t6g_mb_lib.t6g(sch_1):page82_i120@pure_quanta.q_res(chips)',
 P_PATH='@t6g_mb_lib.t6g(sch_1):page83_i120@pure_quanta.q_res(chips)',
 PATH='I120',
 DRAWING='@T6G_MB_LIB.T6G(SCH_1):PAGE82',
 BOM_COST='MEM',
 WATTAGE='1/16W',
 TOLERANCE='1%',
 MATERIAL='CHIP',
 PHYS_PAGE='83',
 XY='(-3425,4475)',
 ROT='0',
 VER='2',
 PACK_TYPE='0402LF',
 LOCATION='R804',
 CDS_LIB='pure_quanta',
 CDS_PART_NAME='Q_RES_0402LF-10K,1%,1/16W,CHIP,CS31002FB08',
 PART_NUMBER='CS31002FB08',
 VALUE='10K',
 PRIM_FILE='./archive_libs/logical/q_res/chips/chips.prt';

PART_NAME
 R805 'Q_RES_0201LF-0,5%,1/20W,CHIP,CS00001JE10':;

SECTION_NUMBER 1
 '@T6G_MB_LIB.T6G(SCH_1):PAGE377_I46@PURE_QUANTA.Q_RES(CHIPS)':
 C_PATH='@t6g_mb_lib.t6g(sch_1):page377_i46@pure_quanta.q_res(chips)',
 P_PATH='@t6g_mb_lib.t6g(sch_1):page185_i46@pure_quanta.q_res(chips)',
 PATH='I46',
 DRAWING='@T6G_MB_LIB.T6G(SCH_1):PAGE377',
 WATTAGE='1/20W',
 TOLERANCE='5%',
 MATERIAL='CHIP',
 PHYS_PAGE='185',
 XY='(-6425,5300)',
 ROT='0',
 VER='1',
 PACK_TYPE='0201LF',
 LOCATION='R805',
 CDS_LIB='pure_quanta',
 CDS_PART_NAME='Q_RES_0201LF-0,5%,1/20W,CHIP,CS00001JE10',
 PART_NUMBER='CS00001JE10',
 VALUE='0',
 PRIM_FILE='./archive_libs/logical/q_res/chips/chips.prt';

PART_NAME
 R806 'Q_RES_0201LF-0,5%,1/20W,CHIP,CS00001JE10':;

SECTION_NUMBER 1
 '@T6G_MB_LIB.T6G(SCH_1):PAGE377_I47@PURE_QUANTA.Q_RES(CHIPS)':
 C_PATH='@t6g_mb_lib.t6g(sch_1):page377_i47@pure_quanta.q_res(chips)',
 P_PATH='@t6g_mb_lib.t6g(sch_1):page185_i47@pure_quanta.q_res(chips)',
 PATH='I47',
 DRAWING='@T6G_MB_LIB.T6G(SCH_1):PAGE377',
 WATTAGE='1/20W',
 TOLERANCE='5%',
 MATERIAL='CHIP',
 PHYS_PAGE='185',
 XY='(-6425,5250)',
 ROT='0',
 VER='1',
 PACK_TYPE='0201LF',
 LOCATION='R806',
 CDS_LIB='pure_quanta',
 CDS_PART_NAME='Q_RES_0201LF-0,5%,1/20W,CHIP,CS00001JE10',
 PART_NUMBER='CS00001JE10',
 VALUE='0',
 PRIM_FILE='./archive_libs/logical/q_res/chips/chips.prt';

PART_NAME
 R807 'Q_RES_0201LF-0,5%,1/20W,CHIP,CS00001JE10':;

SECTION_NUMBER 1
 '@T6G_MB_LIB.T6G(SCH_1):PAGE377_I43@PURE_QUANTA.Q_RES(CHIPS)':
 C_PATH='@t6g_mb_lib.t6g(sch_1):page377_i43@pure_quanta.q_res(chips)',
 P_PATH='@t6g_mb_lib.t6g(sch_1):page185_i43@pure_quanta.q_res(chips)',
 PATH='I43',
 DRAWING='@T6G_MB_LIB.T6G(SCH_1):PAGE377',
 WATTAGE='1/20W',
 TOLERANCE='5%',
 MATERIAL='CHIP',
 PHYS_PAGE='185',
 XY='(-6425,5200)',
 ROT='0',
 VER='1',
 PACK_TYPE='0201LF',
 LOCATION='R807',
 CDS_LIB='pure_quanta',
 CDS_PART_NAME='Q_RES_0201LF-0,5%,1/20W,CHIP,CS00001JE10',
 PART_NUMBER='CS00001JE10',
 VALUE='0',
 PRIM_FILE='./archive_libs/logical/q_res/chips/chips.prt';

PART_NAME
 R808 'Q_RES_0201LF-0,5%,1/20W,CHIP,CS00001JE10':;

SECTION_NUMBER 1
 '@T6G_MB_LIB.T6G(SCH_1):PAGE377_I45@PURE_QUANTA.Q_RES(CHIPS)':
 C_PATH='@t6g_mb_lib.t6g(sch_1):page377_i45@pure_quanta.q_res(chips)',
 P_PATH='@t6g_mb_lib.t6g(sch_1):page185_i45@pure_quanta.q_res(chips)',
 PATH='I45',
 DRAWING='@T6G_MB_LIB.T6G(SCH_1):PAGE377',
 WATTAGE='1/20W',
 TOLERANCE='5%',
 MATERIAL='CHIP',
 PHYS_PAGE='185',
 XY='(-6425,5150)',
 ROT='0',
 VER='1',
 PACK_TYPE='0201LF',
 LOCATION='R808',
 CDS_LIB='pure_quanta',
 CDS_PART_NAME='Q_RES_0201LF-0,5%,1/20W,CHIP,CS00001JE10',
 PART_NUMBER='CS00001JE10',
 VALUE='0',
 PRIM_FILE='./archive_libs/logical/q_res/chips/chips.prt';

PART_NAME
 R809 'Q_RES_0201LF-0,5%,1/20W,CHIP,CS00001JE10':;

SECTION_NUMBER 1
 '@T6G_MB_LIB.T6G(SCH_1):PAGE377_I44@PURE_QUANTA.Q_RES(CHIPS)':
 C_PATH='@t6g_mb_lib.t6g(sch_1):page377_i44@pure_quanta.q_res(chips)',
 P_PATH='@t6g_mb_lib.t6g(sch_1):page185_i44@pure_quanta.q_res(chips)',
 PATH='I44',
 DRAWING='@T6G_MB_LIB.T6G(SCH_1):PAGE377',
 WATTAGE='1/20W',
 TOLERANCE='5%',
 MATERIAL='CHIP',
 PHYS_PAGE='185',
 XY='(-6425,5100)',
 ROT='0',
 VER='1',
 PACK_TYPE='0201LF',
 LOCATION='R809',
 CDS_LIB='pure_quanta',
 CDS_PART_NAME='Q_RES_0201LF-0,5%,1/20W,CHIP,CS00001JE10',
 PART_NUMBER='CS00001JE10',
 VALUE='0',
 PRIM_FILE='./archive_libs/logical/q_res/chips/chips.prt';

PART_NAME
 R810 'Q_RES_0201LF-1K,1%,1/20W,CHIP,CS21001FE07':;

SECTION_NUMBER 1
 '@T6G_MB_LIB.T6G(SCH_1):PAGE377_I61@PURE_QUANTA.Q_RES(CHIPS)':
 C_PATH='@t6g_mb_lib.t6g(sch_1):page377_i61@pure_quanta.q_res(chips)',
 P_PATH='@t6g_mb_lib.t6g(sch_1):page185_i61@pure_quanta.q_res(chips)',
 PATH='I61',
 DRAWING='@T6G_MB_LIB.T6G(SCH_1):PAGE377',
 WATTAGE='1/20W',
 TOLERANCE='1%',
 MATERIAL='CHIP',
 PHYS_PAGE='185',
 XY='(-2550,1375)',
 ROT='0',
 VER='1',
 PACK_TYPE='0201LF',
 LOCATION='R810',
 CDS_LIB='pure_quanta',
 CDS_PART_NAME='Q_RES_0201LF-1K,1%,1/20W,CHIP,CS21001FE07',
 PART_NUMBER='CS21001FE07',
 VALUE='1K',
 PRIM_FILE='./archive_libs/logical/q_res/chips/chips.prt';

PART_NAME
 R811 'Q_RES_0402LF-1K,1%,1/16W,CHIP,CS21002FB06':;

SECTION_NUMBER 1
 '@T6G_MB_LIB.T6G(SCH_1):PAGE76_I106@PURE_QUANTA.Q_RES(CHIPS)':
 C_PATH='@t6g_mb_lib.t6g(sch_1):page76_i106@pure_quanta.q_res(chips)',
 P_PATH='@t6g_mb_lib.t6g(sch_1):page77_i106@pure_quanta.q_res(chips)',
 PATH='I106',
 DRAWING='@T6G_MB_LIB.T6G(SCH_1):PAGE76',
 WATTAGE='1/16W',
 TOLERANCE='1%',
 MATERIAL='CHIP',
 PHYS_PAGE='77',
 XY='(-8025,5875)',
 ROT='0',
 VER='2',
 PACK_TYPE='0402LF',
 LOCATION='R811',
 CDS_LIB='pure_quanta',
 CDS_PART_NAME='Q_RES_0402LF-1K,1%,1/16W,CHIP,CS21002FB06',
 PART_NUMBER='CS21002FB06',
 VALUE='1K',
 PRIM_FILE='./archive_libs/logical/q_res/chips/chips.prt';

PART_NAME
 R812 'Q_RES_0201LF-1K,1%,1/20W,CHIP,CS21001FE07':;

SECTION_NUMBER 1
 '@T6G_MB_LIB.T6G(SCH_1):PAGE377_I60@PURE_QUANTA.Q_RES(CHIPS)':
 C_PATH='@t6g_mb_lib.t6g(sch_1):page377_i60@pure_quanta.q_res(chips)',
 P_PATH='@t6g_mb_lib.t6g(sch_1):page185_i60@pure_quanta.q_res(chips)',
 PATH='I60',
 DRAWING='@T6G_MB_LIB.T6G(SCH_1):PAGE377',
 WATTAGE='1/20W',
 TOLERANCE='1%',
 MATERIAL='CHIP',
 PHYS_PAGE='185',
 XY='(-2550,1300)',
 ROT='0',
 VER='1',
 PACK_TYPE='0201LF',
 LOCATION='R812',
 CDS_LIB='pure_quanta',
 CDS_PART_NAME='Q_RES_0201LF-1K,1%,1/20W,CHIP,CS21001FE07',
 PART_NUMBER='CS21001FE07',
 VALUE='1K',
 PRIM_FILE='./archive_libs/logical/q_res/chips/chips.prt';

PART_NAME
 R813 'Q_RES_0402LF-10K,5%,1/16W,CHIP,CS31002JB08':;

SECTION_NUMBER 1
 '@T6G_MB_LIB.T6G(SCH_1):PAGE141_I199@PURE_QUANTA.Q_RES(CHIPS)':
 C_PATH='@t6g_mb_lib.t6g(sch_1):page141_i199@pure_quanta.q_res(chips)',
 P_PATH='@t6g_mb_lib.t6g(sch_1):page164_i199@pure_quanta.q_res(chips)',
 PATH='I199',
 DRAWING='@T6G_MB_LIB.T6G(SCH_1):PAGE141',
 WATTAGE='1/16W',
 TOLERANCE='5%',
 MATERIAL='CHIP',
 PHYS_PAGE='164',
 XY='(-8050,4125)',
 ROT='0',
 VER='2',
 PACK_TYPE='0402LF',
 LOCATION='R813',
 CDS_LIB='pure_quanta',
 CDS_PART_NAME='Q_RES_0402LF-10K,5%,1/16W,CHIP,CS31002JB08',
 PART_NUMBER='CS31002JB08',
 VALUE='10K',
 PRIM_FILE='./archive_libs/logical/q_res/chips/chips.prt';

PART_NAME
 R814 'Q_RES_0402LF-10K,5%,1/16W,EMPTY,CS31002JB08':;

SECTION_NUMBER 1
 '@T6G_MB_LIB.T6G(SCH_1):PAGE141_I198@PURE_QUANTA.Q_RES(CHIPS)':
 C_PATH='@t6g_mb_lib.t6g(sch_1):page141_i198@pure_quanta.q_res(chips)',
 P_PATH='@t6g_mb_lib.t6g(sch_1):page164_i198@pure_quanta.q_res(chips)',
 PATH='I198',
 DRAWING='@T6G_MB_LIB.T6G(SCH_1):PAGE141',
 WATTAGE='1/16W',
 TOLERANCE='5%',
 MATERIAL='EMPTY',
 PHYS_PAGE='164',
 XY='(-7850,4125)',
 ROT='0',
 VER='2',
 PACK_TYPE='0402LF',
 LOCATION='R814',
 CDS_LIB='pure_quanta',
 CDS_PART_NAME='Q_RES_0402LF-10K,5%,1/16W,EMPTY,CS31002JB08',
 PART_NUMBER='CS31002JB08',
 VALUE='10K',
 PRIM_FILE='./archive_libs/logical/q_res/chips/chips.prt';

PART_NAME
 R815 'Q_RES_0402LF-10K,5%,1/16W,EMPTY,CS31002JB08':;

SECTION_NUMBER 1
 '@T6G_MB_LIB.T6G(SCH_1):PAGE141_I197@PURE_QUANTA.Q_RES(CHIPS)':
 C_PATH='@t6g_mb_lib.t6g(sch_1):page141_i197@pure_quanta.q_res(chips)',
 P_PATH='@t6g_mb_lib.t6g(sch_1):page164_i197@pure_quanta.q_res(chips)',
 PATH='I197',
 DRAWING='@T6G_MB_LIB.T6G(SCH_1):PAGE141',
 WATTAGE='1/16W',
 TOLERANCE='5%',
 MATERIAL='EMPTY',
 PHYS_PAGE='164',
 XY='(-7625,4125)',
 ROT='0',
 VER='2',
 PACK_TYPE='0402LF',
 LOCATION='R815',
 CDS_LIB='pure_quanta',
 CDS_PART_NAME='Q_RES_0402LF-10K,5%,1/16W,EMPTY,CS31002JB08',
 PART_NUMBER='CS31002JB08',
 VALUE='10K',
 PRIM_FILE='./archive_libs/logical/q_res/chips/chips.prt';

PART_NAME
 R816 'Q_RES_0402LF-10K,5%,1/16W,CHIP,CS31002JB08':;

SECTION_NUMBER 1
 '@T6G_MB_LIB.T6G(SCH_1):PAGE141_I196@PURE_QUANTA.Q_RES(CHIPS)':
 C_PATH='@t6g_mb_lib.t6g(sch_1):page141_i196@pure_quanta.q_res(chips)',
 P_PATH='@t6g_mb_lib.t6g(sch_1):page164_i196@pure_quanta.q_res(chips)',
 PATH='I196',
 DRAWING='@T6G_MB_LIB.T6G(SCH_1):PAGE141',
 WATTAGE='1/16W',
 TOLERANCE='5%',
 MATERIAL='CHIP',
 PHYS_PAGE='164',
 XY='(-7425,4125)',
 ROT='0',
 VER='2',
 PACK_TYPE='0402LF',
 LOCATION='R816',
 CDS_LIB='pure_quanta',
 CDS_PART_NAME='Q_RES_0402LF-10K,5%,1/16W,CHIP,CS31002JB08',
 PART_NUMBER='CS31002JB08',
 VALUE='10K',
 PRIM_FILE='./archive_libs/logical/q_res/chips/chips.prt';

PART_NAME
 R817 'Q_RES_0402LF-0,5%,1/16W,CHIP,CS00002JB13':;

SECTION_NUMBER 1
 '@T6G_MB_LIB.T6G(SCH_1):PAGE141_I231@PURE_QUANTA.Q_RES(CHIPS)':
 C_PATH='@t6g_mb_lib.t6g(sch_1):page141_i231@pure_quanta.q_res(chips)',
 P_PATH='@t6g_mb_lib.t6g(sch_1):page164_i231@pure_quanta.q_res(chips)',
 PATH='I231',
 DRAWING='@T6G_MB_LIB.T6G(SCH_1):PAGE141',
 WATTAGE='1/16W',
 TOLERANCE='5%',
 MATERIAL='CHIP',
 PHYS_PAGE='164',
 XY='(-5825,3300)',
 ROT='0',
 VER='1',
 PACK_TYPE='0402LF',
 LOCATION='R817',
 CDS_LIB='pure_quanta',
 CDS_PART_NAME='Q_RES_0402LF-0,5%,1/16W,CHIP,CS00002JB13',
 PART_NUMBER='CS00002JB13',
 VALUE='0',
 PRIM_FILE='./archive_libs/logical/q_res/chips/chips.prt';

PART_NAME
 R818 'Q_RES_0402LF-0,5%,1/16W,CHIP,CS00002JB13':;

SECTION_NUMBER 1
 '@T6G_MB_LIB.T6G(SCH_1):PAGE141_I220@PURE_QUANTA.Q_RES(CHIPS)':
 C_PATH='@t6g_mb_lib.t6g(sch_1):page141_i220@pure_quanta.q_res(chips)',
 P_PATH='@t6g_mb_lib.t6g(sch_1):page164_i220@pure_quanta.q_res(chips)',
 PATH='I220',
 DRAWING='@T6G_MB_LIB.T6G(SCH_1):PAGE141',
 WATTAGE='1/16W',
 TOLERANCE='5%',
 MATERIAL='CHIP',
 PHYS_PAGE='164',
 XY='(-3050,3350)',
 ROT='0',
 VER='1',
 PACK_TYPE='0402LF',
 LOCATION='R818',
 CDS_LIB='pure_quanta',
 CDS_PART_NAME='Q_RES_0402LF-0,5%,1/16W,CHIP,CS00002JB13',
 PART_NUMBER='CS00002JB13',
 VALUE='0',
 PRIM_FILE='./archive_libs/logical/q_res/chips/chips.prt';

PART_NAME
 R819 'Q_RES_0402LF-0,5%,1/16W,CHIP,CS00002JB13':;

SECTION_NUMBER 1
 '@T6G_MB_LIB.T6G(SCH_1):PAGE141_I212@PURE_QUANTA.Q_RES(CHIPS)':
 C_PATH='@t6g_mb_lib.t6g(sch_1):page141_i212@pure_quanta.q_res(chips)',
 P_PATH='@t6g_mb_lib.t6g(sch_1):page164_i212@pure_quanta.q_res(chips)',
 PATH='I212',
 DRAWING='@T6G_MB_LIB.T6G(SCH_1):PAGE141',
 WATTAGE='1/16W',
 TOLERANCE='5%',
 MATERIAL='CHIP',
 PHYS_PAGE='164',
 XY='(-2950,1425)',
 ROT='0',
 VER='1',
 PACK_TYPE='0402LF',
 LOCATION='R819',
 CDS_LIB='pure_quanta',
 CDS_PART_NAME='Q_RES_0402LF-0,5%,1/16W,CHIP,CS00002JB13',
 PART_NUMBER='CS00002JB13',
 VALUE='0',
 PRIM_FILE='./archive_libs/logical/q_res/chips/chips.prt';

PART_NAME
 R820 'Q_RES_0402LF-10K,5%,1/16W,EMPTY,CS31002JB08':;

SECTION_NUMBER 1
 '@T6G_MB_LIB.T6G(SCH_1):PAGE141_I186@PURE_QUANTA.Q_RES(CHIPS)':
 C_PATH='@t6g_mb_lib.t6g(sch_1):page141_i186@pure_quanta.q_res(chips)',
 P_PATH='@t6g_mb_lib.t6g(sch_1):page164_i186@pure_quanta.q_res(chips)',
 PATH='I186',
 DRAWING='@T6G_MB_LIB.T6G(SCH_1):PAGE141',
 WATTAGE='1/16W',
 TOLERANCE='5%',
 MATERIAL='EMPTY',
 PHYS_PAGE='164',
 XY='(-2375,1100)',
 ROT='1',
 VER='1',
 PACK_TYPE='0402LF',
 LOCATION='R820',
 CDS_LIB='pure_quanta',
 CDS_PART_NAME='Q_RES_0402LF-10K,5%,1/16W,EMPTY,CS31002JB08',
 PART_NUMBER='CS31002JB08',
 VALUE='10K',
 PRIM_FILE='./archive_libs/logical/q_res/chips/chips.prt';

PART_NAME
 R821 'Q_RES_0402LF-10K,5%,1/16W,CHIP,CS31002JB08':;

SECTION_NUMBER 1
 '@T6G_MB_LIB.T6G(SCH_1):PAGE141_I185@PURE_QUANTA.Q_RES(CHIPS)':
 C_PATH='@t6g_mb_lib.t6g(sch_1):page141_i185@pure_quanta.q_res(chips)',
 P_PATH='@t6g_mb_lib.t6g(sch_1):page164_i185@pure_quanta.q_res(chips)',
 PATH='I185',
 DRAWING='@T6G_MB_LIB.T6G(SCH_1):PAGE141',
 WATTAGE='1/16W',
 TOLERANCE='5%',
 MATERIAL='CHIP',
 PHYS_PAGE='164',
 XY='(-2150,1075)',
 ROT='0',
 VER='2',
 PACK_TYPE='0402LF',
 LOCATION='R821',
 CDS_LIB='pure_quanta',
 CDS_PART_NAME='Q_RES_0402LF-10K,5%,1/16W,CHIP,CS31002JB08',
 PART_NUMBER='CS31002JB08',
 VALUE='10K',
 PRIM_FILE='./archive_libs/logical/q_res/chips/chips.prt';

PART_NAME
 R822 'Q_RES_0402LF-10K,5%,1/16W,CHIP,CS31002JB08':;

SECTION_NUMBER 1
 '@T6G_MB_LIB.T6G(SCH_1):PAGE141_I206@PURE_QUANTA.Q_RES(CHIPS)':
 C_PATH='@t6g_mb_lib.t6g(sch_1):page141_i206@pure_quanta.q_res(chips)',
 P_PATH='@t6g_mb_lib.t6g(sch_1):page164_i206@pure_quanta.q_res(chips)',
 PATH='I206',
 DRAWING='@T6G_MB_LIB.T6G(SCH_1):PAGE141',
 WATTAGE='1/16W',
 TOLERANCE='5%',
 MATERIAL='CHIP',
 PHYS_PAGE='164',
 XY='(-1250,4425)',
 ROT='0',
 VER='2',
 PACK_TYPE='0402LF',
 LOCATION='R822',
 CDS_LIB='pure_quanta',
 CDS_PART_NAME='Q_RES_0402LF-10K,5%,1/16W,CHIP,CS31002JB08',
 PART_NUMBER='CS31002JB08',
 VALUE='10K',
 PRIM_FILE='./archive_libs/logical/q_res/chips/chips.prt';

PART_NAME
 R823 'Q_RES_0402LF-10K,5%,1/16W,EMPTY,CS31002JB08':;

SECTION_NUMBER 1
 '@T6G_MB_LIB.T6G(SCH_1):PAGE141_I205@PURE_QUANTA.Q_RES(CHIPS)':
 C_PATH='@t6g_mb_lib.t6g(sch_1):page141_i205@pure_quanta.q_res(chips)',
 P_PATH='@t6g_mb_lib.t6g(sch_1):page164_i205@pure_quanta.q_res(chips)',
 PATH='I205',
 DRAWING='@T6G_MB_LIB.T6G(SCH_1):PAGE141',
 WATTAGE='1/16W',
 TOLERANCE='5%',
 MATERIAL='EMPTY',
 PHYS_PAGE='164',
 XY='(-1050,4425)',
 ROT='0',
 VER='2',
 PACK_TYPE='0402LF',
 LOCATION='R823',
 CDS_LIB='pure_quanta',
 CDS_PART_NAME='Q_RES_0402LF-10K,5%,1/16W,EMPTY,CS31002JB08',
 PART_NUMBER='CS31002JB08',
 VALUE='10K',
 PRIM_FILE='./archive_libs/logical/q_res/chips/chips.prt';

PART_NAME
 R824 'Q_RES_0402LF-10K,5%,1/16W,CHIP,CS31002JB08':;

SECTION_NUMBER 1
 '@T6G_MB_LIB.T6G(SCH_1):PAGE141_I204@PURE_QUANTA.Q_RES(CHIPS)':
 C_PATH='@t6g_mb_lib.t6g(sch_1):page141_i204@pure_quanta.q_res(chips)',
 P_PATH='@t6g_mb_lib.t6g(sch_1):page164_i204@pure_quanta.q_res(chips)',
 PATH='I204',
 DRAWING='@T6G_MB_LIB.T6G(SCH_1):PAGE141',
 WATTAGE='1/16W',
 TOLERANCE='5%',
 MATERIAL='CHIP',
 PHYS_PAGE='164',
 XY='(-825,4425)',
 ROT='0',
 VER='2',
 PACK_TYPE='0402LF',
 LOCATION='R824',
 CDS_LIB='pure_quanta',
 CDS_PART_NAME='Q_RES_0402LF-10K,5%,1/16W,CHIP,CS31002JB08',
 PART_NUMBER='CS31002JB08',
 VALUE='10K',
 PRIM_FILE='./archive_libs/logical/q_res/chips/chips.prt';

PART_NAME
 R825 'Q_RES_0402LF-10K,5%,1/16W,EMPTY,CS31002JB08':;

SECTION_NUMBER 1
 '@T6G_MB_LIB.T6G(SCH_1):PAGE141_I203@PURE_QUANTA.Q_RES(CHIPS)':
 C_PATH='@t6g_mb_lib.t6g(sch_1):page141_i203@pure_quanta.q_res(chips)',
 P_PATH='@t6g_mb_lib.t6g(sch_1):page164_i203@pure_quanta.q_res(chips)',
 PATH='I203',
 DRAWING='@T6G_MB_LIB.T6G(SCH_1):PAGE141',
 WATTAGE='1/16W',
 TOLERANCE='5%',
 MATERIAL='EMPTY',
 PHYS_PAGE='164',
 XY='(-625,4425)',
 ROT='0',
 VER='2',
 PACK_TYPE='0402LF',
 LOCATION='R825',
 CDS_LIB='pure_quanta',
 CDS_PART_NAME='Q_RES_0402LF-10K,5%,1/16W,EMPTY,CS31002JB08',
 PART_NUMBER='CS31002JB08',
 VALUE='10K',
 PRIM_FILE='./archive_libs/logical/q_res/chips/chips.prt';

PART_NAME
 R826 'Q_RES_0201LF-1K,1%,1/20W,CHIP,CS21001FE07':;

SECTION_NUMBER 1
 '@T6G_MB_LIB.T6G(SCH_1):PAGE377_I59@PURE_QUANTA.Q_RES(CHIPS)':
 C_PATH='@t6g_mb_lib.t6g(sch_1):page377_i59@pure_quanta.q_res(chips)',
 P_PATH='@t6g_mb_lib.t6g(sch_1):page185_i59@pure_quanta.q_res(chips)',
 PATH='I59',
 DRAWING='@T6G_MB_LIB.T6G(SCH_1):PAGE377',
 WATTAGE='1/20W',
 TOLERANCE='1%',
 MATERIAL='CHIP',
 PHYS_PAGE='185',
 XY='(-2550,1225)',
 ROT='0',
 VER='1',
 PACK_TYPE='0201LF',
 LOCATION='R826',
 CDS_LIB='pure_quanta',
 CDS_PART_NAME='Q_RES_0201LF-1K,1%,1/20W,CHIP,CS21001FE07',
 PART_NUMBER='CS21001FE07',
 VALUE='1K',
 PRIM_FILE='./archive_libs/logical/q_res/chips/chips.prt';

PART_NAME
 R827 'Q_RES_0201LF-1K,1%,1/20W,CHIP,CS21001FE07':;

SECTION_NUMBER 1
 '@T6G_MB_LIB.T6G(SCH_1):PAGE377_I58@PURE_QUANTA.Q_RES(CHIPS)':
 C_PATH='@t6g_mb_lib.t6g(sch_1):page377_i58@pure_quanta.q_res(chips)',
 P_PATH='@t6g_mb_lib.t6g(sch_1):page185_i58@pure_quanta.q_res(chips)',
 PATH='I58',
 DRAWING='@T6G_MB_LIB.T6G(SCH_1):PAGE377',
 WATTAGE='1/20W',
 TOLERANCE='1%',
 MATERIAL='CHIP',
 PHYS_PAGE='185',
 XY='(-2550,1150)',
 ROT='0',
 VER='1',
 PACK_TYPE='0201LF',
 LOCATION='R827',
 CDS_LIB='pure_quanta',
 CDS_PART_NAME='Q_RES_0201LF-1K,1%,1/20W,CHIP,CS21001FE07',
 PART_NUMBER='CS21001FE07',
 VALUE='1K',
 PRIM_FILE='./archive_libs/logical/q_res/chips/chips.prt';

PART_NAME
 R828 'Q_RES_0201LF-0,5%,1/20W,CHIP,CS00001JE10':;

SECTION_NUMBER 1
 '@T6G_MB_LIB.T6G(SCH_1):PAGE377_I76@PURE_QUANTA.Q_RES(CHIPS)':
 C_PATH='@t6g_mb_lib.t6g(sch_1):page377_i76@pure_quanta.q_res(chips)',
 P_PATH='@t6g_mb_lib.t6g(sch_1):page185_i76@pure_quanta.q_res(chips)',
 PATH='I76',
 DRAWING='@T6G_MB_LIB.T6G(SCH_1):PAGE377',
 WATTAGE='1/20W',
 TOLERANCE='5%',
 MATERIAL='CHIP',
 PHYS_PAGE='185',
 XY='(-2775,5350)',
 ROT='0',
 VER='1',
 PACK_TYPE='0201LF',
 LOCATION='R828',
 CDS_LIB='pure_quanta',
 CDS_PART_NAME='Q_RES_0201LF-0,5%,1/20W,CHIP,CS00001JE10',
 PART_NUMBER='CS00001JE10',
 VALUE='0',
 PRIM_FILE='./archive_libs/logical/q_res/chips/chips.prt';

PART_NAME
 R829 'Q_RES_0201LF-0,5%,1/20W,CHIP,CS00001JE10':;

SECTION_NUMBER 1
 '@T6G_MB_LIB.T6G(SCH_1):PAGE377_I77@PURE_QUANTA.Q_RES(CHIPS)':
 C_PATH='@t6g_mb_lib.t6g(sch_1):page377_i77@pure_quanta.q_res(chips)',
 P_PATH='@t6g_mb_lib.t6g(sch_1):page185_i77@pure_quanta.q_res(chips)',
 PATH='I77',
 DRAWING='@T6G_MB_LIB.T6G(SCH_1):PAGE377',
 WATTAGE='1/20W',
 TOLERANCE='5%',
 MATERIAL='CHIP',
 PHYS_PAGE='185',
 XY='(-2775,5300)',
 ROT='0',
 VER='1',
 PACK_TYPE='0201LF',
 LOCATION='R829',
 CDS_LIB='pure_quanta',
 CDS_PART_NAME='Q_RES_0201LF-0,5%,1/20W,CHIP,CS00001JE10',
 PART_NUMBER='CS00001JE10',
 VALUE='0',
 PRIM_FILE='./archive_libs/logical/q_res/chips/chips.prt';

PART_NAME
 R830 'Q_RES_0201LF-0,5%,1/20W,CHIP,CS00001JE10':;

SECTION_NUMBER 1
 '@T6G_MB_LIB.T6G(SCH_1):PAGE377_I78@PURE_QUANTA.Q_RES(CHIPS)':
 C_PATH='@t6g_mb_lib.t6g(sch_1):page377_i78@pure_quanta.q_res(chips)',
 P_PATH='@t6g_mb_lib.t6g(sch_1):page185_i78@pure_quanta.q_res(chips)',
 PATH='I78',
 DRAWING='@T6G_MB_LIB.T6G(SCH_1):PAGE377',
 WATTAGE='1/20W',
 TOLERANCE='5%',
 MATERIAL='CHIP',
 PHYS_PAGE='185',
 XY='(-2775,5250)',
 ROT='0',
 VER='1',
 PACK_TYPE='0201LF',
 LOCATION='R830',
 CDS_LIB='pure_quanta',
 CDS_PART_NAME='Q_RES_0201LF-0,5%,1/20W,CHIP,CS00001JE10',
 PART_NUMBER='CS00001JE10',
 VALUE='0',
 PRIM_FILE='./archive_libs/logical/q_res/chips/chips.prt';

PART_NAME
 R831 'Q_RES_0201LF-0,5%,1/20W,CHIP,CS00001JE10':;

SECTION_NUMBER 1
 '@T6G_MB_LIB.T6G(SCH_1):PAGE377_I74@PURE_QUANTA.Q_RES(CHIPS)':
 C_PATH='@t6g_mb_lib.t6g(sch_1):page377_i74@pure_quanta.q_res(chips)',
 P_PATH='@t6g_mb_lib.t6g(sch_1):page185_i74@pure_quanta.q_res(chips)',
 PATH='I74',
 DRAWING='@T6G_MB_LIB.T6G(SCH_1):PAGE377',
 WATTAGE='1/20W',
 TOLERANCE='5%',
 MATERIAL='CHIP',
 PHYS_PAGE='185',
 XY='(-2775,5200)',
 ROT='0',
 VER='1',
 PACK_TYPE='0201LF',
 LOCATION='R831',
 CDS_LIB='pure_quanta',
 CDS_PART_NAME='Q_RES_0201LF-0,5%,1/20W,CHIP,CS00001JE10',
 PART_NUMBER='CS00001JE10',
 VALUE='0',
 PRIM_FILE='./archive_libs/logical/q_res/chips/chips.prt';

PART_NAME
 R832 'Q_RES_0201LF-0,5%,1/20W,CHIP,CS00001JE10':;

SECTION_NUMBER 1
 '@T6G_MB_LIB.T6G(SCH_1):PAGE377_I75@PURE_QUANTA.Q_RES(CHIPS)':
 C_PATH='@t6g_mb_lib.t6g(sch_1):page377_i75@pure_quanta.q_res(chips)',
 P_PATH='@t6g_mb_lib.t6g(sch_1):page185_i75@pure_quanta.q_res(chips)',
 PATH='I75',
 DRAWING='@T6G_MB_LIB.T6G(SCH_1):PAGE377',
 WATTAGE='1/20W',
 TOLERANCE='5%',
 MATERIAL='CHIP',
 PHYS_PAGE='185',
 XY='(-2775,5150)',
 ROT='0',
 VER='1',
 PACK_TYPE='0201LF',
 LOCATION='R832',
 CDS_LIB='pure_quanta',
 CDS_PART_NAME='Q_RES_0201LF-0,5%,1/20W,CHIP,CS00001JE10',
 PART_NUMBER='CS00001JE10',
 VALUE='0',
 PRIM_FILE='./archive_libs/logical/q_res/chips/chips.prt';

PART_NAME
 R833 'Q_RES_0201LF-0,5%,1/20W,CHIP,CS00001JE10':;

SECTION_NUMBER 1
 '@T6G_MB_LIB.T6G(SCH_1):PAGE377_I73@PURE_QUANTA.Q_RES(CHIPS)':
 C_PATH='@t6g_mb_lib.t6g(sch_1):page377_i73@pure_quanta.q_res(chips)',
 P_PATH='@t6g_mb_lib.t6g(sch_1):page185_i73@pure_quanta.q_res(chips)',
 PATH='I73',
 DRAWING='@T6G_MB_LIB.T6G(SCH_1):PAGE377',
 WATTAGE='1/20W',
 TOLERANCE='5%',
 MATERIAL='CHIP',
 PHYS_PAGE='185',
 XY='(-2775,5100)',
 ROT='0',
 VER='1',
 PACK_TYPE='0201LF',
 LOCATION='R833',
 CDS_LIB='pure_quanta',
 CDS_PART_NAME='Q_RES_0201LF-0,5%,1/20W,CHIP,CS00001JE10',
 PART_NUMBER='CS00001JE10',
 VALUE='0',
 PRIM_FILE='./archive_libs/logical/q_res/chips/chips.prt';

PART_NAME
 R834 'Q_RES_0201LF-1K,1%,1/20W,CHIP,CS21001FE07':;

SECTION_NUMBER 1
 '@T6G_MB_LIB.T6G(SCH_1):PAGE377_I24@PURE_QUANTA.Q_RES(CHIPS)':
 C_PATH='@t6g_mb_lib.t6g(sch_1):page377_i24@pure_quanta.q_res(chips)',
 P_PATH='@t6g_mb_lib.t6g(sch_1):page185_i24@pure_quanta.q_res(chips)',
 PATH='I24',
 DRAWING='@T6G_MB_LIB.T6G(SCH_1):PAGE377',
 WATTAGE='1/20W',
 TOLERANCE='1%',
 MATERIAL='CHIP',
 PHYS_PAGE='185',
 XY='(-5875,1800)',
 ROT='0',
 VER='1',
 PACK_TYPE='0201LF',
 LOCATION='R834',
 CDS_LIB='pure_quanta',
 CDS_PART_NAME='Q_RES_0201LF-1K,1%,1/20W,CHIP,CS21001FE07',
 PART_NUMBER='CS21001FE07',
 VALUE='1K',
 PRIM_FILE='./archive_libs/logical/q_res/chips/chips.prt';

PART_NAME
 R835 'Q_RES_0201LF-1K,1%,1/20W,CHIP,CS21001FE07':;

SECTION_NUMBER 1
 '@T6G_MB_LIB.T6G(SCH_1):PAGE377_I23@PURE_QUANTA.Q_RES(CHIPS)':
 C_PATH='@t6g_mb_lib.t6g(sch_1):page377_i23@pure_quanta.q_res(chips)',
 P_PATH='@t6g_mb_lib.t6g(sch_1):page185_i23@pure_quanta.q_res(chips)',
 PATH='I23',
 DRAWING='@T6G_MB_LIB.T6G(SCH_1):PAGE377',
 WATTAGE='1/20W',
 TOLERANCE='1%',
 MATERIAL='CHIP',
 PHYS_PAGE='185',
 XY='(-5875,1700)',
 ROT='0',
 VER='1',
 PACK_TYPE='0201LF',
 LOCATION='R835',
 CDS_LIB='pure_quanta',
 CDS_PART_NAME='Q_RES_0201LF-1K,1%,1/20W,CHIP,CS21001FE07',
 PART_NUMBER='CS21001FE07',
 VALUE='1K',
 PRIM_FILE='./archive_libs/logical/q_res/chips/chips.prt';

PART_NAME
 R836 'Q_RES_0201LF-1K,1%,1/20W,CHIP,CS21001FE07':;

SECTION_NUMBER 1
 '@T6G_MB_LIB.T6G(SCH_1):PAGE377_I22@PURE_QUANTA.Q_RES(CHIPS)':
 C_PATH='@t6g_mb_lib.t6g(sch_1):page377_i22@pure_quanta.q_res(chips)',
 P_PATH='@t6g_mb_lib.t6g(sch_1):page185_i22@pure_quanta.q_res(chips)',
 PATH='I22',
 DRAWING='@T6G_MB_LIB.T6G(SCH_1):PAGE377',
 WATTAGE='1/20W',
 TOLERANCE='1%',
 MATERIAL='CHIP',
 PHYS_PAGE='185',
 XY='(-5875,1625)',
 ROT='0',
 VER='1',
 PACK_TYPE='0201LF',
 LOCATION='R836',
 CDS_LIB='pure_quanta',
 CDS_PART_NAME='Q_RES_0201LF-1K,1%,1/20W,CHIP,CS21001FE07',
 PART_NUMBER='CS21001FE07',
 VALUE='1K',
 PRIM_FILE='./archive_libs/logical/q_res/chips/chips.prt';

PART_NAME
 R837 'Q_RES_0201LF-1K,1%,1/20W,CHIP,CS21001FE07':;

SECTION_NUMBER 1
 '@T6G_MB_LIB.T6G(SCH_1):PAGE377_I21@PURE_QUANTA.Q_RES(CHIPS)':
 C_PATH='@t6g_mb_lib.t6g(sch_1):page377_i21@pure_quanta.q_res(chips)',
 P_PATH='@t6g_mb_lib.t6g(sch_1):page185_i21@pure_quanta.q_res(chips)',
 PATH='I21',
 DRAWING='@T6G_MB_LIB.T6G(SCH_1):PAGE377',
 WATTAGE='1/20W',
 TOLERANCE='1%',
 MATERIAL='CHIP',
 PHYS_PAGE='185',
 XY='(-5875,1550)',
 ROT='0',
 VER='1',
 PACK_TYPE='0201LF',
 LOCATION='R837',
 CDS_LIB='pure_quanta',
 CDS_PART_NAME='Q_RES_0201LF-1K,1%,1/20W,CHIP,CS21001FE07',
 PART_NUMBER='CS21001FE07',
 VALUE='1K',
 PRIM_FILE='./archive_libs/logical/q_res/chips/chips.prt';

PART_NAME
 R838 'Q_RES_0201LF-1K,1%,1/20W,CHIP,CS21001FE07':;

SECTION_NUMBER 1
 '@T6G_MB_LIB.T6G(SCH_1):PAGE377_I19@PURE_QUANTA.Q_RES(CHIPS)':
 C_PATH='@t6g_mb_lib.t6g(sch_1):page377_i19@pure_quanta.q_res(chips)',
 P_PATH='@t6g_mb_lib.t6g(sch_1):page185_i19@pure_quanta.q_res(chips)',
 PATH='I19',
 DRAWING='@T6G_MB_LIB.T6G(SCH_1):PAGE377',
 WATTAGE='1/20W',
 TOLERANCE='1%',
 MATERIAL='CHIP',
 PHYS_PAGE='185',
 XY='(-5875,1450)',
 ROT='0',
 VER='1',
 PACK_TYPE='0201LF',
 LOCATION='R838',
 CDS_LIB='pure_quanta',
 CDS_PART_NAME='Q_RES_0201LF-1K,1%,1/20W,CHIP,CS21001FE07',
 PART_NUMBER='CS21001FE07',
 VALUE='1K',
 PRIM_FILE='./archive_libs/logical/q_res/chips/chips.prt';

PART_NAME
 R839 'Q_RES_0201LF-1K,1%,1/20W,CHIP,CS21001FE07':;

SECTION_NUMBER 1
 '@T6G_MB_LIB.T6G(SCH_1):PAGE377_I20@PURE_QUANTA.Q_RES(CHIPS)':
 C_PATH='@t6g_mb_lib.t6g(sch_1):page377_i20@pure_quanta.q_res(chips)',
 P_PATH='@t6g_mb_lib.t6g(sch_1):page185_i20@pure_quanta.q_res(chips)',
 PATH='I20',
 DRAWING='@T6G_MB_LIB.T6G(SCH_1):PAGE377',
 WATTAGE='1/20W',
 TOLERANCE='1%',
 MATERIAL='CHIP',
 PHYS_PAGE='185',
 XY='(-5875,1375)',
 ROT='0',
 VER='1',
 PACK_TYPE='0201LF',
 LOCATION='R839',
 CDS_LIB='pure_quanta',
 CDS_PART_NAME='Q_RES_0201LF-1K,1%,1/20W,CHIP,CS21001FE07',
 PART_NUMBER='CS21001FE07',
 VALUE='1K',
 PRIM_FILE='./archive_libs/logical/q_res/chips/chips.prt';

PART_NAME
 R840 'Q_RES_0201LF-1K,1%,1/20W,CHIP,CS21001FE07':;

SECTION_NUMBER 1
 '@T6G_MB_LIB.T6G(SCH_1):PAGE377_I18@PURE_QUANTA.Q_RES(CHIPS)':
 C_PATH='@t6g_mb_lib.t6g(sch_1):page377_i18@pure_quanta.q_res(chips)',
 P_PATH='@t6g_mb_lib.t6g(sch_1):page185_i18@pure_quanta.q_res(chips)',
 PATH='I18',
 DRAWING='@T6G_MB_LIB.T6G(SCH_1):PAGE377',
 WATTAGE='1/20W',
 TOLERANCE='1%',
 MATERIAL='CHIP',
 PHYS_PAGE='185',
 XY='(-5875,1300)',
 ROT='0',
 VER='1',
 PACK_TYPE='0201LF',
 LOCATION='R840',
 CDS_LIB='pure_quanta',
 CDS_PART_NAME='Q_RES_0201LF-1K,1%,1/20W,CHIP,CS21001FE07',
 PART_NUMBER='CS21001FE07',
 VALUE='1K',
 PRIM_FILE='./archive_libs/logical/q_res/chips/chips.prt';

PART_NAME
 R841 'Q_RES_0201LF-1K,1%,1/20W,CHIP,CS21001FE07':;

SECTION_NUMBER 1
 '@T6G_MB_LIB.T6G(SCH_1):PAGE377_I17@PURE_QUANTA.Q_RES(CHIPS)':
 C_PATH='@t6g_mb_lib.t6g(sch_1):page377_i17@pure_quanta.q_res(chips)',
 P_PATH='@t6g_mb_lib.t6g(sch_1):page185_i17@pure_quanta.q_res(chips)',
 PATH='I17',
 DRAWING='@T6G_MB_LIB.T6G(SCH_1):PAGE377',
 WATTAGE='1/20W',
 TOLERANCE='1%',
 MATERIAL='CHIP',
 PHYS_PAGE='185',
 XY='(-5875,1225)',
 ROT='0',
 VER='1',
 PACK_TYPE='0201LF',
 LOCATION='R841',
 CDS_LIB='pure_quanta',
 CDS_PART_NAME='Q_RES_0201LF-1K,1%,1/20W,CHIP,CS21001FE07',
 PART_NUMBER='CS21001FE07',
 VALUE='1K',
 PRIM_FILE='./archive_libs/logical/q_res/chips/chips.prt';

PART_NAME
 R842 'Q_RES_0201LF-4.7K,5%,1/20W,EMPTY,CS24701JE04':;

SECTION_NUMBER 1
 '@T6G_MB_LIB.T6G(SCH_1):PAGE377_I4@PURE_QUANTA.Q_RES(CHIPS)':
 C_PATH='@t6g_mb_lib.t6g(sch_1):page377_i4@pure_quanta.q_res(chips)',
 P_PATH='@t6g_mb_lib.t6g(sch_1):page185_i4@pure_quanta.q_res(chips)',
 PATH='I4',
 DRAWING='@T6G_MB_LIB.T6G(SCH_1):PAGE377',
 WATTAGE='1/20W',
 TOLERANCE='5%',
 MATERIAL='EMPTY',
 PHYS_PAGE='185',
 XY='(-8525,2075)',
 ROT='0',
 VER='2',
 PACK_TYPE='0201LF',
 LOCATION='R842',
 CDS_LIB='pure_quanta',
 CDS_PART_NAME='Q_RES_0201LF-4.7K,5%,1/20W,EMPTY,CS24701JE04',
 PART_NUMBER='CS24701JE04',
 VALUE='4.7K',
 PRIM_FILE='./archive_libs/logical/q_res/chips/chips.prt';

PART_NAME
 R843 'Q_RES_0201LF-4.7K,5%,1/20W,EMPTY,CS24701JE04':;

SECTION_NUMBER 1
 '@T6G_MB_LIB.T6G(SCH_1):PAGE377_I5@PURE_QUANTA.Q_RES(CHIPS)':
 C_PATH='@t6g_mb_lib.t6g(sch_1):page377_i5@pure_quanta.q_res(chips)',
 P_PATH='@t6g_mb_lib.t6g(sch_1):page185_i5@pure_quanta.q_res(chips)',
 PATH='I5',
 DRAWING='@T6G_MB_LIB.T6G(SCH_1):PAGE377',
 WATTAGE='1/20W',
 TOLERANCE='5%',
 MATERIAL='EMPTY',
 PHYS_PAGE='185',
 XY='(-8225,2075)',
 ROT='0',
 VER='2',
 PACK_TYPE='0201LF',
 LOCATION='R843',
 CDS_LIB='pure_quanta',
 CDS_PART_NAME='Q_RES_0201LF-4.7K,5%,1/20W,EMPTY,CS24701JE04',
 PART_NUMBER='CS24701JE04',
 VALUE='4.7K',
 PRIM_FILE='./archive_libs/logical/q_res/chips/chips.prt';

PART_NAME
 R844 'Q_RES_0201LF-4.7K,5%,1/20W,EMPTY,CS24701JE04':;

SECTION_NUMBER 1
 '@T6G_MB_LIB.T6G(SCH_1):PAGE377_I9@PURE_QUANTA.Q_RES(CHIPS)':
 C_PATH='@t6g_mb_lib.t6g(sch_1):page377_i9@pure_quanta.q_res(chips)',
 P_PATH='@t6g_mb_lib.t6g(sch_1):page185_i9@pure_quanta.q_res(chips)',
 PATH='I9',
 DRAWING='@T6G_MB_LIB.T6G(SCH_1):PAGE377',
 WATTAGE='1/20W',
 TOLERANCE='5%',
 MATERIAL='EMPTY',
 PHYS_PAGE='185',
 XY='(-7875,2050)',
 ROT='0',
 VER='2',
 PACK_TYPE='0201LF',
 LOCATION='R844',
 CDS_LIB='pure_quanta',
 CDS_PART_NAME='Q_RES_0201LF-4.7K,5%,1/20W,EMPTY,CS24701JE04',
 PART_NUMBER='CS24701JE04',
 VALUE='4.7K',
 PRIM_FILE='./archive_libs/logical/q_res/chips/chips.prt';

PART_NAME
 R845 'Q_RES_0201LF-4.7K,5%,1/20W,CHIP,CS24701JE04':;

SECTION_NUMBER 1
 '@T6G_MB_LIB.T6G(SCH_1):PAGE377_I2@PURE_QUANTA.Q_RES(CHIPS)':
 C_PATH='@t6g_mb_lib.t6g(sch_1):page377_i2@pure_quanta.q_res(chips)',
 P_PATH='@t6g_mb_lib.t6g(sch_1):page185_i2@pure_quanta.q_res(chips)',
 PATH='I2',
 DRAWING='@T6G_MB_LIB.T6G(SCH_1):PAGE377',
 WATTAGE='1/20W',
 TOLERANCE='5%',
 MATERIAL='CHIP',
 PHYS_PAGE='185',
 XY='(-8525,1300)',
 ROT='0',
 VER='2',
 PACK_TYPE='0201LF',
 LOCATION='R845',
 CDS_LIB='pure_quanta',
 CDS_PART_NAME='Q_RES_0201LF-4.7K,5%,1/20W,CHIP,CS24701JE04',
 PART_NUMBER='CS24701JE04',
 VALUE='4.7K',
 PRIM_FILE='./archive_libs/logical/q_res/chips/chips.prt';

PART_NAME
 R846 'Q_RES_0201LF-4.7K,5%,1/20W,CHIP,CS24701JE04':;

SECTION_NUMBER 1
 '@T6G_MB_LIB.T6G(SCH_1):PAGE377_I3@PURE_QUANTA.Q_RES(CHIPS)':
 C_PATH='@t6g_mb_lib.t6g(sch_1):page377_i3@pure_quanta.q_res(chips)',
 P_PATH='@t6g_mb_lib.t6g(sch_1):page185_i3@pure_quanta.q_res(chips)',
 PATH='I3',
 DRAWING='@T6G_MB_LIB.T6G(SCH_1):PAGE377',
 WATTAGE='1/20W',
 TOLERANCE='5%',
 MATERIAL='CHIP',
 PHYS_PAGE='185',
 XY='(-8225,1300)',
 ROT='0',
 VER='2',
 PACK_TYPE='0201LF',
 LOCATION='R846',
 CDS_LIB='pure_quanta',
 CDS_PART_NAME='Q_RES_0201LF-4.7K,5%,1/20W,CHIP,CS24701JE04',
 PART_NUMBER='CS24701JE04',
 VALUE='4.7K',
 PRIM_FILE='./archive_libs/logical/q_res/chips/chips.prt';

PART_NAME
 R847 'Q_RES_0201LF-4.7K,5%,1/20W,CHIP,CS24701JE04':;

SECTION_NUMBER 1
 '@T6G_MB_LIB.T6G(SCH_1):PAGE377_I8@PURE_QUANTA.Q_RES(CHIPS)':
 C_PATH='@t6g_mb_lib.t6g(sch_1):page377_i8@pure_quanta.q_res(chips)',
 P_PATH='@t6g_mb_lib.t6g(sch_1):page185_i8@pure_quanta.q_res(chips)',
 PATH='I8',
 DRAWING='@T6G_MB_LIB.T6G(SCH_1):PAGE377',
 WATTAGE='1/20W',
 TOLERANCE='5%',
 MATERIAL='CHIP',
 PHYS_PAGE='185',
 XY='(-7875,1300)',
 ROT='0',
 VER='2',
 PACK_TYPE='0201LF',
 LOCATION='R847',
 CDS_LIB='pure_quanta',
 CDS_PART_NAME='Q_RES_0201LF-4.7K,5%,1/20W,CHIP,CS24701JE04',
 PART_NUMBER='CS24701JE04',
 VALUE='4.7K',
 PRIM_FILE='./archive_libs/logical/q_res/chips/chips.prt';

PART_NAME
 R848 'Q_RES_0201LF-0,5%,1/20W,CHIP,CS00001JE10':;

SECTION_NUMBER 1
 '@T6G_MB_LIB.T6G(SCH_1):PAGE377_I42@PURE_QUANTA.Q_RES(CHIPS)':
 C_PATH='@t6g_mb_lib.t6g(sch_1):page377_i42@pure_quanta.q_res(chips)',
 P_PATH='@t6g_mb_lib.t6g(sch_1):page185_i42@pure_quanta.q_res(chips)',
 PATH='I42',
 DRAWING='@T6G_MB_LIB.T6G(SCH_1):PAGE377',
 WATTAGE='1/20W',
 TOLERANCE='5%',
 MATERIAL='CHIP',
 PHYS_PAGE='185',
 XY='(-6625,5550)',
 ROT='0',
 VER='1',
 PACK_TYPE='0201LF',
 LOCATION='R848',
 CDS_LIB='pure_quanta',
 CDS_PART_NAME='Q_RES_0201LF-0,5%,1/20W,CHIP,CS00001JE10',
 PART_NUMBER='CS00001JE10',
 VALUE='0',
 PRIM_FILE='./archive_libs/logical/q_res/chips/chips.prt';

PART_NAME
 R849 'Q_RES_0201LF-10K,1%,1/20W,CHIP,CS31001FE17':;

SECTION_NUMBER 1
 '@T6G_MB_LIB.T6G(SCH_1):PAGE377_I16@PURE_QUANTA.Q_RES(CHIPS)':
 C_PATH='@t6g_mb_lib.t6g(sch_1):page377_i16@pure_quanta.q_res(chips)',
 P_PATH='@t6g_mb_lib.t6g(sch_1):page185_i16@pure_quanta.q_res(chips)',
 PATH='I16',
 DRAWING='@T6G_MB_LIB.T6G(SCH_1):PAGE377',
 WATTAGE='1/20W',
 TOLERANCE='1%',
 MATERIAL='CHIP',
 PHYS_PAGE='185',
 XY='(-7750,3300)',
 ROT='0',
 VER='2',
 PACK_TYPE='0201LF',
 LOCATION='R849',
 CDS_LIB='pure_quanta',
 CDS_PART_NAME='Q_RES_0201LF-10K,1%,1/20W,CHIP,CS31001FE17',
 PART_NUMBER='CS31001FE17',
 VALUE='10K',
 PRIM_FILE='./archive_libs/logical/q_res/chips/chips.prt';

PART_NAME
 R850 'Q_RES_0201LF-0,5%,1/20W,CHIP,CS00001JE10':;

SECTION_NUMBER 1
 '@T6G_MB_LIB.T6G(SCH_1):PAGE377_I81@PURE_QUANTA.Q_RES(CHIPS)':
 C_PATH='@t6g_mb_lib.t6g(sch_1):page377_i81@pure_quanta.q_res(chips)',
 P_PATH='@t6g_mb_lib.t6g(sch_1):page185_i81@pure_quanta.q_res(chips)',
 PATH='I81',
 DRAWING='@T6G_MB_LIB.T6G(SCH_1):PAGE377',
 WATTAGE='1/20W',
 TOLERANCE='5%',
 MATERIAL='CHIP',
 PHYS_PAGE='185',
 XY='(-3025,5700)',
 ROT='0',
 VER='1',
 PACK_TYPE='0201LF',
 LOCATION='R850',
 CDS_LIB='pure_quanta',
 CDS_PART_NAME='Q_RES_0201LF-0,5%,1/20W,CHIP,CS00001JE10',
 PART_NUMBER='CS00001JE10',
 VALUE='0',
 PRIM_FILE='./archive_libs/logical/q_res/chips/chips.prt';

PART_NAME
 R851 'Q_RES_0201LF-0,5%,1/20W,CHIP,CS00001JE10':;

SECTION_NUMBER 1
 '@T6G_MB_LIB.T6G(SCH_1):PAGE377_I82@PURE_QUANTA.Q_RES(CHIPS)':
 C_PATH='@t6g_mb_lib.t6g(sch_1):page377_i82@pure_quanta.q_res(chips)',
 P_PATH='@t6g_mb_lib.t6g(sch_1):page185_i82@pure_quanta.q_res(chips)',
 PATH='I82',
 DRAWING='@T6G_MB_LIB.T6G(SCH_1):PAGE377',
 WATTAGE='1/20W',
 TOLERANCE='5%',
 MATERIAL='CHIP',
 PHYS_PAGE='185',
 XY='(-3025,5650)',
 ROT='0',
 VER='1',
 PACK_TYPE='0201LF',
 LOCATION='R851',
 CDS_LIB='pure_quanta',
 CDS_PART_NAME='Q_RES_0201LF-0,5%,1/20W,CHIP,CS00001JE10',
 PART_NUMBER='CS00001JE10',
 VALUE='0',
 PRIM_FILE='./archive_libs/logical/q_res/chips/chips.prt';

PART_NAME
 R852 'Q_RES_0402LF-0,5%,1/16W,EMPTY,CS00002JB13':;

SECTION_NUMBER 1
 '@T6G_MB_LIB.T6G(SCH_1):PAGE454_I2@PURE_QUANTA.Q_RES(CHIPS)':
 C_PATH='@t6g_mb_lib.t6g(sch_1):page454_i2@pure_quanta.q_res(chips)',
 P_PATH='@t6g_mb_lib.t6g(sch_1):page345_i2@pure_quanta.q_res(chips)',
 PATH='I2',
 DRAWING='@T6G_MB_LIB.T6G(SCH_1):PAGE454',
 SEC_TYPE='0402LF',
 WATTAGE='1/16W',
 TOLERANCE='5%',
 MATERIAL='EMPTY',
 PHYS_PAGE='345',
 XY='(-7650,3900)',
 ROT='0',
 VER='1',
 PACK_TYPE='0402LF',
 LOCATION='R852',
 SEC='1',
 CDS_LIB='pure_quanta',
 CDS_PART_NAME='Q_RES_0402LF-0,5%,1/16W,EMPTY,CS00002JB13',
 PART_NUMBER='CS00002JB13',
 VALUE='0',
 PRIM_FILE='./archive_libs/logical/q_res/chips/chips.prt';

PART_NAME
 R853 'Q_RES_0402LF-0,5%,1/16W,EMPTY,CS00002JB13':;

SECTION_NUMBER 1
 '@T6G_MB_LIB.T6G(SCH_1):PAGE454_I3@PURE_QUANTA.Q_RES(CHIPS)':
 C_PATH='@t6g_mb_lib.t6g(sch_1):page454_i3@pure_quanta.q_res(chips)',
 P_PATH='@t6g_mb_lib.t6g(sch_1):page345_i3@pure_quanta.q_res(chips)',
 PATH='I3',
 DRAWING='@T6G_MB_LIB.T6G(SCH_1):PAGE454',
 SEC_TYPE='0402LF',
 WATTAGE='1/16W',
 TOLERANCE='5%',
 MATERIAL='EMPTY',
 PHYS_PAGE='345',
 XY='(-7650,3700)',
 ROT='0',
 VER='1',
 PACK_TYPE='0402LF',
 LOCATION='R853',
 SEC='1',
 CDS_LIB='pure_quanta',
 CDS_PART_NAME='Q_RES_0402LF-0,5%,1/16W,EMPTY,CS00002JB13',
 PART_NUMBER='CS00002JB13',
 VALUE='0',
 PRIM_FILE='./archive_libs/logical/q_res/chips/chips.prt';

PART_NAME
 R854 'Q_RES_0201LF-0,5%,1/20W,CHIP,CS00001JE10':;

SECTION_NUMBER 1
 '@T6G_MB_LIB.T6G(SCH_1):PAGE451_I63@PURE_QUANTA.Q_RES(CHIPS)':
 C_PATH='@t6g_mb_lib.t6g(sch_1):page451_i63@pure_quanta.q_res(chips)',
 P_PATH='@t6g_mb_lib.t6g(sch_1):page342_i63@pure_quanta.q_res(chips)',
 PATH='I63',
 DRAWING='@T6G_MB_LIB.T6G(SCH_1):PAGE451',
 SEC_TYPE='0201LF',
 WATTAGE='1/20W',
 TOLERANCE='5%',
 MATERIAL='CHIP',
 PHYS_PAGE='342',
 XY='(-2550,2175)',
 ROT='0',
 VER='1',
 PACK_TYPE='0201LF',
 LOCATION='R854',
 SEC='1',
 CDS_LIB='pure_quanta',
 CDS_PART_NAME='Q_RES_0201LF-0,5%,1/20W,CHIP,CS00001JE10',
 PART_NUMBER='CS00001JE10',
 VALUE='0',
 PRIM_FILE='./archive_libs/logical/q_res/chips/chips.prt';

PART_NAME
 R855 'Q_RES_0402LF-11.5K,1%,1/16W,EMPTY,CS31152FB03':;

SECTION_NUMBER 1
 '@T6G_MB_LIB.T6G(SCH_1):PAGE146_I3@PURE_QUANTA.Q_RES(CHIPS)':
 C_PATH='@t6g_mb_lib.t6g(sch_1):page146_i3@pure_quanta.q_res(chips)',
 P_PATH='@t6g_mb_lib.t6g(sch_1):page169_i3@pure_quanta.q_res(chips)',
 PATH='I3',
 DRAWING='@T6G_MB_LIB.T6G(SCH_1):PAGE146',
 WATTAGE='1/16W',
 TOLERANCE='1%',
 MATERIAL='EMPTY',
 PHYS_PAGE='169',
 XY='(-9175,3900)',
 ROT='0',
 VER='2',
 PACK_TYPE='0402LF',
 LOCATION='R855',
 CDS_LIB='pure_quanta',
 CDS_PART_NAME='Q_RES_0402LF-11.5K,1%,1/16W,EMPTY,CS31152FB03',
 PART_NUMBER='CS31152FB03',
 VALUE='11.5K',
 PRIM_FILE='./archive_libs/logical/q_res/chips/chips.prt';

PART_NAME
 R856 'Q_RES_0402LF-0,5%,1/16W,CHIP,CS00002JB13':;

SECTION_NUMBER 1
 '@T6G_MB_LIB.T6G(SCH_1):PAGE80_I167@PURE_QUANTA.Q_RES(CHIPS)':
 C_PATH='@t6g_mb_lib.t6g(sch_1):page80_i167@pure_quanta.q_res(chips)',
 P_PATH='@t6g_mb_lib.t6g(sch_1):page81_i167@pure_quanta.q_res(chips)',
 PATH='I167',
 DRAWING='@T6G_MB_LIB.T6G(SCH_1):PAGE80',
 BOM_COST='MEM',
 WATTAGE='1/16W',
 TOLERANCE='5%',
 MATERIAL='CHIP',
 PHYS_PAGE='81',
 XY='(-3225,5075)',
 ROT='0',
 VER='1',
 PACK_TYPE='0402LF',
 LOCATION='R856',
 CDS_LIB='pure_quanta',
 CDS_PART_NAME='Q_RES_0402LF-0,5%,1/16W,CHIP,CS00002JB13',
 PART_NUMBER='CS00002JB13',
 VALUE='0',
 PRIM_FILE='./archive_libs/logical/q_res/chips/chips.prt';

PART_NAME
 R857 'Q_RES_0402LF-0,5%,1/16W,EMPTY,CS00002JB13':;

SECTION_NUMBER 1
 '@T6G_MB_LIB.T6G(SCH_1):PAGE454_I89@PURE_QUANTA.Q_RES(CHIPS)':
 C_PATH='@t6g_mb_lib.t6g(sch_1):page454_i89@pure_quanta.q_res(chips)',
 P_PATH='@t6g_mb_lib.t6g(sch_1):page345_i89@pure_quanta.q_res(chips)',
 PATH='I89',
 DRAWING='@T6G_MB_LIB.T6G(SCH_1):PAGE454',
 WATTAGE='1/16W',
 TOLERANCE='5%',
 MATERIAL='EMPTY',
 PHYS_PAGE='345',
 XY='(-8050,4225)',
 ROT='0',
 VER='2',
 PACK_TYPE='0402LF',
 LOCATION='R857',
 CDS_LIB='pure_quanta',
 CDS_PART_NAME='Q_RES_0402LF-0,5%,1/16W,EMPTY,CS00002JB13',
 PART_NUMBER='CS00002JB13',
 VALUE='0',
 PRIM_FILE='./archive_libs/logical/q_res/chips/chips.prt';

PART_NAME
 R858 'Q_RES_0603LF-0,5%,1/4W,EMPTY,CS00006J900':;

SECTION_NUMBER 1
 '@T6G_MB_LIB.T6G(SCH_1):PAGE454_I20@PURE_QUANTA.Q_RES(CHIPS)':
 C_PATH='@t6g_mb_lib.t6g(sch_1):page454_i20@pure_quanta.q_res(chips)',
 P_PATH='@t6g_mb_lib.t6g(sch_1):page345_i20@pure_quanta.q_res(chips)',
 PATH='I20',
 DRAWING='@T6G_MB_LIB.T6G(SCH_1):PAGE454',
 WATTAGE='1/4W',
 TOLERANCE='5%',
 MATERIAL='EMPTY',
 PHYS_PAGE='345',
 XY='(-4250,2900)',
 ROT='2',
 VER='2',
 PACK_TYPE='0603LF',
 LOCATION='R858',
 CDS_LIB='pure_quanta',
 CDS_PART_NAME='Q_RES_0603LF-0,5%,1/4W,EMPTY,CS00006J900',
 PART_NUMBER='CS00006J900',
 VALUE='0',
 PRIM_FILE='./archive_libs/logical/q_res/chips/chips.prt';

PART_NAME
 R859 'Q_RES_0603LF-0,5%,1/4W,CHIP,CS00006J900':;

SECTION_NUMBER 1
 '@T6G_MB_LIB.T6G(SCH_1):PAGE454_I41@PURE_QUANTA.Q_RES(CHIPS)':
 C_PATH='@t6g_mb_lib.t6g(sch_1):page454_i41@pure_quanta.q_res(chips)',
 P_PATH='@t6g_mb_lib.t6g(sch_1):page345_i41@pure_quanta.q_res(chips)',
 PATH='I41',
 DRAWING='@T6G_MB_LIB.T6G(SCH_1):PAGE454',
 WATTAGE='1/4W',
 TOLERANCE='5%',
 MATERIAL='CHIP',
 PHYS_PAGE='345',
 XY='(-3875,2625)',
 ROT='0',
 VER='1',
 PACK_TYPE='0603LF',
 LOCATION='R859',
 CDS_LIB='pure_quanta',
 CDS_PART_NAME='Q_RES_0603LF-0,5%,1/4W,CHIP,CS00006J900',
 PART_NUMBER='CS00006J900',
 VALUE='0',
 PRIM_FILE='./archive_libs/logical/q_res/chips/chips.prt';

PART_NAME
 R860 'Q_RES_0201LF-0,5%,1/20W,CHIP,CS00001JE10':;

SECTION_NUMBER 1
 '@T6G_MB_LIB.T6G(SCH_1):PAGE451_I62@PURE_QUANTA.Q_RES(CHIPS)':
 C_PATH='@t6g_mb_lib.t6g(sch_1):page451_i62@pure_quanta.q_res(chips)',
 P_PATH='@t6g_mb_lib.t6g(sch_1):page342_i62@pure_quanta.q_res(chips)',
 PATH='I62',
 DRAWING='@T6G_MB_LIB.T6G(SCH_1):PAGE451',
 WATTAGE='1/20W',
 TOLERANCE='5%',
 MATERIAL='CHIP',
 PHYS_PAGE='342',
 XY='(-2550,2075)',
 ROT='0',
 VER='1',
 PACK_TYPE='0201LF',
 LOCATION='R860',
 CDS_LIB='pure_quanta',
 CDS_PART_NAME='Q_RES_0201LF-0,5%,1/20W,CHIP,CS00001JE10',
 PART_NUMBER='CS00001JE10',
 VALUE='0',
 PRIM_FILE='./archive_libs/logical/q_res/chips/chips.prt';

PART_NAME
 R861 'Q_RES_0201LF-1K,1%,1/20W,CHIP,CS21001FE07':;

SECTION_NUMBER 1
 '@T6G_MB_LIB.T6G(SCH_1):PAGE451_I74@PURE_QUANTA.Q_RES(CHIPS)':
 C_PATH='@t6g_mb_lib.t6g(sch_1):page451_i74@pure_quanta.q_res(chips)',
 P_PATH='@t6g_mb_lib.t6g(sch_1):page342_i74@pure_quanta.q_res(chips)',
 PATH='I74',
 DRAWING='@T6G_MB_LIB.T6G(SCH_1):PAGE451',
 WATTAGE='1/20W',
 TOLERANCE='1%',
 MATERIAL='CHIP',
 PHYS_PAGE='342',
 XY='(-3600,6075)',
 ROT='0',
 VER='2',
 PACK_TYPE='0201LF',
 LOCATION='R861',
 CDS_LIB='pure_quanta',
 CDS_PART_NAME='Q_RES_0201LF-1K,1%,1/20W,CHIP,CS21001FE07',
 PART_NUMBER='CS21001FE07',
 VALUE='1K',
 PRIM_FILE='./archive_libs/logical/q_res/chips/chips.prt';

PART_NAME
 R862 'Q_RES_0402LF-0,5%,1/16W,CHIP,CS00002JB13':;

SECTION_NUMBER 1
 '@T6G_MB_LIB.T6G(SCH_1):PAGE54_I364@PURE_QUANTA.Q_RES(CHIPS)':
 C_PATH='@t6g_mb_lib.t6g(sch_1):page54_i364@pure_quanta.q_res(chips)',
 P_PATH='@t6g_mb_lib.t6g(sch_1):page54_i364@pure_quanta.q_res(chips)',
 PATH='I364',
 DRAWING='@T6G_MB_LIB.T6G(SCH_1):PAGE54',
 WATTAGE='1/16W',
 TOLERANCE='5%',
 MATERIAL='CHIP',
 PHYS_PAGE='54',
 XY='(-3100,4725)',
 ROT='0',
 VER='1',
 PACK_TYPE='0402LF',
 LOCATION='R862',
 CDS_LIB='pure_quanta',
 CDS_PART_NAME='Q_RES_0402LF-0,5%,1/16W,CHIP,CS00002JB13',
 PART_NUMBER='CS00002JB13',
 VALUE='0',
 PRIM_FILE='./archive_libs/logical/q_res/chips/chips.prt';

PART_NAME
 R863 'Q_RES_0201LF-1K,1%,1/20W,EMPTY,CS21001FE07':;

SECTION_NUMBER 1
 '@T6G_MB_LIB.T6G(SCH_1):PAGE451_I71@PURE_QUANTA.Q_RES(CHIPS)':
 C_PATH='@t6g_mb_lib.t6g(sch_1):page451_i71@pure_quanta.q_res(chips)',
 P_PATH='@t6g_mb_lib.t6g(sch_1):page342_i71@pure_quanta.q_res(chips)',
 PATH='I71',
 DRAWING='@T6G_MB_LIB.T6G(SCH_1):PAGE451',
 WATTAGE='1/20W',
 TOLERANCE='1%',
 MATERIAL='EMPTY',
 PHYS_PAGE='342',
 XY='(-3600,5300)',
 ROT='0',
 VER='2',
 PACK_TYPE='0201LF',
 LOCATION='R863',
 CDS_LIB='pure_quanta',
 CDS_PART_NAME='Q_RES_0201LF-1K,1%,1/20W,EMPTY,CS21001FE07',
 PART_NUMBER='CS21001FE07',
 VALUE='1K',
 PRIM_FILE='./archive_libs/logical/q_res/chips/chips.prt';

PART_NAME
 R864 'Q_RES_0201LF-1K,1%,1/20W,EMPTY,CS21001FE07':;

SECTION_NUMBER 1
 '@T6G_MB_LIB.T6G(SCH_1):PAGE451_I75@PURE_QUANTA.Q_RES(CHIPS)':
 C_PATH='@t6g_mb_lib.t6g(sch_1):page451_i75@pure_quanta.q_res(chips)',
 P_PATH='@t6g_mb_lib.t6g(sch_1):page342_i75@pure_quanta.q_res(chips)',
 PATH='I75',
 DRAWING='@T6G_MB_LIB.T6G(SCH_1):PAGE451',
 WATTAGE='1/20W',
 TOLERANCE='1%',
 MATERIAL='EMPTY',
 PHYS_PAGE='342',
 XY='(-3300,6075)',
 ROT='0',
 VER='2',
 PACK_TYPE='0201LF',
 LOCATION='R864',
 CDS_LIB='pure_quanta',
 CDS_PART_NAME='Q_RES_0201LF-1K,1%,1/20W,EMPTY,CS21001FE07',
 PART_NUMBER='CS21001FE07',
 VALUE='1K',
 PRIM_FILE='./archive_libs/logical/q_res/chips/chips.prt';

PART_NAME
 R865 'Q_RES_0201LF-20K,1%,1/20W,CHIP,CS32001FE00':;

SECTION_NUMBER 1
 '@T6G_MB_LIB.T6G(SCH_1):PAGE451_I72@PURE_QUANTA.Q_RES(CHIPS)':
 C_PATH='@t6g_mb_lib.t6g(sch_1):page451_i72@pure_quanta.q_res(chips)',
 P_PATH='@t6g_mb_lib.t6g(sch_1):page342_i72@pure_quanta.q_res(chips)',
 PATH='I72',
 DRAWING='@T6G_MB_LIB.T6G(SCH_1):PAGE451',
 WATTAGE='1/20W',
 TOLERANCE='1%',
 MATERIAL='CHIP',
 PHYS_PAGE='342',
 XY='(-3300,5300)',
 ROT='0',
 VER='2',
 PACK_TYPE='0201LF',
 LOCATION='R865',
 CDS_LIB='pure_quanta',
 CDS_PART_NAME='Q_RES_0201LF-20K,1%,1/20W,CHIP,CS32001FE00',
 PART_NUMBER='CS32001FE00',
 VALUE='20K',
 PRIM_FILE='./archive_libs/logical/q_res/chips/chips.prt';

PART_NAME
 R866 'Q_RES_0201LF-10K,1%,1/20W,CHIP,CS31001FE17':;

SECTION_NUMBER 1
 '@T6G_MB_LIB.T6G(SCH_1):PAGE451_I82@PURE_QUANTA.Q_RES(CHIPS)':
 C_PATH='@t6g_mb_lib.t6g(sch_1):page451_i82@pure_quanta.q_res(chips)',
 P_PATH='@t6g_mb_lib.t6g(sch_1):page342_i82@pure_quanta.q_res(chips)',
 PATH='I82',
 DRAWING='@T6G_MB_LIB.T6G(SCH_1):PAGE451',
 WATTAGE='1/20W',
 TOLERANCE='1%',
 MATERIAL='CHIP',
 PHYS_PAGE='342',
 XY='(-1275,5200)',
 ROT='0',
 VER='2',
 PACK_TYPE='0201LF',
 LOCATION='R866',
 CDS_LIB='pure_quanta',
 CDS_PART_NAME='Q_RES_0201LF-10K,1%,1/20W,CHIP,CS31001FE17',
 PART_NUMBER='CS31001FE17',
 VALUE='10K',
 PRIM_FILE='./archive_libs/logical/q_res/chips/chips.prt';

PART_NAME
 R867 'Q_RES_0201LF-10K,1%,1/20W,CHIP,CS31001FE17':;

SECTION_NUMBER 1
 '@T6G_MB_LIB.T6G(SCH_1):PAGE451_I80@PURE_QUANTA.Q_RES(CHIPS)':
 C_PATH='@t6g_mb_lib.t6g(sch_1):page451_i80@pure_quanta.q_res(chips)',
 P_PATH='@t6g_mb_lib.t6g(sch_1):page342_i80@pure_quanta.q_res(chips)',
 PATH='I80',
 DRAWING='@T6G_MB_LIB.T6G(SCH_1):PAGE451',
 WATTAGE='1/20W',
 TOLERANCE='1%',
 MATERIAL='CHIP',
 PHYS_PAGE='342',
 XY='(-1450,5200)',
 ROT='2',
 VER='2',
 PACK_TYPE='0201LF',
 LOCATION='R867',
 CDS_LIB='pure_quanta',
 CDS_PART_NAME='Q_RES_0201LF-10K,1%,1/20W,CHIP,CS31001FE17',
 PART_NUMBER='CS31001FE17',
 VALUE='10K',
 PRIM_FILE='./archive_libs/logical/q_res/chips/chips.prt';

PART_NAME
 R868 'Q_RES_0201LF-4.7K,5%,1/20W,EMPTY,CS24701JE04':;

SECTION_NUMBER 1
 '@T6G_MB_LIB.T6G(SCH_1):PAGE451_I17@PURE_QUANTA.Q_RES(CHIPS)':
 C_PATH='@t6g_mb_lib.t6g(sch_1):page451_i17@pure_quanta.q_res(chips)',
 P_PATH='@t6g_mb_lib.t6g(sch_1):page342_i17@pure_quanta.q_res(chips)',
 PATH='I17',
 DRAWING='@T6G_MB_LIB.T6G(SCH_1):PAGE451',
 WATTAGE='1/20W',
 TOLERANCE='5%',
 MATERIAL='EMPTY',
 PHYS_PAGE='342',
 XY='(-8950,4100)',
 ROT='0',
 VER='2',
 PACK_TYPE='0201LF',
 LOCATION='R868',
 CDS_LIB='pure_quanta',
 CDS_PART_NAME='Q_RES_0201LF-4.7K,5%,1/20W,EMPTY,CS24701JE04',
 PART_NUMBER='CS24701JE04',
 VALUE='4.7K',
 PRIM_FILE='./archive_libs/logical/q_res/chips/chips.prt';

PART_NAME
 R869 'Q_RES_0201LF-200,1%,1/20W,CHIP,CS12001FE12':;

SECTION_NUMBER 1
 '@T6G_MB_LIB.T6G(SCH_1):PAGE451_I119@PURE_QUANTA.Q_RES(CHIPS)':
 C_PATH='@t6g_mb_lib.t6g(sch_1):page451_i119@pure_quanta.q_res(chips)',
 P_PATH='@t6g_mb_lib.t6g(sch_1):page342_i119@pure_quanta.q_res(chips)',
 PATH='I119',
 DRAWING='@T6G_MB_LIB.T6G(SCH_1):PAGE451',
 WATTAGE='1/20W',
 TOLERANCE='1%',
 MATERIAL='CHIP',
 PHYS_PAGE='342',
 XY='(-8950,3425)',
 ROT='0',
 VER='2',
 PACK_TYPE='0201LF',
 LOCATION='R869',
 CDS_LIB='pure_quanta',
 CDS_PART_NAME='Q_RES_0201LF-200,1%,1/20W,CHIP,CS12001FE12',
 PART_NUMBER='CS12001FE12',
 VALUE='200',
 PRIM_FILE='./archive_libs/logical/q_res/chips/chips.prt';

PART_NAME
 R870 'Q_RES_0201LF-4.7K,5%,1/20W,EMPTY,CS24701JE04':;

SECTION_NUMBER 1
 '@T6G_MB_LIB.T6G(SCH_1):PAGE451_I86@PURE_QUANTA.Q_RES(CHIPS)':
 C_PATH='@t6g_mb_lib.t6g(sch_1):page451_i86@pure_quanta.q_res(chips)',
 P_PATH='@t6g_mb_lib.t6g(sch_1):page342_i86@pure_quanta.q_res(chips)',
 PATH='I86',
 DRAWING='@T6G_MB_LIB.T6G(SCH_1):PAGE451',
 WATTAGE='1/20W',
 TOLERANCE='5%',
 MATERIAL='EMPTY',
 PHYS_PAGE='342',
 XY='(-1450,6025)',
 ROT='2',
 VER='2',
 PACK_TYPE='0201LF',
 LOCATION='R870',
 CDS_LIB='pure_quanta',
 CDS_PART_NAME='Q_RES_0201LF-4.7K,5%,1/20W,EMPTY,CS24701JE04',
 PART_NUMBER='CS24701JE04',
 VALUE='4.7K',
 PRIM_FILE='./archive_libs/logical/q_res/chips/chips.prt';

PART_NAME
 R871 'Q_RES_0201LF-4.7K,5%,1/20W,EMPTY,CS24701JE04':;

SECTION_NUMBER 1
 '@T6G_MB_LIB.T6G(SCH_1):PAGE451_I50@PURE_QUANTA.Q_RES(CHIPS)':
 C_PATH='@t6g_mb_lib.t6g(sch_1):page451_i50@pure_quanta.q_res(chips)',
 P_PATH='@t6g_mb_lib.t6g(sch_1):page342_i50@pure_quanta.q_res(chips)',
 PATH='I50',
 DRAWING='@T6G_MB_LIB.T6G(SCH_1):PAGE451',
 WATTAGE='1/20W',
 TOLERANCE='5%',
 MATERIAL='EMPTY',
 PHYS_PAGE='342',
 XY='(-7400,5975)',
 ROT='0',
 VER='2',
 PACK_TYPE='0201LF',
 LOCATION='R871',
 CDS_LIB='pure_quanta',
 CDS_PART_NAME='Q_RES_0201LF-4.7K,5%,1/20W,EMPTY,CS24701JE04',
 PART_NUMBER='CS24701JE04',
 VALUE='4.7K',
 PRIM_FILE='./archive_libs/logical/q_res/chips/chips.prt';

PART_NAME
 R872 'Q_RES_0201LF-0,5%,1/20W,CHIP,CS00001JE10':;

SECTION_NUMBER 1
 '@T6G_MB_LIB.T6G(SCH_1):PAGE451_I34@PURE_QUANTA.Q_RES(CHIPS)':
 C_PATH='@t6g_mb_lib.t6g(sch_1):page451_i34@pure_quanta.q_res(chips)',
 P_PATH='@t6g_mb_lib.t6g(sch_1):page342_i34@pure_quanta.q_res(chips)',
 PATH='I34',
 DRAWING='@T6G_MB_LIB.T6G(SCH_1):PAGE451',
 WATTAGE='1/20W',
 TOLERANCE='5%',
 MATERIAL='CHIP',
 PHYS_PAGE='342',
 XY='(-6325,2875)',
 ROT='0',
 VER='1',
 PACK_TYPE='0201LF',
 LOCATION='R872',
 CDS_LIB='pure_quanta',
 CDS_PART_NAME='Q_RES_0201LF-0,5%,1/20W,CHIP,CS00001JE10',
 PART_NUMBER='CS00001JE10',
 VALUE='0',
 PRIM_FILE='./archive_libs/logical/q_res/chips/chips.prt';

PART_NAME
 R873 'Q_RES_0201LF-0,5%,1/20W,CHIP,CS00001JE10':;

SECTION_NUMBER 1
 '@T6G_MB_LIB.T6G(SCH_1):PAGE451_I35@PURE_QUANTA.Q_RES(CHIPS)':
 C_PATH='@t6g_mb_lib.t6g(sch_1):page451_i35@pure_quanta.q_res(chips)',
 P_PATH='@t6g_mb_lib.t6g(sch_1):page342_i35@pure_quanta.q_res(chips)',
 PATH='I35',
 DRAWING='@T6G_MB_LIB.T6G(SCH_1):PAGE451',
 WATTAGE='1/20W',
 TOLERANCE='5%',
 MATERIAL='CHIP',
 PHYS_PAGE='342',
 XY='(-6325,2775)',
 ROT='0',
 VER='1',
 PACK_TYPE='0201LF',
 LOCATION='R873',
 CDS_LIB='pure_quanta',
 CDS_PART_NAME='Q_RES_0201LF-0,5%,1/20W,CHIP,CS00001JE10',
 PART_NUMBER='CS00001JE10',
 VALUE='0',
 PRIM_FILE='./archive_libs/logical/q_res/chips/chips.prt';

PART_NAME
 R874 'Q_RES_0201LF-4.7K,5%,1/20W,EMPTY,CS24701JE04':;

SECTION_NUMBER 1
 '@T6G_MB_LIB.T6G(SCH_1):PAGE451_I21@PURE_QUANTA.Q_RES(CHIPS)':
 C_PATH='@t6g_mb_lib.t6g(sch_1):page451_i21@pure_quanta.q_res(chips)',
 P_PATH='@t6g_mb_lib.t6g(sch_1):page342_i21@pure_quanta.q_res(chips)',
 PATH='I21',
 DRAWING='@T6G_MB_LIB.T6G(SCH_1):PAGE451',
 WATTAGE='1/20W',
 TOLERANCE='5%',
 MATERIAL='EMPTY',
 PHYS_PAGE='342',
 XY='(-8925,5975)',
 ROT='0',
 VER='2',
 PACK_TYPE='0201LF',
 LOCATION='R874',
 CDS_LIB='pure_quanta',
 CDS_PART_NAME='Q_RES_0201LF-4.7K,5%,1/20W,EMPTY,CS24701JE04',
 PART_NUMBER='CS24701JE04',
 VALUE='4.7K',
 PRIM_FILE='./archive_libs/logical/q_res/chips/chips.prt';

PART_NAME
 R875 'Q_RES_0201LF-10K,1%,1/20W,CHIP,CS31001FE17':;

SECTION_NUMBER 1
 '@T6G_MB_LIB.T6G(SCH_1):PAGE451_I19@PURE_QUANTA.Q_RES(CHIPS)':
 C_PATH='@t6g_mb_lib.t6g(sch_1):page451_i19@pure_quanta.q_res(chips)',
 P_PATH='@t6g_mb_lib.t6g(sch_1):page342_i19@pure_quanta.q_res(chips)',
 PATH='I19',
 DRAWING='@T6G_MB_LIB.T6G(SCH_1):PAGE451',
 WATTAGE='1/20W',
 TOLERANCE='1%',
 MATERIAL='CHIP',
 PHYS_PAGE='342',
 XY='(-8925,5025)',
 ROT='0',
 VER='2',
 PACK_TYPE='0201LF',
 LOCATION='R875',
 CDS_LIB='pure_quanta',
 CDS_PART_NAME='Q_RES_0201LF-10K,1%,1/20W,CHIP,CS31001FE17',
 PART_NUMBER='CS31001FE17',
 VALUE='10K',
 PRIM_FILE='./archive_libs/logical/q_res/chips/chips.prt';

PART_NAME
 R876 'Q_RES_0201LF-10K,1%,1/20W,CHIP,CS31001FE17':;

SECTION_NUMBER 1
 '@T6G_MB_LIB.T6G(SCH_1):PAGE451_I20@PURE_QUANTA.Q_RES(CHIPS)':
 C_PATH='@t6g_mb_lib.t6g(sch_1):page451_i20@pure_quanta.q_res(chips)',
 P_PATH='@t6g_mb_lib.t6g(sch_1):page342_i20@pure_quanta.q_res(chips)',
 PATH='I20',
 DRAWING='@T6G_MB_LIB.T6G(SCH_1):PAGE451',
 WATTAGE='1/20W',
 TOLERANCE='1%',
 MATERIAL='CHIP',
 PHYS_PAGE='342',
 XY='(-8625,5025)',
 ROT='0',
 VER='2',
 PACK_TYPE='0201LF',
 LOCATION='R876',
 CDS_LIB='pure_quanta',
 CDS_PART_NAME='Q_RES_0201LF-10K,1%,1/20W,CHIP,CS31001FE17',
 PART_NUMBER='CS31001FE17',
 VALUE='10K',
 PRIM_FILE='./archive_libs/logical/q_res/chips/chips.prt';

PART_NAME
 R877 'Q_RES_0402LF-0,5%,1/16W,CHIP,CS00002JB13':;

SECTION_NUMBER 1
 '@T6G_MB_LIB.T6G(SCH_1):PAGE337_I79@PURE_QUANTA.Q_RES(CHIPS)':
 C_PATH='@t6g_mb_lib.t6g(sch_1):page337_i79@pure_quanta.q_res(chips)',
 P_PATH='@t6g_mb_lib.t6g(sch_1):page133_i79@pure_quanta.q_res(chips)',
 PATH='I79',
 DRAWING='@T6G_MB_LIB.T6G(SCH_1):PAGE337',
 BOM_COST='MEM',
 WATTAGE='1/16W',
 TOLERANCE='5%',
 MATERIAL='CHIP',
 PHYS_PAGE='133',
 XY='(-6975,7025)',
 ROT='0',
 VER='1',
 PACK_TYPE='0402LF',
 LOCATION='R877',
 CDS_LIB='pure_quanta',
 CDS_PART_NAME='Q_RES_0402LF-0,5%,1/16W,CHIP,CS00002JB13',
 PART_NUMBER='CS00002JB13',
 VALUE='0',
 PRIM_FILE='./archive_libs/logical/q_res/chips/chips.prt';

PART_NAME
 R878 'Q_RES_0201LF-4.7K,5%,1/20W,EMPTY,CS24701JE04':;

SECTION_NUMBER 1
 '@T6G_MB_LIB.T6G(SCH_1):PAGE451_I47@PURE_QUANTA.Q_RES(CHIPS)':
 C_PATH='@t6g_mb_lib.t6g(sch_1):page451_i47@pure_quanta.q_res(chips)',
 P_PATH='@t6g_mb_lib.t6g(sch_1):page342_i47@pure_quanta.q_res(chips)',
 PATH='I47',
 DRAWING='@T6G_MB_LIB.T6G(SCH_1):PAGE451',
 WATTAGE='1/20W',
 TOLERANCE='5%',
 MATERIAL='EMPTY',
 PHYS_PAGE='342',
 XY='(-8300,5975)',
 ROT='0',
 VER='2',
 PACK_TYPE='0201LF',
 LOCATION='R878',
 CDS_LIB='pure_quanta',
 CDS_PART_NAME='Q_RES_0201LF-4.7K,5%,1/20W,EMPTY,CS24701JE04',
 PART_NUMBER='CS24701JE04',
 VALUE='4.7K',
 PRIM_FILE='./archive_libs/logical/q_res/chips/chips.prt';

PART_NAME
 R879 'Q_RES_0201LF-4.7K,5%,1/20W,CHIP,CS24701JE04':;

SECTION_NUMBER 1
 '@T6G_MB_LIB.T6G(SCH_1):PAGE451_I42@PURE_QUANTA.Q_RES(CHIPS)':
 C_PATH='@t6g_mb_lib.t6g(sch_1):page451_i42@pure_quanta.q_res(chips)',
 P_PATH='@t6g_mb_lib.t6g(sch_1):page342_i42@pure_quanta.q_res(chips)',
 PATH='I42',
 DRAWING='@T6G_MB_LIB.T6G(SCH_1):PAGE451',
 WATTAGE='1/20W',
 TOLERANCE='5%',
 MATERIAL='CHIP',
 PHYS_PAGE='342',
 XY='(-8300,5025)',
 ROT='0',
 VER='2',
 PACK_TYPE='0201LF',
 LOCATION='R879',
 CDS_LIB='pure_quanta',
 CDS_PART_NAME='Q_RES_0201LF-4.7K,5%,1/20W,CHIP,CS24701JE04',
 PART_NUMBER='CS24701JE04',
 VALUE='4.7K',
 PRIM_FILE='./archive_libs/logical/q_res/chips/chips.prt';

PART_NAME
 R880 'Q_RES_0201LF-4.7K,5%,1/20W,EMPTY,CS24701JE04':;

SECTION_NUMBER 1
 '@T6G_MB_LIB.T6G(SCH_1):PAGE451_I48@PURE_QUANTA.Q_RES(CHIPS)':
 C_PATH='@t6g_mb_lib.t6g(sch_1):page451_i48@pure_quanta.q_res(chips)',
 P_PATH='@t6g_mb_lib.t6g(sch_1):page342_i48@pure_quanta.q_res(chips)',
 PATH='I48',
 DRAWING='@T6G_MB_LIB.T6G(SCH_1):PAGE451',
 WATTAGE='1/20W',
 TOLERANCE='5%',
 MATERIAL='EMPTY',
 PHYS_PAGE='342',
 XY='(-8000,5925)',
 ROT='0',
 VER='2',
 PACK_TYPE='0201LF',
 LOCATION='R880',
 CDS_LIB='pure_quanta',
 CDS_PART_NAME='Q_RES_0201LF-4.7K,5%,1/20W,EMPTY,CS24701JE04',
 PART_NUMBER='CS24701JE04',
 VALUE='4.7K',
 PRIM_FILE='./archive_libs/logical/q_res/chips/chips.prt';

PART_NAME
 R881 'Q_RES_0201LF-4.7K,5%,1/20W,CHIP,CS24701JE04':;

SECTION_NUMBER 1
 '@T6G_MB_LIB.T6G(SCH_1):PAGE451_I43@PURE_QUANTA.Q_RES(CHIPS)':
 C_PATH='@t6g_mb_lib.t6g(sch_1):page451_i43@pure_quanta.q_res(chips)',
 P_PATH='@t6g_mb_lib.t6g(sch_1):page342_i43@pure_quanta.q_res(chips)',
 PATH='I43',
 DRAWING='@T6G_MB_LIB.T6G(SCH_1):PAGE451',
 WATTAGE='1/20W',
 TOLERANCE='5%',
 MATERIAL='CHIP',
 PHYS_PAGE='342',
 XY='(-8000,5000)',
 ROT='0',
 VER='2',
 PACK_TYPE='0201LF',
 LOCATION='R881',
 CDS_LIB='pure_quanta',
 CDS_PART_NAME='Q_RES_0201LF-4.7K,5%,1/20W,CHIP,CS24701JE04',
 PART_NUMBER='CS24701JE04',
 VALUE='4.7K',
 PRIM_FILE='./archive_libs/logical/q_res/chips/chips.prt';

PART_NAME
 R882 'Q_RES_0201LF-4.7K,5%,1/20W,EMPTY,CS24701JE04':;

SECTION_NUMBER 1
 '@T6G_MB_LIB.T6G(SCH_1):PAGE451_I49@PURE_QUANTA.Q_RES(CHIPS)':
 C_PATH='@t6g_mb_lib.t6g(sch_1):page451_i49@pure_quanta.q_res(chips)',
 P_PATH='@t6g_mb_lib.t6g(sch_1):page342_i49@pure_quanta.q_res(chips)',
 PATH='I49',
 DRAWING='@T6G_MB_LIB.T6G(SCH_1):PAGE451',
 WATTAGE='1/20W',
 TOLERANCE='5%',
 MATERIAL='EMPTY',
 PHYS_PAGE='342',
 XY='(-7700,5950)',
 ROT='0',
 VER='2',
 PACK_TYPE='0201LF',
 LOCATION='R882',
 CDS_LIB='pure_quanta',
 CDS_PART_NAME='Q_RES_0201LF-4.7K,5%,1/20W,EMPTY,CS24701JE04',
 PART_NUMBER='CS24701JE04',
 VALUE='4.7K',
 PRIM_FILE='./archive_libs/logical/q_res/chips/chips.prt';

PART_NAME
 R883 'Q_RES_0201LF-4.7K,5%,1/20W,CHIP,CS24701JE04':;

SECTION_NUMBER 1
 '@T6G_MB_LIB.T6G(SCH_1):PAGE451_I45@PURE_QUANTA.Q_RES(CHIPS)':
 C_PATH='@t6g_mb_lib.t6g(sch_1):page451_i45@pure_quanta.q_res(chips)',
 P_PATH='@t6g_mb_lib.t6g(sch_1):page342_i45@pure_quanta.q_res(chips)',
 PATH='I45',
 DRAWING='@T6G_MB_LIB.T6G(SCH_1):PAGE451',
 WATTAGE='1/20W',
 TOLERANCE='5%',
 MATERIAL='CHIP',
 PHYS_PAGE='342',
 XY='(-7700,5000)',
 ROT='0',
 VER='2',
 PACK_TYPE='0201LF',
 LOCATION='R883',
 CDS_LIB='pure_quanta',
 CDS_PART_NAME='Q_RES_0201LF-4.7K,5%,1/20W,CHIP,CS24701JE04',
 PART_NUMBER='CS24701JE04',
 VALUE='4.7K',
 PRIM_FILE='./archive_libs/logical/q_res/chips/chips.prt';

PART_NAME
 R884 'Q_RES_0201LF-4.7K,5%,1/20W,CHIP,CS24701JE04':;

SECTION_NUMBER 1
 '@T6G_MB_LIB.T6G(SCH_1):PAGE451_I46@PURE_QUANTA.Q_RES(CHIPS)':
 C_PATH='@t6g_mb_lib.t6g(sch_1):page451_i46@pure_quanta.q_res(chips)',
 P_PATH='@t6g_mb_lib.t6g(sch_1):page342_i46@pure_quanta.q_res(chips)',
 PATH='I46',
 DRAWING='@T6G_MB_LIB.T6G(SCH_1):PAGE451',
 WATTAGE='1/20W',
 TOLERANCE='5%',
 MATERIAL='CHIP',
 PHYS_PAGE='342',
 XY='(-7400,4975)',
 ROT='0',
 VER='2',
 PACK_TYPE='0201LF',
 LOCATION='R884',
 CDS_LIB='pure_quanta',
 CDS_PART_NAME='Q_RES_0201LF-4.7K,5%,1/20W,CHIP,CS24701JE04',
 PART_NUMBER='CS24701JE04',
 VALUE='4.7K',
 PRIM_FILE='./archive_libs/logical/q_res/chips/chips.prt';

PART_NAME
 R885 'Q_RES_0201LF-4.7K,5%,1/20W,CHIP,CS24701JE04':;

SECTION_NUMBER 1
 '@T6G_MB_LIB.T6G(SCH_1):PAGE451_I59@PURE_QUANTA.Q_RES(CHIPS)':
 C_PATH='@t6g_mb_lib.t6g(sch_1):page451_i59@pure_quanta.q_res(chips)',
 P_PATH='@t6g_mb_lib.t6g(sch_1):page342_i59@pure_quanta.q_res(chips)',
 PATH='I59',
 DRAWING='@T6G_MB_LIB.T6G(SCH_1):PAGE451',
 WATTAGE='1/20W',
 TOLERANCE='5%',
 MATERIAL='CHIP',
 PHYS_PAGE='342',
 XY='(-5000,6050)',
 ROT='0',
 VER='2',
 PACK_TYPE='0201LF',
 LOCATION='R885',
 CDS_LIB='pure_quanta',
 CDS_PART_NAME='Q_RES_0201LF-4.7K,5%,1/20W,CHIP,CS24701JE04',
 PART_NUMBER='CS24701JE04',
 VALUE='4.7K',
 PRIM_FILE='./archive_libs/logical/q_res/chips/chips.prt';

PART_NAME
 R886 'Q_RES_0201LF-4.7K,5%,1/20W,EMPTY,CS24701JE04':;

SECTION_NUMBER 1
 '@T6G_MB_LIB.T6G(SCH_1):PAGE451_I58@PURE_QUANTA.Q_RES(CHIPS)':
 C_PATH='@t6g_mb_lib.t6g(sch_1):page451_i58@pure_quanta.q_res(chips)',
 P_PATH='@t6g_mb_lib.t6g(sch_1):page342_i58@pure_quanta.q_res(chips)',
 PATH='I58',
 DRAWING='@T6G_MB_LIB.T6G(SCH_1):PAGE451',
 WATTAGE='1/20W',
 TOLERANCE='5%',
 MATERIAL='EMPTY',
 PHYS_PAGE='342',
 XY='(-5000,5525)',
 ROT='0',
 VER='2',
 PACK_TYPE='0201LF',
 LOCATION='R886',
 CDS_LIB='pure_quanta',
 CDS_PART_NAME='Q_RES_0201LF-4.7K,5%,1/20W,EMPTY,CS24701JE04',
 PART_NUMBER='CS24701JE04',
 VALUE='4.7K',
 PRIM_FILE='./archive_libs/logical/q_res/chips/chips.prt';

PART_NAME
 R887 'Q_RES_0201LF-1K,1%,1/20W,EMPTY,CS21001FE07':;

SECTION_NUMBER 1
 '@T6G_MB_LIB.T6G(SCH_1):PAGE451_I77@PURE_QUANTA.Q_RES(CHIPS)':
 C_PATH='@t6g_mb_lib.t6g(sch_1):page451_i77@pure_quanta.q_res(chips)',
 P_PATH='@t6g_mb_lib.t6g(sch_1):page342_i77@pure_quanta.q_res(chips)',
 PATH='I77',
 DRAWING='@T6G_MB_LIB.T6G(SCH_1):PAGE451',
 WATTAGE='1/20W',
 TOLERANCE='1%',
 MATERIAL='EMPTY',
 PHYS_PAGE='342',
 XY='(-2950,6050)',
 ROT='0',
 VER='2',
 PACK_TYPE='0201LF',
 LOCATION='R887',
 CDS_LIB='pure_quanta',
 CDS_PART_NAME='Q_RES_0201LF-1K,1%,1/20W,EMPTY,CS21001FE07',
 PART_NUMBER='CS21001FE07',
 VALUE='1K',
 PRIM_FILE='./archive_libs/logical/q_res/chips/chips.prt';

PART_NAME
 R888 'Q_RES_0402LF-10K,5%,1/16W,EMPTY,CS31002JB08':;

SECTION_NUMBER 1
 '@T6G_MB_LIB.T6G(SCH_1):PAGE349_I145@PURE_QUANTA.Q_RES(CHIPS)':
 C_PATH='@t6g_mb_lib.t6g(sch_1):page349_i145@pure_quanta.q_res(chips)',
 P_PATH='@t6g_mb_lib.t6g(sch_1):page151_i145@pure_quanta.q_res(chips)',
 PATH='I145',
 DRAWING='@T6G_MB_LIB.T6G(SCH_1):PAGE349',
 WATTAGE='1/16W',
 TOLERANCE='5%',
 MATERIAL='EMPTY',
 PHYS_PAGE='151',
 XY='(5500,6350)',
 ROT='0',
 VER='2',
 PACK_TYPE='0402LF',
 LOCATION='R888',
 CDS_LIB='pure_quanta',
 CDS_PART_NAME='Q_RES_0402LF-10K,5%,1/16W,EMPTY,CS31002JB08',
 PART_NUMBER='CS31002JB08',
 VALUE='10K',
 PRIM_FILE='./archive_libs/logical/q_res/chips/chips.prt';

PART_NAME
 R889 'Q_RES_0402LF-10K,5%,1/16W,EMPTY,CS31002JB08':;

SECTION_NUMBER 1
 '@T6G_MB_LIB.T6G(SCH_1):PAGE349_I142@PURE_QUANTA.Q_RES(CHIPS)':
 C_PATH='@t6g_mb_lib.t6g(sch_1):page349_i142@pure_quanta.q_res(chips)',
 P_PATH='@t6g_mb_lib.t6g(sch_1):page151_i142@pure_quanta.q_res(chips)',
 PATH='I142',
 DRAWING='@T6G_MB_LIB.T6G(SCH_1):PAGE349',
 WATTAGE='1/16W',
 TOLERANCE='5%',
 MATERIAL='EMPTY',
 PHYS_PAGE='151',
 XY='(5500,5875)',
 ROT='0',
 VER='2',
 PACK_TYPE='0402LF',
 LOCATION='R889',
 CDS_LIB='pure_quanta',
 CDS_PART_NAME='Q_RES_0402LF-10K,5%,1/16W,EMPTY,CS31002JB08',
 PART_NUMBER='CS31002JB08',
 VALUE='10K',
 PRIM_FILE='./archive_libs/logical/q_res/chips/chips.prt';

PART_NAME
 R890 'Q_RES_0402LF-10K,5%,1/16W,EMPTY,CS31002JB08':;

SECTION_NUMBER 1
 '@T6G_MB_LIB.T6G(SCH_1):PAGE349_I147@PURE_QUANTA.Q_RES(CHIPS)':
 C_PATH='@t6g_mb_lib.t6g(sch_1):page349_i147@pure_quanta.q_res(chips)',
 P_PATH='@t6g_mb_lib.t6g(sch_1):page151_i147@pure_quanta.q_res(chips)',
 PATH='I147',
 DRAWING='@T6G_MB_LIB.T6G(SCH_1):PAGE349',
 WATTAGE='1/16W',
 TOLERANCE='5%',
 MATERIAL='EMPTY',
 PHYS_PAGE='151',
 XY='(5700,6350)',
 ROT='0',
 VER='2',
 PACK_TYPE='0402LF',
 LOCATION='R890',
 CDS_LIB='pure_quanta',
 CDS_PART_NAME='Q_RES_0402LF-10K,5%,1/16W,EMPTY,CS31002JB08',
 PART_NUMBER='CS31002JB08',
 VALUE='10K',
 PRIM_FILE='./archive_libs/logical/q_res/chips/chips.prt';

PART_NAME
 R891 'Q_RES_0402LF-10K,5%,1/16W,EMPTY,CS31002JB08':;

SECTION_NUMBER 1
 '@T6G_MB_LIB.T6G(SCH_1):PAGE349_I144@PURE_QUANTA.Q_RES(CHIPS)':
 C_PATH='@t6g_mb_lib.t6g(sch_1):page349_i144@pure_quanta.q_res(chips)',
 P_PATH='@t6g_mb_lib.t6g(sch_1):page151_i144@pure_quanta.q_res(chips)',
 PATH='I144',
 DRAWING='@T6G_MB_LIB.T6G(SCH_1):PAGE349',
 WATTAGE='1/16W',
 TOLERANCE='5%',
 MATERIAL='EMPTY',
 PHYS_PAGE='151',
 XY='(5700,5875)',
 ROT='0',
 VER='2',
 PACK_TYPE='0402LF',
 LOCATION='R891',
 CDS_LIB='pure_quanta',
 CDS_PART_NAME='Q_RES_0402LF-10K,5%,1/16W,EMPTY,CS31002JB08',
 PART_NUMBER='CS31002JB08',
 VALUE='10K',
 PRIM_FILE='./archive_libs/logical/q_res/chips/chips.prt';

PART_NAME
 R892 'Q_RES_0201LF-1K,1%,1/20W,CHIP,CS21001FE07':;

SECTION_NUMBER 1
 '@T6G_MB_LIB.T6G(SCH_1):PAGE451_I76@PURE_QUANTA.Q_RES(CHIPS)':
 C_PATH='@t6g_mb_lib.t6g(sch_1):page451_i76@pure_quanta.q_res(chips)',
 P_PATH='@t6g_mb_lib.t6g(sch_1):page342_i76@pure_quanta.q_res(chips)',
 PATH='I76',
 DRAWING='@T6G_MB_LIB.T6G(SCH_1):PAGE451',
 WATTAGE='1/20W',
 TOLERANCE='1%',
 MATERIAL='CHIP',
 PHYS_PAGE='342',
 XY='(-2950,5300)',
 ROT='0',
 VER='2',
 PACK_TYPE='0201LF',
 LOCATION='R892',
 CDS_LIB='pure_quanta',
 CDS_PART_NAME='Q_RES_0201LF-1K,1%,1/20W,CHIP,CS21001FE07',
 PART_NUMBER='CS21001FE07',
 VALUE='1K',
 PRIM_FILE='./archive_libs/logical/q_res/chips/chips.prt';

PART_NAME
 R893 'Q_RES_0402LF-0,5%,1/16W,EMPTY,CS00002JB13':;

SECTION_NUMBER 1
 '@T6G_MB_LIB.T6G(SCH_1):PAGE465_I2@PURE_QUANTA.Q_RES(CHIPS)':
 C_PATH='@t6g_mb_lib.t6g(sch_1):page465_i2@pure_quanta.q_res(chips)',
 P_PATH='@t6g_mb_lib.t6g(sch_1):page356_i2@pure_quanta.q_res(chips)',
 PATH='I2',
 DRAWING='@T6G_MB_LIB.T6G(SCH_1):PAGE465',
 SEC_TYPE='0402LF',
 WATTAGE='1/16W',
 TOLERANCE='5%',
 MATERIAL='EMPTY',
 PHYS_PAGE='356',
 XY='(-7700,3725)',
 ROT='0',
 VER='1',
 PACK_TYPE='0402LF',
 LOCATION='R893',
 SEC='1',
 CDS_LIB='pure_quanta',
 CDS_PART_NAME='Q_RES_0402LF-0,5%,1/16W,EMPTY,CS00002JB13',
 PART_NUMBER='CS00002JB13',
 VALUE='0',
 PRIM_FILE='./archive_libs/logical/q_res/chips/chips.prt';

PART_NAME
 R894 'Q_RES_0402LF-0,5%,1/16W,EMPTY,CS00002JB13':;

SECTION_NUMBER 1
 '@T6G_MB_LIB.T6G(SCH_1):PAGE465_I1@PURE_QUANTA.Q_RES(CHIPS)':
 C_PATH='@t6g_mb_lib.t6g(sch_1):page465_i1@pure_quanta.q_res(chips)',
 P_PATH='@t6g_mb_lib.t6g(sch_1):page356_i1@pure_quanta.q_res(chips)',
 PATH='I1',
 DRAWING='@T6G_MB_LIB.T6G(SCH_1):PAGE465',
 SEC_TYPE='0402LF',
 WATTAGE='1/16W',
 TOLERANCE='5%',
 MATERIAL='EMPTY',
 PHYS_PAGE='356',
 XY='(-7700,3525)',
 ROT='0',
 VER='1',
 PACK_TYPE='0402LF',
 LOCATION='R894',
 SEC='1',
 CDS_LIB='pure_quanta',
 CDS_PART_NAME='Q_RES_0402LF-0,5%,1/16W,EMPTY,CS00002JB13',
 PART_NUMBER='CS00002JB13',
 VALUE='0',
 PRIM_FILE='./archive_libs/logical/q_res/chips/chips.prt';

PART_NAME
 R895 'Q_RES_0201LF-0,5%,1/20W,CHIP,CS00001JE10':;

SECTION_NUMBER 1
 '@T6G_MB_LIB.T6G(SCH_1):PAGE462_I69@PURE_QUANTA.Q_RES(CHIPS)':
 C_PATH='@t6g_mb_lib.t6g(sch_1):page462_i69@pure_quanta.q_res(chips)',
 P_PATH='@t6g_mb_lib.t6g(sch_1):page353_i69@pure_quanta.q_res(chips)',
 PATH='I69',
 DRAWING='@T6G_MB_LIB.T6G(SCH_1):PAGE462',
 SEC_TYPE='0201LF',
 WATTAGE='1/20W',
 TOLERANCE='5%',
 MATERIAL='CHIP',
 PHYS_PAGE='353',
 XY='(-2625,2200)',
 ROT='0',
 VER='1',
 PACK_TYPE='0201LF',
 LOCATION='R895',
 SEC='1',
 CDS_LIB='pure_quanta',
 CDS_PART_NAME='Q_RES_0201LF-0,5%,1/20W,CHIP,CS00001JE10',
 PART_NUMBER='CS00001JE10',
 VALUE='0',
 PRIM_FILE='./archive_libs/logical/q_res/chips/chips.prt';

PART_NAME
 R896 'Q_RES_0402LF-30K,1%,1/16W,EMPTY,CS33002FB02':;

SECTION_NUMBER 1
 '@T6G_MB_LIB.T6G(SCH_1):PAGE146_I35@PURE_QUANTA.Q_RES(CHIPS)':
 C_PATH='@t6g_mb_lib.t6g(sch_1):page146_i35@pure_quanta.q_res(chips)',
 P_PATH='@t6g_mb_lib.t6g(sch_1):page169_i35@pure_quanta.q_res(chips)',
 PATH='I35',
 DRAWING='@T6G_MB_LIB.T6G(SCH_1):PAGE146',
 WATTAGE='1/16W',
 TOLERANCE='1%',
 MATERIAL='EMPTY',
 PHYS_PAGE='169',
 XY='(-9050,2175)',
 ROT='0',
 VER='2',
 PACK_TYPE='0402LF',
 LOCATION='R896',
 CDS_LIB='pure_quanta',
 CDS_PART_NAME='Q_RES_0402LF-30K,1%,1/16W,EMPTY,CS33002FB02',
 PART_NUMBER='CS33002FB02',
 VALUE='30K',
 PRIM_FILE='./archive_libs/logical/q_res/chips/chips.prt';

PART_NAME
 R897 'Q_RES_0402LF-0,5%,1/16W,EMPTY,CS00002JB13':;

SECTION_NUMBER 1
 '@T6G_MB_LIB.T6G(SCH_1):PAGE465_I89@PURE_QUANTA.Q_RES(CHIPS)':
 C_PATH='@t6g_mb_lib.t6g(sch_1):page465_i89@pure_quanta.q_res(chips)',
 P_PATH='@t6g_mb_lib.t6g(sch_1):page356_i89@pure_quanta.q_res(chips)',
 PATH='I89',
 DRAWING='@T6G_MB_LIB.T6G(SCH_1):PAGE465',
 WATTAGE='1/16W',
 TOLERANCE='5%',
 MATERIAL='EMPTY',
 PHYS_PAGE='356',
 XY='(-8100,4050)',
 ROT='0',
 VER='2',
 PACK_TYPE='0402LF',
 LOCATION='R897',
 CDS_LIB='pure_quanta',
 CDS_PART_NAME='Q_RES_0402LF-0,5%,1/16W,EMPTY,CS00002JB13',
 PART_NUMBER='CS00002JB13',
 VALUE='0',
 PRIM_FILE='./archive_libs/logical/q_res/chips/chips.prt';

PART_NAME
 R898 'Q_RES_0603LF-0,5%,1/4W,EMPTY,CS00006J900':;

SECTION_NUMBER 1
 '@T6G_MB_LIB.T6G(SCH_1):PAGE465_I8@PURE_QUANTA.Q_RES(CHIPS)':
 C_PATH='@t6g_mb_lib.t6g(sch_1):page465_i8@pure_quanta.q_res(chips)',
 P_PATH='@t6g_mb_lib.t6g(sch_1):page356_i8@pure_quanta.q_res(chips)',
 PATH='I8',
 DRAWING='@T6G_MB_LIB.T6G(SCH_1):PAGE465',
 WATTAGE='1/4W',
 TOLERANCE='5%',
 MATERIAL='EMPTY',
 PHYS_PAGE='356',
 XY='(-4300,2725)',
 ROT='2',
 VER='2',
 PACK_TYPE='0603LF',
 LOCATION='R898',
 CDS_LIB='pure_quanta',
 CDS_PART_NAME='Q_RES_0603LF-0,5%,1/4W,EMPTY,CS00006J900',
 PART_NUMBER='CS00006J900',
 VALUE='0',
 PRIM_FILE='./archive_libs/logical/q_res/chips/chips.prt';

PART_NAME
 R899 'Q_RES_0402LF-0,5%,1/16W,CHIP,CS00002JB13':;

SECTION_NUMBER 1
 '@T6G_MB_LIB.T6G(SCH_1):PAGE337_I78@PURE_QUANTA.Q_RES(CHIPS)':
 C_PATH='@t6g_mb_lib.t6g(sch_1):page337_i78@pure_quanta.q_res(chips)',
 P_PATH='@t6g_mb_lib.t6g(sch_1):page133_i78@pure_quanta.q_res(chips)',
 PATH='I78',
 DRAWING='@T6G_MB_LIB.T6G(SCH_1):PAGE337',
 BOM_COST='MEM',
 WATTAGE='1/16W',
 TOLERANCE='5%',
 MATERIAL='CHIP',
 PHYS_PAGE='133',
 XY='(-6975,6975)',
 ROT='0',
 VER='1',
 PACK_TYPE='0402LF',
 LOCATION='R899',
 CDS_LIB='pure_quanta',
 CDS_PART_NAME='Q_RES_0402LF-0,5%,1/16W,CHIP,CS00002JB13',
 PART_NUMBER='CS00002JB13',
 VALUE='0',
 PRIM_FILE='./archive_libs/logical/q_res/chips/chips.prt';

PART_NAME
 R900 'Q_RES_0603LF-0,5%,1/4W,CHIP,CS00006J900':;

SECTION_NUMBER 1
 '@T6G_MB_LIB.T6G(SCH_1):PAGE465_I36@PURE_QUANTA.Q_RES(CHIPS)':
 C_PATH='@t6g_mb_lib.t6g(sch_1):page465_i36@pure_quanta.q_res(chips)',
 P_PATH='@t6g_mb_lib.t6g(sch_1):page356_i36@pure_quanta.q_res(chips)',
 PATH='I36',
 DRAWING='@T6G_MB_LIB.T6G(SCH_1):PAGE465',
 WATTAGE='1/4W',
 TOLERANCE='5%',
 MATERIAL='CHIP',
 PHYS_PAGE='356',
 XY='(-3925,2450)',
 ROT='0',
 VER='1',
 PACK_TYPE='0603LF',
 LOCATION='R900',
 CDS_LIB='pure_quanta',
 CDS_PART_NAME='Q_RES_0603LF-0,5%,1/4W,CHIP,CS00006J900',
 PART_NUMBER='CS00006J900',
 VALUE='0',
 PRIM_FILE='./archive_libs/logical/q_res/chips/chips.prt';

PART_NAME
 R901 'Q_RES_0201LF-0,5%,1/20W,CHIP,CS00001JE10':;

SECTION_NUMBER 1
 '@T6G_MB_LIB.T6G(SCH_1):PAGE462_I70@PURE_QUANTA.Q_RES(CHIPS)':
 C_PATH='@t6g_mb_lib.t6g(sch_1):page462_i70@pure_quanta.q_res(chips)',
 P_PATH='@t6g_mb_lib.t6g(sch_1):page353_i70@pure_quanta.q_res(chips)',
 PATH='I70',
 DRAWING='@T6G_MB_LIB.T6G(SCH_1):PAGE462',
 WATTAGE='1/20W',
 TOLERANCE='5%',
 MATERIAL='CHIP',
 PHYS_PAGE='353',
 XY='(-2625,2100)',
 ROT='0',
 VER='1',
 PACK_TYPE='0201LF',
 LOCATION='R901',
 CDS_LIB='pure_quanta',
 CDS_PART_NAME='Q_RES_0201LF-0,5%,1/20W,CHIP,CS00001JE10',
 PART_NUMBER='CS00001JE10',
 VALUE='0',
 PRIM_FILE='./archive_libs/logical/q_res/chips/chips.prt';

PART_NAME
 R902 'Q_RES_0201LF-1K,1%,1/20W,CHIP,CS21001FE07':;

SECTION_NUMBER 1
 '@T6G_MB_LIB.T6G(SCH_1):PAGE462_I80@PURE_QUANTA.Q_RES(CHIPS)':
 C_PATH='@t6g_mb_lib.t6g(sch_1):page462_i80@pure_quanta.q_res(chips)',
 P_PATH='@t6g_mb_lib.t6g(sch_1):page353_i80@pure_quanta.q_res(chips)',
 PATH='I80',
 DRAWING='@T6G_MB_LIB.T6G(SCH_1):PAGE462',
 WATTAGE='1/20W',
 TOLERANCE='1%',
 MATERIAL='CHIP',
 PHYS_PAGE='353',
 XY='(-3675,6100)',
 ROT='0',
 VER='2',
 PACK_TYPE='0201LF',
 LOCATION='R902',
 CDS_LIB='pure_quanta',
 CDS_PART_NAME='Q_RES_0201LF-1K,1%,1/20W,CHIP,CS21001FE07',
 PART_NUMBER='CS21001FE07',
 VALUE='1K',
 PRIM_FILE='./archive_libs/logical/q_res/chips/chips.prt';

PART_NAME
 R903 'Q_RES_0201LF-1K,1%,1/20W,EMPTY,CS21001FE07':;

SECTION_NUMBER 1
 '@T6G_MB_LIB.T6G(SCH_1):PAGE462_I79@PURE_QUANTA.Q_RES(CHIPS)':
 C_PATH='@t6g_mb_lib.t6g(sch_1):page462_i79@pure_quanta.q_res(chips)',
 P_PATH='@t6g_mb_lib.t6g(sch_1):page353_i79@pure_quanta.q_res(chips)',
 PATH='I79',
 DRAWING='@T6G_MB_LIB.T6G(SCH_1):PAGE462',
 WATTAGE='1/20W',
 TOLERANCE='1%',
 MATERIAL='EMPTY',
 PHYS_PAGE='353',
 XY='(-3675,5325)',
 ROT='0',
 VER='2',
 PACK_TYPE='0201LF',
 LOCATION='R903',
 CDS_LIB='pure_quanta',
 CDS_PART_NAME='Q_RES_0201LF-1K,1%,1/20W,EMPTY,CS21001FE07',
 PART_NUMBER='CS21001FE07',
 VALUE='1K',
 PRIM_FILE='./archive_libs/logical/q_res/chips/chips.prt';

PART_NAME
 R904 'Q_RES_0201LF-1K,1%,1/20W,EMPTY,CS21001FE07':;

SECTION_NUMBER 1
 '@T6G_MB_LIB.T6G(SCH_1):PAGE462_I82@PURE_QUANTA.Q_RES(CHIPS)':
 C_PATH='@t6g_mb_lib.t6g(sch_1):page462_i82@pure_quanta.q_res(chips)',
 P_PATH='@t6g_mb_lib.t6g(sch_1):page353_i82@pure_quanta.q_res(chips)',
 PATH='I82',
 DRAWING='@T6G_MB_LIB.T6G(SCH_1):PAGE462',
 WATTAGE='1/20W',
 TOLERANCE='1%',
 MATERIAL='EMPTY',
 PHYS_PAGE='353',
 XY='(-3375,6100)',
 ROT='0',
 VER='2',
 PACK_TYPE='0201LF',
 LOCATION='R904',
 CDS_LIB='pure_quanta',
 CDS_PART_NAME='Q_RES_0201LF-1K,1%,1/20W,EMPTY,CS21001FE07',
 PART_NUMBER='CS21001FE07',
 VALUE='1K',
 PRIM_FILE='./archive_libs/logical/q_res/chips/chips.prt';

PART_NAME
 R905 'Q_RES_0402LF-0,5%,1/16W,CHIP,CS00002JB13':;

SECTION_NUMBER 1
 '@T6G_MB_LIB.T6G(SCH_1):PAGE337_I80@PURE_QUANTA.Q_RES(CHIPS)':
 C_PATH='@t6g_mb_lib.t6g(sch_1):page337_i80@pure_quanta.q_res(chips)',
 P_PATH='@t6g_mb_lib.t6g(sch_1):page133_i80@pure_quanta.q_res(chips)',
 PATH='I80',
 DRAWING='@T6G_MB_LIB.T6G(SCH_1):PAGE337',
 BOM_COST='MEM',
 WATTAGE='1/16W',
 TOLERANCE='5%',
 MATERIAL='CHIP',
 PHYS_PAGE='133',
 XY='(-6975,6925)',
 ROT='0',
 VER='1',
 PACK_TYPE='0402LF',
 LOCATION='R905',
 CDS_LIB='pure_quanta',
 CDS_PART_NAME='Q_RES_0402LF-0,5%,1/16W,CHIP,CS00002JB13',
 PART_NUMBER='CS00002JB13',
 VALUE='0',
 PRIM_FILE='./archive_libs/logical/q_res/chips/chips.prt';

PART_NAME
 R906 'Q_RES_0201LF-20K,1%,1/20W,CHIP,CS32001FE00':;

SECTION_NUMBER 1
 '@T6G_MB_LIB.T6G(SCH_1):PAGE462_I81@PURE_QUANTA.Q_RES(CHIPS)':
 C_PATH='@t6g_mb_lib.t6g(sch_1):page462_i81@pure_quanta.q_res(chips)',
 P_PATH='@t6g_mb_lib.t6g(sch_1):page353_i81@pure_quanta.q_res(chips)',
 PATH='I81',
 DRAWING='@T6G_MB_LIB.T6G(SCH_1):PAGE462',
 WATTAGE='1/20W',
 TOLERANCE='1%',
 MATERIAL='CHIP',
 PHYS_PAGE='353',
 XY='(-3375,5325)',
 ROT='0',
 VER='2',
 PACK_TYPE='0201LF',
 LOCATION='R906',
 CDS_LIB='pure_quanta',
 CDS_PART_NAME='Q_RES_0201LF-20K,1%,1/20W,CHIP,CS32001FE00',
 PART_NUMBER='CS32001FE00',
 VALUE='20K',
 PRIM_FILE='./archive_libs/logical/q_res/chips/chips.prt';

PART_NAME
 R907 'Q_RES_0201LF-10K,1%,1/20W,CHIP,CS31001FE17':;

SECTION_NUMBER 1
 '@T6G_MB_LIB.T6G(SCH_1):PAGE462_I92@PURE_QUANTA.Q_RES(CHIPS)':
 C_PATH='@t6g_mb_lib.t6g(sch_1):page462_i92@pure_quanta.q_res(chips)',
 P_PATH='@t6g_mb_lib.t6g(sch_1):page353_i92@pure_quanta.q_res(chips)',
 PATH='I92',
 DRAWING='@T6G_MB_LIB.T6G(SCH_1):PAGE462',
 WATTAGE='1/20W',
 TOLERANCE='1%',
 MATERIAL='CHIP',
 PHYS_PAGE='353',
 XY='(-1350,5225)',
 ROT='0',
 VER='2',
 PACK_TYPE='0201LF',
 LOCATION='R907',
 CDS_LIB='pure_quanta',
 CDS_PART_NAME='Q_RES_0201LF-10K,1%,1/20W,CHIP,CS31001FE17',
 PART_NUMBER='CS31001FE17',
 VALUE='10K',
 PRIM_FILE='./archive_libs/logical/q_res/chips/chips.prt';

PART_NAME
 R908 'Q_RES_0201LF-10K,1%,1/20W,CHIP,CS31001FE17':;

SECTION_NUMBER 1
 '@T6G_MB_LIB.T6G(SCH_1):PAGE462_I90@PURE_QUANTA.Q_RES(CHIPS)':
 C_PATH='@t6g_mb_lib.t6g(sch_1):page462_i90@pure_quanta.q_res(chips)',
 P_PATH='@t6g_mb_lib.t6g(sch_1):page353_i90@pure_quanta.q_res(chips)',
 PATH='I90',
 DRAWING='@T6G_MB_LIB.T6G(SCH_1):PAGE462',
 WATTAGE='1/20W',
 TOLERANCE='1%',
 MATERIAL='CHIP',
 PHYS_PAGE='353',
 XY='(-1525,5225)',
 ROT='2',
 VER='2',
 PACK_TYPE='0201LF',
 LOCATION='R908',
 CDS_LIB='pure_quanta',
 CDS_PART_NAME='Q_RES_0201LF-10K,1%,1/20W,CHIP,CS31001FE17',
 PART_NUMBER='CS31001FE17',
 VALUE='10K',
 PRIM_FILE='./archive_libs/logical/q_res/chips/chips.prt';

PART_NAME
 R909 'Q_RES_0201LF-4.7K,5%,1/20W,EMPTY,CS24701JE04':;

SECTION_NUMBER 1
 '@T6G_MB_LIB.T6G(SCH_1):PAGE462_I17@PURE_QUANTA.Q_RES(CHIPS)':
 C_PATH='@t6g_mb_lib.t6g(sch_1):page462_i17@pure_quanta.q_res(chips)',
 P_PATH='@t6g_mb_lib.t6g(sch_1):page353_i17@pure_quanta.q_res(chips)',
 PATH='I17',
 DRAWING='@T6G_MB_LIB.T6G(SCH_1):PAGE462',
 WATTAGE='1/20W',
 TOLERANCE='5%',
 MATERIAL='EMPTY',
 PHYS_PAGE='353',
 XY='(-9025,4125)',
 ROT='0',
 VER='2',
 PACK_TYPE='0201LF',
 LOCATION='R909',
 CDS_LIB='pure_quanta',
 CDS_PART_NAME='Q_RES_0201LF-4.7K,5%,1/20W,EMPTY,CS24701JE04',
 PART_NUMBER='CS24701JE04',
 VALUE='4.7K',
 PRIM_FILE='./archive_libs/logical/q_res/chips/chips.prt';

PART_NAME
 R910 'Q_RES_0201LF-200,1%,1/20W,CHIP,CS12001FE12':;

SECTION_NUMBER 1
 '@T6G_MB_LIB.T6G(SCH_1):PAGE462_I119@PURE_QUANTA.Q_RES(CHIPS)':
 C_PATH='@t6g_mb_lib.t6g(sch_1):page462_i119@pure_quanta.q_res(chips)',
 P_PATH='@t6g_mb_lib.t6g(sch_1):page353_i119@pure_quanta.q_res(chips)',
 PATH='I119',
 DRAWING='@T6G_MB_LIB.T6G(SCH_1):PAGE462',
 WATTAGE='1/20W',
 TOLERANCE='1%',
 MATERIAL='CHIP',
 PHYS_PAGE='353',
 XY='(-9025,3450)',
 ROT='0',
 VER='2',
 PACK_TYPE='0201LF',
 LOCATION='R910',
 CDS_LIB='pure_quanta',
 CDS_PART_NAME='Q_RES_0201LF-200,1%,1/20W,CHIP,CS12001FE12',
 PART_NUMBER='CS12001FE12',
 VALUE='200',
 PRIM_FILE='./archive_libs/logical/q_res/chips/chips.prt';

PART_NAME
 R911 'Q_RES_0201LF-4.7K,5%,1/20W,EMPTY,CS24701JE04':;

SECTION_NUMBER 1
 '@T6G_MB_LIB.T6G(SCH_1):PAGE462_I93@PURE_QUANTA.Q_RES(CHIPS)':
 C_PATH='@t6g_mb_lib.t6g(sch_1):page462_i93@pure_quanta.q_res(chips)',
 P_PATH='@t6g_mb_lib.t6g(sch_1):page353_i93@pure_quanta.q_res(chips)',
 PATH='I93',
 DRAWING='@T6G_MB_LIB.T6G(SCH_1):PAGE462',
 WATTAGE='1/20W',
 TOLERANCE='5%',
 MATERIAL='EMPTY',
 PHYS_PAGE='353',
 XY='(-1525,6050)',
 ROT='2',
 VER='2',
 PACK_TYPE='0201LF',
 LOCATION='R911',
 CDS_LIB='pure_quanta',
 CDS_PART_NAME='Q_RES_0201LF-4.7K,5%,1/20W,EMPTY,CS24701JE04',
 PART_NUMBER='CS24701JE04',
 VALUE='4.7K',
 PRIM_FILE='./archive_libs/logical/q_res/chips/chips.prt';

PART_NAME
 R912 'Q_RES_0201LF-4.7K,5%,1/20W,EMPTY,CS24701JE04':;

SECTION_NUMBER 1
 '@T6G_MB_LIB.T6G(SCH_1):PAGE462_I56@PURE_QUANTA.Q_RES(CHIPS)':
 C_PATH='@t6g_mb_lib.t6g(sch_1):page462_i56@pure_quanta.q_res(chips)',
 P_PATH='@t6g_mb_lib.t6g(sch_1):page353_i56@pure_quanta.q_res(chips)',
 PATH='I56',
 DRAWING='@T6G_MB_LIB.T6G(SCH_1):PAGE462',
 WATTAGE='1/20W',
 TOLERANCE='5%',
 MATERIAL='EMPTY',
 PHYS_PAGE='353',
 XY='(-7475,6000)',
 ROT='0',
 VER='2',
 PACK_TYPE='0201LF',
 LOCATION='R912',
 CDS_LIB='pure_quanta',
 CDS_PART_NAME='Q_RES_0201LF-4.7K,5%,1/20W,EMPTY,CS24701JE04',
 PART_NUMBER='CS24701JE04',
 VALUE='4.7K',
 PRIM_FILE='./archive_libs/logical/q_res/chips/chips.prt';

PART_NAME
 R913 'Q_RES_0201LF-0,5%,1/20W,CHIP,CS00001JE10':;

SECTION_NUMBER 1
 '@T6G_MB_LIB.T6G(SCH_1):PAGE462_I42@PURE_QUANTA.Q_RES(CHIPS)':
 C_PATH='@t6g_mb_lib.t6g(sch_1):page462_i42@pure_quanta.q_res(chips)',
 P_PATH='@t6g_mb_lib.t6g(sch_1):page353_i42@pure_quanta.q_res(chips)',
 PATH='I42',
 DRAWING='@T6G_MB_LIB.T6G(SCH_1):PAGE462',
 WATTAGE='1/20W',
 TOLERANCE='5%',
 MATERIAL='CHIP',
 PHYS_PAGE='353',
 XY='(-6400,2900)',
 ROT='0',
 VER='1',
 PACK_TYPE='0201LF',
 LOCATION='R913',
 CDS_LIB='pure_quanta',
 CDS_PART_NAME='Q_RES_0201LF-0,5%,1/20W,CHIP,CS00001JE10',
 PART_NUMBER='CS00001JE10',
 VALUE='0',
 PRIM_FILE='./archive_libs/logical/q_res/chips/chips.prt';

PART_NAME
 R914 'Q_RES_0201LF-0,5%,1/20W,CHIP,CS00001JE10':;

SECTION_NUMBER 1
 '@T6G_MB_LIB.T6G(SCH_1):PAGE462_I41@PURE_QUANTA.Q_RES(CHIPS)':
 C_PATH='@t6g_mb_lib.t6g(sch_1):page462_i41@pure_quanta.q_res(chips)',
 P_PATH='@t6g_mb_lib.t6g(sch_1):page353_i41@pure_quanta.q_res(chips)',
 PATH='I41',
 DRAWING='@T6G_MB_LIB.T6G(SCH_1):PAGE462',
 WATTAGE='1/20W',
 TOLERANCE='5%',
 MATERIAL='CHIP',
 PHYS_PAGE='353',
 XY='(-6400,2800)',
 ROT='0',
 VER='1',
 PACK_TYPE='0201LF',
 LOCATION='R914',
 CDS_LIB='pure_quanta',
 CDS_PART_NAME='Q_RES_0201LF-0,5%,1/20W,CHIP,CS00001JE10',
 PART_NUMBER='CS00001JE10',
 VALUE='0',
 PRIM_FILE='./archive_libs/logical/q_res/chips/chips.prt';

PART_NAME
 R915 'Q_RES_0201LF-4.7K,5%,1/20W,EMPTY,CS24701JE04':;

SECTION_NUMBER 1
 '@T6G_MB_LIB.T6G(SCH_1):PAGE462_I22@PURE_QUANTA.Q_RES(CHIPS)':
 C_PATH='@t6g_mb_lib.t6g(sch_1):page462_i22@pure_quanta.q_res(chips)',
 P_PATH='@t6g_mb_lib.t6g(sch_1):page353_i22@pure_quanta.q_res(chips)',
 PATH='I22',
 DRAWING='@T6G_MB_LIB.T6G(SCH_1):PAGE462',
 WATTAGE='1/20W',
 TOLERANCE='5%',
 MATERIAL='EMPTY',
 PHYS_PAGE='353',
 XY='(-9000,6000)',
 ROT='0',
 VER='2',
 PACK_TYPE='0201LF',
 LOCATION='R915',
 CDS_LIB='pure_quanta',
 CDS_PART_NAME='Q_RES_0201LF-4.7K,5%,1/20W,EMPTY,CS24701JE04',
 PART_NUMBER='CS24701JE04',
 VALUE='4.7K',
 PRIM_FILE='./archive_libs/logical/q_res/chips/chips.prt';

PART_NAME
 R916 'Q_RES_0201LF-10K,1%,1/20W,CHIP,CS31001FE17':;

SECTION_NUMBER 1
 '@T6G_MB_LIB.T6G(SCH_1):PAGE462_I19@PURE_QUANTA.Q_RES(CHIPS)':
 C_PATH='@t6g_mb_lib.t6g(sch_1):page462_i19@pure_quanta.q_res(chips)',
 P_PATH='@t6g_mb_lib.t6g(sch_1):page353_i19@pure_quanta.q_res(chips)',
 PATH='I19',
 DRAWING='@T6G_MB_LIB.T6G(SCH_1):PAGE462',
 WATTAGE='1/20W',
 TOLERANCE='1%',
 MATERIAL='CHIP',
 PHYS_PAGE='353',
 XY='(-9000,5050)',
 ROT='0',
 VER='2',
 PACK_TYPE='0201LF',
 LOCATION='R916',
 CDS_LIB='pure_quanta',
 CDS_PART_NAME='Q_RES_0201LF-10K,1%,1/20W,CHIP,CS31001FE17',
 PART_NUMBER='CS31001FE17',
 VALUE='10K',
 PRIM_FILE='./archive_libs/logical/q_res/chips/chips.prt';

PART_NAME
 R917 'Q_RES_0201LF-10K,1%,1/20W,CHIP,CS31001FE17':;

SECTION_NUMBER 1
 '@T6G_MB_LIB.T6G(SCH_1):PAGE462_I20@PURE_QUANTA.Q_RES(CHIPS)':
 C_PATH='@t6g_mb_lib.t6g(sch_1):page462_i20@pure_quanta.q_res(chips)',
 P_PATH='@t6g_mb_lib.t6g(sch_1):page353_i20@pure_quanta.q_res(chips)',
 PATH='I20',
 DRAWING='@T6G_MB_LIB.T6G(SCH_1):PAGE462',
 WATTAGE='1/20W',
 TOLERANCE='1%',
 MATERIAL='CHIP',
 PHYS_PAGE='353',
 XY='(-8700,5050)',
 ROT='0',
 VER='2',
 PACK_TYPE='0201LF',
 LOCATION='R917',
 CDS_LIB='pure_quanta',
 CDS_PART_NAME='Q_RES_0201LF-10K,1%,1/20W,CHIP,CS31001FE17',
 PART_NUMBER='CS31001FE17',
 VALUE='10K',
 PRIM_FILE='./archive_libs/logical/q_res/chips/chips.prt';

PART_NAME
 R918 'Q_RES_0201LF-4.7K,5%,1/20W,EMPTY,CS24701JE04':;

SECTION_NUMBER 1
 '@T6G_MB_LIB.T6G(SCH_1):PAGE462_I23@PURE_QUANTA.Q_RES(CHIPS)':
 C_PATH='@t6g_mb_lib.t6g(sch_1):page462_i23@pure_quanta.q_res(chips)',
 P_PATH='@t6g_mb_lib.t6g(sch_1):page353_i23@pure_quanta.q_res(chips)',
 PATH='I23',
 DRAWING='@T6G_MB_LIB.T6G(SCH_1):PAGE462',
 WATTAGE='1/20W',
 TOLERANCE='5%',
 MATERIAL='EMPTY',
 PHYS_PAGE='353',
 XY='(-8375,6000)',
 ROT='0',
 VER='2',
 PACK_TYPE='0201LF',
 LOCATION='R918',
 CDS_LIB='pure_quanta',
 CDS_PART_NAME='Q_RES_0201LF-4.7K,5%,1/20W,EMPTY,CS24701JE04',
 PART_NUMBER='CS24701JE04',
 VALUE='4.7K',
 PRIM_FILE='./archive_libs/logical/q_res/chips/chips.prt';

PART_NAME
 R919 'Q_RES_0201LF-4.7K,5%,1/20W,CHIP,CS24701JE04':;

SECTION_NUMBER 1
 '@T6G_MB_LIB.T6G(SCH_1):PAGE462_I21@PURE_QUANTA.Q_RES(CHIPS)':
 C_PATH='@t6g_mb_lib.t6g(sch_1):page462_i21@pure_quanta.q_res(chips)',
 P_PATH='@t6g_mb_lib.t6g(sch_1):page353_i21@pure_quanta.q_res(chips)',
 PATH='I21',
 DRAWING='@T6G_MB_LIB.T6G(SCH_1):PAGE462',
 WATTAGE='1/20W',
 TOLERANCE='5%',
 MATERIAL='CHIP',
 PHYS_PAGE='353',
 XY='(-8375,5050)',
 ROT='0',
 VER='2',
 PACK_TYPE='0201LF',
 LOCATION='R919',
 CDS_LIB='pure_quanta',
 CDS_PART_NAME='Q_RES_0201LF-4.7K,5%,1/20W,CHIP,CS24701JE04',
 PART_NUMBER='CS24701JE04',
 VALUE='4.7K',
 PRIM_FILE='./archive_libs/logical/q_res/chips/chips.prt';

PART_NAME
 R920 'Q_RES_0201LF-4.7K,5%,1/20W,EMPTY,CS24701JE04':;

SECTION_NUMBER 1
 '@T6G_MB_LIB.T6G(SCH_1):PAGE462_I54@PURE_QUANTA.Q_RES(CHIPS)':
 C_PATH='@t6g_mb_lib.t6g(sch_1):page462_i54@pure_quanta.q_res(chips)',
 P_PATH='@t6g_mb_lib.t6g(sch_1):page353_i54@pure_quanta.q_res(chips)',
 PATH='I54',
 DRAWING='@T6G_MB_LIB.T6G(SCH_1):PAGE462',
 WATTAGE='1/20W',
 TOLERANCE='5%',
 MATERIAL='EMPTY',
 PHYS_PAGE='353',
 XY='(-8075,5950)',
 ROT='0',
 VER='2',
 PACK_TYPE='0201LF',
 LOCATION='R920',
 CDS_LIB='pure_quanta',
 CDS_PART_NAME='Q_RES_0201LF-4.7K,5%,1/20W,EMPTY,CS24701JE04',
 PART_NUMBER='CS24701JE04',
 VALUE='4.7K',
 PRIM_FILE='./archive_libs/logical/q_res/chips/chips.prt';

PART_NAME
 R921 'Q_RES_0201LF-4.7K,5%,1/20W,CHIP,CS24701JE04':;

SECTION_NUMBER 1
 '@T6G_MB_LIB.T6G(SCH_1):PAGE462_I50@PURE_QUANTA.Q_RES(CHIPS)':
 C_PATH='@t6g_mb_lib.t6g(sch_1):page462_i50@pure_quanta.q_res(chips)',
 P_PATH='@t6g_mb_lib.t6g(sch_1):page353_i50@pure_quanta.q_res(chips)',
 PATH='I50',
 DRAWING='@T6G_MB_LIB.T6G(SCH_1):PAGE462',
 WATTAGE='1/20W',
 TOLERANCE='5%',
 MATERIAL='CHIP',
 PHYS_PAGE='353',
 XY='(-8075,5025)',
 ROT='0',
 VER='2',
 PACK_TYPE='0201LF',
 LOCATION='R921',
 CDS_LIB='pure_quanta',
 CDS_PART_NAME='Q_RES_0201LF-4.7K,5%,1/20W,CHIP,CS24701JE04',
 PART_NUMBER='CS24701JE04',
 VALUE='4.7K',
 PRIM_FILE='./archive_libs/logical/q_res/chips/chips.prt';

PART_NAME
 R922 'Q_RES_0201LF-4.7K,5%,1/20W,EMPTY,CS24701JE04':;

SECTION_NUMBER 1
 '@T6G_MB_LIB.T6G(SCH_1):PAGE462_I55@PURE_QUANTA.Q_RES(CHIPS)':
 C_PATH='@t6g_mb_lib.t6g(sch_1):page462_i55@pure_quanta.q_res(chips)',
 P_PATH='@t6g_mb_lib.t6g(sch_1):page353_i55@pure_quanta.q_res(chips)',
 PATH='I55',
 DRAWING='@T6G_MB_LIB.T6G(SCH_1):PAGE462',
 WATTAGE='1/20W',
 TOLERANCE='5%',
 MATERIAL='EMPTY',
 PHYS_PAGE='353',
 XY='(-7775,5975)',
 ROT='0',
 VER='2',
 PACK_TYPE='0201LF',
 LOCATION='R922',
 CDS_LIB='pure_quanta',
 CDS_PART_NAME='Q_RES_0201LF-4.7K,5%,1/20W,EMPTY,CS24701JE04',
 PART_NUMBER='CS24701JE04',
 VALUE='4.7K',
 PRIM_FILE='./archive_libs/logical/q_res/chips/chips.prt';

PART_NAME
 R923 'Q_RES_0201LF-4.7K,5%,1/20W,CHIP,CS24701JE04':;

SECTION_NUMBER 1
 '@T6G_MB_LIB.T6G(SCH_1):PAGE462_I51@PURE_QUANTA.Q_RES(CHIPS)':
 C_PATH='@t6g_mb_lib.t6g(sch_1):page462_i51@pure_quanta.q_res(chips)',
 P_PATH='@t6g_mb_lib.t6g(sch_1):page353_i51@pure_quanta.q_res(chips)',
 PATH='I51',
 DRAWING='@T6G_MB_LIB.T6G(SCH_1):PAGE462',
 WATTAGE='1/20W',
 TOLERANCE='5%',
 MATERIAL='CHIP',
 PHYS_PAGE='353',
 XY='(-7775,5025)',
 ROT='0',
 VER='2',
 PACK_TYPE='0201LF',
 LOCATION='R923',
 CDS_LIB='pure_quanta',
 CDS_PART_NAME='Q_RES_0201LF-4.7K,5%,1/20W,CHIP,CS24701JE04',
 PART_NUMBER='CS24701JE04',
 VALUE='4.7K',
 PRIM_FILE='./archive_libs/logical/q_res/chips/chips.prt';

PART_NAME
 R924 'Q_RES_0201LF-4.7K,5%,1/20W,CHIP,CS24701JE04':;

SECTION_NUMBER 1
 '@T6G_MB_LIB.T6G(SCH_1):PAGE462_I53@PURE_QUANTA.Q_RES(CHIPS)':
 C_PATH='@t6g_mb_lib.t6g(sch_1):page462_i53@pure_quanta.q_res(chips)',
 P_PATH='@t6g_mb_lib.t6g(sch_1):page353_i53@pure_quanta.q_res(chips)',
 PATH='I53',
 DRAWING='@T6G_MB_LIB.T6G(SCH_1):PAGE462',
 WATTAGE='1/20W',
 TOLERANCE='5%',
 MATERIAL='CHIP',
 PHYS_PAGE='353',
 XY='(-7475,5000)',
 ROT='0',
 VER='2',
 PACK_TYPE='0201LF',
 LOCATION='R924',
 CDS_LIB='pure_quanta',
 CDS_PART_NAME='Q_RES_0201LF-4.7K,5%,1/20W,CHIP,CS24701JE04',
 PART_NUMBER='CS24701JE04',
 VALUE='4.7K',
 PRIM_FILE='./archive_libs/logical/q_res/chips/chips.prt';

PART_NAME
 R925 'Q_RES_0201LF-4.7K,5%,1/20W,CHIP,CS24701JE04':;

SECTION_NUMBER 1
 '@T6G_MB_LIB.T6G(SCH_1):PAGE462_I65@PURE_QUANTA.Q_RES(CHIPS)':
 C_PATH='@t6g_mb_lib.t6g(sch_1):page462_i65@pure_quanta.q_res(chips)',
 P_PATH='@t6g_mb_lib.t6g(sch_1):page353_i65@pure_quanta.q_res(chips)',
 PATH='I65',
 DRAWING='@T6G_MB_LIB.T6G(SCH_1):PAGE462',
 WATTAGE='1/20W',
 TOLERANCE='5%',
 MATERIAL='CHIP',
 PHYS_PAGE='353',
 XY='(-5075,6075)',
 ROT='0',
 VER='2',
 PACK_TYPE='0201LF',
 LOCATION='R925',
 CDS_LIB='pure_quanta',
 CDS_PART_NAME='Q_RES_0201LF-4.7K,5%,1/20W,CHIP,CS24701JE04',
 PART_NUMBER='CS24701JE04',
 VALUE='4.7K',
 PRIM_FILE='./archive_libs/logical/q_res/chips/chips.prt';

PART_NAME
 R926 'Q_RES_0201LF-4.7K,5%,1/20W,EMPTY,CS24701JE04':;

SECTION_NUMBER 1
 '@T6G_MB_LIB.T6G(SCH_1):PAGE462_I64@PURE_QUANTA.Q_RES(CHIPS)':
 C_PATH='@t6g_mb_lib.t6g(sch_1):page462_i64@pure_quanta.q_res(chips)',
 P_PATH='@t6g_mb_lib.t6g(sch_1):page353_i64@pure_quanta.q_res(chips)',
 PATH='I64',
 DRAWING='@T6G_MB_LIB.T6G(SCH_1):PAGE462',
 WATTAGE='1/20W',
 TOLERANCE='5%',
 MATERIAL='EMPTY',
 PHYS_PAGE='353',
 XY='(-5075,5550)',
 ROT='0',
 VER='2',
 PACK_TYPE='0201LF',
 LOCATION='R926',
 CDS_LIB='pure_quanta',
 CDS_PART_NAME='Q_RES_0201LF-4.7K,5%,1/20W,EMPTY,CS24701JE04',
 PART_NUMBER='CS24701JE04',
 VALUE='4.7K',
 PRIM_FILE='./archive_libs/logical/q_res/chips/chips.prt';

PART_NAME
 R927 'Q_RES_0201LF-1K,1%,1/20W,EMPTY,CS21001FE07':;

SECTION_NUMBER 1
 '@T6G_MB_LIB.T6G(SCH_1):PAGE462_I84@PURE_QUANTA.Q_RES(CHIPS)':
 C_PATH='@t6g_mb_lib.t6g(sch_1):page462_i84@pure_quanta.q_res(chips)',
 P_PATH='@t6g_mb_lib.t6g(sch_1):page353_i84@pure_quanta.q_res(chips)',
 PATH='I84',
 DRAWING='@T6G_MB_LIB.T6G(SCH_1):PAGE462',
 WATTAGE='1/20W',
 TOLERANCE='1%',
 MATERIAL='EMPTY',
 PHYS_PAGE='353',
 XY='(-3025,6075)',
 ROT='0',
 VER='2',
 PACK_TYPE='0201LF',
 LOCATION='R927',
 CDS_LIB='pure_quanta',
 CDS_PART_NAME='Q_RES_0201LF-1K,1%,1/20W,EMPTY,CS21001FE07',
 PART_NUMBER='CS21001FE07',
 VALUE='1K',
 PRIM_FILE='./archive_libs/logical/q_res/chips/chips.prt';

PART_NAME
 R928 'Q_RES_0402LF-0,5%,1/16W,CHIP,CS00002JB13':;

SECTION_NUMBER 1
 '@T6G_MB_LIB.T6G(SCH_1):PAGE54_I363@PURE_QUANTA.Q_RES(CHIPS)':
 C_PATH='@t6g_mb_lib.t6g(sch_1):page54_i363@pure_quanta.q_res(chips)',
 P_PATH='@t6g_mb_lib.t6g(sch_1):page54_i363@pure_quanta.q_res(chips)',
 PATH='I363',
 DRAWING='@T6G_MB_LIB.T6G(SCH_1):PAGE54',
 WATTAGE='1/16W',
 TOLERANCE='5%',
 MATERIAL='CHIP',
 PHYS_PAGE='54',
 XY='(-3100,4675)',
 ROT='0',
 VER='1',
 PACK_TYPE='0402LF',
 LOCATION='R928',
 CDS_LIB='pure_quanta',
 CDS_PART_NAME='Q_RES_0402LF-0,5%,1/16W,CHIP,CS00002JB13',
 PART_NUMBER='CS00002JB13',
 VALUE='0',
 PRIM_FILE='./archive_libs/logical/q_res/chips/chips.prt';

PART_NAME
 R929 'Q_RES_0402LF-0,5%,1/16W,CHIP,CS00002JB13':;

SECTION_NUMBER 1
 '@T6G_MB_LIB.T6G(SCH_1):PAGE54_I371@PURE_QUANTA.Q_RES(CHIPS)':
 C_PATH='@t6g_mb_lib.t6g(sch_1):page54_i371@pure_quanta.q_res(chips)',
 P_PATH='@t6g_mb_lib.t6g(sch_1):page54_i371@pure_quanta.q_res(chips)',
 PATH='I371',
 DRAWING='@T6G_MB_LIB.T6G(SCH_1):PAGE54',
 WATTAGE='1/16W',
 TOLERANCE='5%',
 MATERIAL='CHIP',
 PHYS_PAGE='54',
 XY='(-1425,3650)',
 ROT='0',
 VER='1',
 PACK_TYPE='0402LF',
 LOCATION='R929',
 CDS_LIB='pure_quanta',
 CDS_PART_NAME='Q_RES_0402LF-0,5%,1/16W,CHIP,CS00002JB13',
 PART_NUMBER='CS00002JB13',
 VALUE='0',
 PRIM_FILE='./archive_libs/logical/q_res/chips/chips.prt';

PART_NAME
 R930 'Q_RES_0402LF-0,5%,1/16W,CHIP,CS00002JB13':;

SECTION_NUMBER 1
 '@T6G_MB_LIB.T6G(SCH_1):PAGE54_I372@PURE_QUANTA.Q_RES(CHIPS)':
 C_PATH='@t6g_mb_lib.t6g(sch_1):page54_i372@pure_quanta.q_res(chips)',
 P_PATH='@t6g_mb_lib.t6g(sch_1):page54_i372@pure_quanta.q_res(chips)',
 PATH='I372',
 DRAWING='@T6G_MB_LIB.T6G(SCH_1):PAGE54',
 WATTAGE='1/16W',
 TOLERANCE='5%',
 MATERIAL='CHIP',
 PHYS_PAGE='54',
 XY='(-1425,3600)',
 ROT='0',
 VER='1',
 PACK_TYPE='0402LF',
 LOCATION='R930',
 CDS_LIB='pure_quanta',
 CDS_PART_NAME='Q_RES_0402LF-0,5%,1/16W,CHIP,CS00002JB13',
 PART_NUMBER='CS00002JB13',
 VALUE='0',
 PRIM_FILE='./archive_libs/logical/q_res/chips/chips.prt';

PART_NAME
 R931 'Q_RES_0402LF-0,5%,1/16W,CHIP,CS00002JB13':;

SECTION_NUMBER 1
 '@T6G_MB_LIB.T6G(SCH_1):PAGE54_I374@PURE_QUANTA.Q_RES(CHIPS)':
 C_PATH='@t6g_mb_lib.t6g(sch_1):page54_i374@pure_quanta.q_res(chips)',
 P_PATH='@t6g_mb_lib.t6g(sch_1):page54_i374@pure_quanta.q_res(chips)',
 PATH='I374',
 DRAWING='@T6G_MB_LIB.T6G(SCH_1):PAGE54',
 WATTAGE='1/16W',
 TOLERANCE='5%',
 MATERIAL='CHIP',
 PHYS_PAGE='54',
 XY='(-1425,3550)',
 ROT='0',
 VER='1',
 PACK_TYPE='0402LF',
 LOCATION='R931',
 CDS_LIB='pure_quanta',
 CDS_PART_NAME='Q_RES_0402LF-0,5%,1/16W,CHIP,CS00002JB13',
 PART_NUMBER='CS00002JB13',
 VALUE='0',
 PRIM_FILE='./archive_libs/logical/q_res/chips/chips.prt';

PART_NAME
 R932 'Q_RES_0402LF-0,5%,1/16W,CHIP,CS00002JB13':;

SECTION_NUMBER 1
 '@T6G_MB_LIB.T6G(SCH_1):PAGE54_I373@PURE_QUANTA.Q_RES(CHIPS)':
 C_PATH='@t6g_mb_lib.t6g(sch_1):page54_i373@pure_quanta.q_res(chips)',
 P_PATH='@t6g_mb_lib.t6g(sch_1):page54_i373@pure_quanta.q_res(chips)',
 PATH='I373',
 DRAWING='@T6G_MB_LIB.T6G(SCH_1):PAGE54',
 WATTAGE='1/16W',
 TOLERANCE='5%',
 MATERIAL='CHIP',
 PHYS_PAGE='54',
 XY='(-1425,3500)',
 ROT='0',
 VER='1',
 PACK_TYPE='0402LF',
 LOCATION='R932',
 CDS_LIB='pure_quanta',
 CDS_PART_NAME='Q_RES_0402LF-0,5%,1/16W,CHIP,CS00002JB13',
 PART_NUMBER='CS00002JB13',
 VALUE='0',
 PRIM_FILE='./archive_libs/logical/q_res/chips/chips.prt';

PART_NAME
 R933 'Q_RES_0402LF-33,5%,1/16W,CHIP,CS03302JB10':;

SECTION_NUMBER 1
 '@T6G_MB_LIB.T6G(SCH_1):PAGE80_I215@PURE_QUANTA.Q_RES(CHIPS)':
 C_PATH='@t6g_mb_lib.t6g(sch_1):page80_i215@pure_quanta.q_res(chips)',
 P_PATH='@t6g_mb_lib.t6g(sch_1):page81_i215@pure_quanta.q_res(chips)',
 PATH='I215',
 DRAWING='@T6G_MB_LIB.T6G(SCH_1):PAGE80',
 BOM_COST='MEM',
 WATTAGE='1/16W',
 TOLERANCE='5%',
 MATERIAL='CHIP',
 PHYS_PAGE='81',
 XY='(-3225,6175)',
 ROT='0',
 VER='1',
 PACK_TYPE='0402LF',
 LOCATION='R933',
 CDS_LIB='pure_quanta',
 CDS_PART_NAME='Q_RES_0402LF-33,5%,1/16W,CHIP,CS03302JB10',
 PART_NUMBER='CS03302JB10',
 VALUE='33',
 PRIM_FILE='./archive_libs/logical/q_res/chips/chips.prt';

PART_NAME
 R934 'Q_RES_0402LF-0,5%,1/16W,CHIP,CS00002JB13':;

SECTION_NUMBER 1
 '@T6G_MB_LIB.T6G(SCH_1):PAGE143_I33@PURE_QUANTA.Q_RES(CHIPS)':
 C_PATH='@t6g_mb_lib.t6g(sch_1):page143_i33@pure_quanta.q_res(chips)',
 P_PATH='@t6g_mb_lib.t6g(sch_1):page166_i33@pure_quanta.q_res(chips)',
 PATH='I33',
 DRAWING='@T6G_MB_LIB.T6G(SCH_1):PAGE143',
 BOM_COST='MEM',
 WATTAGE='1/16W',
 TOLERANCE='5%',
 MATERIAL='CHIP',
 PHYS_PAGE='166',
 XY='(-7950,5125)',
 ROT='0',
 VER='1',
 PACK_TYPE='0402LF',
 LOCATION='R934',
 CDS_LIB='pure_quanta',
 CDS_PART_NAME='Q_RES_0402LF-0,5%,1/16W,CHIP,CS00002JB13',
 PART_NUMBER='CS00002JB13',
 VALUE='0',
 PRIM_FILE='./archive_libs/logical/q_res/chips/chips.prt';

PART_NAME
 R935 'Q_RES_0402LF-0,5%,1/16W,CHIP,CS00002JB13':;

SECTION_NUMBER 1
 '@T6G_MB_LIB.T6G(SCH_1):PAGE143_I21@PURE_QUANTA.Q_RES(CHIPS)':
 C_PATH='@t6g_mb_lib.t6g(sch_1):page143_i21@pure_quanta.q_res(chips)',
 P_PATH='@t6g_mb_lib.t6g(sch_1):page166_i21@pure_quanta.q_res(chips)',
 PATH='I21',
 DRAWING='@T6G_MB_LIB.T6G(SCH_1):PAGE143',
 BOM_COST='MEM',
 WATTAGE='1/16W',
 TOLERANCE='5%',
 MATERIAL='CHIP',
 PHYS_PAGE='166',
 XY='(-5675,5125)',
 ROT='0',
 VER='1',
 PACK_TYPE='0402LF',
 LOCATION='R935',
 CDS_LIB='pure_quanta',
 CDS_PART_NAME='Q_RES_0402LF-0,5%,1/16W,CHIP,CS00002JB13',
 PART_NUMBER='CS00002JB13',
 VALUE='0',
 PRIM_FILE='./archive_libs/logical/q_res/chips/chips.prt';

PART_NAME
 R936 'Q_RES_0402LF-0,5%,1/16W,CHIP,CS00002JB13':;

SECTION_NUMBER 1
 '@T6G_MB_LIB.T6G(SCH_1):PAGE143_I22@PURE_QUANTA.Q_RES(CHIPS)':
 C_PATH='@t6g_mb_lib.t6g(sch_1):page143_i22@pure_quanta.q_res(chips)',
 P_PATH='@t6g_mb_lib.t6g(sch_1):page166_i22@pure_quanta.q_res(chips)',
 PATH='I22',
 DRAWING='@T6G_MB_LIB.T6G(SCH_1):PAGE143',
 BOM_COST='MEM',
 WATTAGE='1/16W',
 TOLERANCE='5%',
 MATERIAL='CHIP',
 PHYS_PAGE='166',
 XY='(-5825,3500)',
 ROT='0',
 VER='1',
 PACK_TYPE='0402LF',
 LOCATION='R936',
 CDS_LIB='pure_quanta',
 CDS_PART_NAME='Q_RES_0402LF-0,5%,1/16W,CHIP,CS00002JB13',
 PART_NUMBER='CS00002JB13',
 VALUE='0',
 PRIM_FILE='./archive_libs/logical/q_res/chips/chips.prt';

PART_NAME
 R937 'Q_RES_0402LF-0,5%,1/16W,CHIP,CS00002JB13':;

SECTION_NUMBER 1
 '@T6G_MB_LIB.T6G(SCH_1):PAGE80_I166@PURE_QUANTA.Q_RES(CHIPS)':
 C_PATH='@t6g_mb_lib.t6g(sch_1):page80_i166@pure_quanta.q_res(chips)',
 P_PATH='@t6g_mb_lib.t6g(sch_1):page81_i166@pure_quanta.q_res(chips)',
 PATH='I166',
 DRAWING='@T6G_MB_LIB.T6G(SCH_1):PAGE80',
 BOM_COST='MEM',
 WATTAGE='1/16W',
 TOLERANCE='5%',
 MATERIAL='CHIP',
 PHYS_PAGE='81',
 XY='(-3225,5025)',
 ROT='0',
 VER='1',
 PACK_TYPE='0402LF',
 LOCATION='R937',
 CDS_LIB='pure_quanta',
 CDS_PART_NAME='Q_RES_0402LF-0,5%,1/16W,CHIP,CS00002JB13',
 PART_NUMBER='CS00002JB13',
 VALUE='0',
 PRIM_FILE='./archive_libs/logical/q_res/chips/chips.prt';

PART_NAME
 R938 'Q_RES_0402LF-4.7K,5%,1/16W,CHIP,CS24702JB10':;

SECTION_NUMBER 1
 '@T6G_MB_LIB.T6G(SCH_1):PAGE28_I69@PURE_QUANTA.Q_RES(CHIPS)':
 C_PATH='@t6g_mb_lib.t6g(sch_1):page28_i69@pure_quanta.q_res(chips)',
 P_PATH='@t6g_mb_lib.t6g(sch_1):page28_i69@pure_quanta.q_res(chips)',
 PATH='I69',
 DRAWING='@T6G_MB_LIB.T6G(SCH_1):PAGE28',
 WATTAGE='1/16W',
 TOLERANCE='5%',
 MATERIAL='CHIP',
 PHYS_PAGE='28',
 XY='(-7775,8975)',
 ROT='0',
 VER='1',
 PACK_TYPE='0402LF',
 LOCATION='R938',
 CDS_LIB='pure_quanta',
 CDS_PART_NAME='Q_RES_0402LF-4.7K,5%,1/16W,CHIP,CS24702JB10',
 PART_NUMBER='CS24702JB10',
 VALUE='4.7K',
 PRIM_FILE='./archive_libs/logical/q_res/chips/chips.prt';

PART_NAME
 R939 'Q_RES_0402LF-0,5%,1/16W,CHIP,CS00002JB13':;

SECTION_NUMBER 1
 '@T6G_MB_LIB.T6G(SCH_1):PAGE28_I93@PURE_QUANTA.Q_RES(CHIPS)':
 C_PATH='@t6g_mb_lib.t6g(sch_1):page28_i93@pure_quanta.q_res(chips)',
 P_PATH='@t6g_mb_lib.t6g(sch_1):page28_i93@pure_quanta.q_res(chips)',
 PATH='I93',
 DRAWING='@T6G_MB_LIB.T6G(SCH_1):PAGE28',
 WATTAGE='1/16W',
 TOLERANCE='5%',
 MATERIAL='CHIP',
 PHYS_PAGE='28',
 XY='(-6375,9925)',
 ROT='2',
 VER='1',
 PACK_TYPE='0402LF',
 LOCATION='R939',
 CDS_LIB='pure_quanta',
 CDS_PART_NAME='Q_RES_0402LF-0,5%,1/16W,CHIP,CS00002JB13',
 PART_NUMBER='CS00002JB13',
 VALUE='0',
 PRIM_FILE='./archive_libs/logical/q_res/chips/chips.prt';

PART_NAME
 R940 'Q_RES_0402LF-0,5%,1/16W,CHIP,CS00002JB13':;

SECTION_NUMBER 1
 '@T6G_MB_LIB.T6G(SCH_1):PAGE28_I94@PURE_QUANTA.Q_RES(CHIPS)':
 C_PATH='@t6g_mb_lib.t6g(sch_1):page28_i94@pure_quanta.q_res(chips)',
 P_PATH='@t6g_mb_lib.t6g(sch_1):page28_i94@pure_quanta.q_res(chips)',
 PATH='I94',
 DRAWING='@T6G_MB_LIB.T6G(SCH_1):PAGE28',
 WATTAGE='1/16W',
 TOLERANCE='5%',
 MATERIAL='CHIP',
 PHYS_PAGE='28',
 XY='(-6375,9875)',
 ROT='2',
 VER='1',
 PACK_TYPE='0402LF',
 LOCATION='R940',
 CDS_LIB='pure_quanta',
 CDS_PART_NAME='Q_RES_0402LF-0,5%,1/16W,CHIP,CS00002JB13',
 PART_NUMBER='CS00002JB13',
 VALUE='0',
 PRIM_FILE='./archive_libs/logical/q_res/chips/chips.prt';

PART_NAME
 R941 'Q_RES_0402LF-0,5%,1/16W,EMPTY,CS00002JB13':;

SECTION_NUMBER 1
 '@T6G_MB_LIB.T6G(SCH_1):PAGE143_I34@PURE_QUANTA.Q_RES(CHIPS)':
 C_PATH='@t6g_mb_lib.t6g(sch_1):page143_i34@pure_quanta.q_res(chips)',
 P_PATH='@t6g_mb_lib.t6g(sch_1):page166_i34@pure_quanta.q_res(chips)',
 PATH='I34',
 DRAWING='@T6G_MB_LIB.T6G(SCH_1):PAGE143',
 WATTAGE='1/16W',
 TOLERANCE='5%',
 MATERIAL='EMPTY',
 PHYS_PAGE='166',
 XY='(-7950,4875)',
 ROT='0',
 VER='1',
 PACK_TYPE='0402LF',
 LOCATION='R941',
 CDS_LIB='pure_quanta',
 CDS_PART_NAME='Q_RES_0402LF-0,5%,1/16W,EMPTY,CS00002JB13',
 PART_NUMBER='CS00002JB13',
 VALUE='0',
 PRIM_FILE='./archive_libs/logical/q_res/chips/chips.prt';

PART_NAME
 R942 'Q_RES_0402LF-4.7K,5%,1/16W,CHIP,CS24702JB10':;

SECTION_NUMBER 1
 '@T6G_MB_LIB.T6G(SCH_1):PAGE34_I60@PURE_QUANTA.Q_RES(CHIPS)':
 C_PATH='@t6g_mb_lib.t6g(sch_1):page34_i60@pure_quanta.q_res(chips)',
 P_PATH='@t6g_mb_lib.t6g(sch_1):page34_i60@pure_quanta.q_res(chips)',
 PATH='I60',
 DRAWING='@T6G_MB_LIB.T6G(SCH_1):PAGE34',
 BOM_COST='OCP3.0 ',
 WATTAGE='1/16W',
 TOLERANCE='5%',
 MATERIAL='CHIP',
 PHYS_PAGE='34',
 XY='(-7075,3050)',
 ROT='2',
 VER='2',
 PACK_TYPE='0402LF',
 LOCATION='R942',
 CDS_LIB='pure_quanta',
 CDS_PART_NAME='Q_RES_0402LF-4.7K,5%,1/16W,CHIP,CS24702JB10',
 PART_NUMBER='CS24702JB10',
 VALUE='4.7K',
 PRIM_FILE='./archive_libs/logical/q_res/chips/chips.prt';

PART_NAME
 R943 'Q_RES_0402LF-4.7K,5%,1/16W,CHIP,CS24702JB10':;

SECTION_NUMBER 1
 '@T6G_MB_LIB.T6G(SCH_1):PAGE34_I53@PURE_QUANTA.Q_RES(CHIPS)':
 C_PATH='@t6g_mb_lib.t6g(sch_1):page34_i53@pure_quanta.q_res(chips)',
 P_PATH='@t6g_mb_lib.t6g(sch_1):page34_i53@pure_quanta.q_res(chips)',
 PATH='I53',
 DRAWING='@T6G_MB_LIB.T6G(SCH_1):PAGE34',
 BOM_COST='OCP3.0 ',
 WATTAGE='1/16W',
 TOLERANCE='5%',
 MATERIAL='CHIP',
 PHYS_PAGE='34',
 XY='(-5400,2975)',
 ROT='0',
 VER='2',
 PACK_TYPE='0402LF',
 LOCATION='R943',
 CDS_LIB='pure_quanta',
 CDS_PART_NAME='Q_RES_0402LF-4.7K,5%,1/16W,CHIP,CS24702JB10',
 PART_NUMBER='CS24702JB10',
 VALUE='4.7K',
 PRIM_FILE='./archive_libs/logical/q_res/chips/chips.prt';

PART_NAME
 R944 'Q_RES_0402LF-4.7K,5%,1/16W,CHIP,CS24702JB10':;

SECTION_NUMBER 1
 '@T6G_MB_LIB.T6G(SCH_1):PAGE143_I15@PURE_QUANTA.Q_RES(CHIPS)':
 C_PATH='@t6g_mb_lib.t6g(sch_1):page143_i15@pure_quanta.q_res(chips)',
 P_PATH='@t6g_mb_lib.t6g(sch_1):page166_i15@pure_quanta.q_res(chips)',
 PATH='I15',
 DRAWING='@T6G_MB_LIB.T6G(SCH_1):PAGE143',
 BOM_COST='OCP3.0 ',
 WATTAGE='1/16W',
 TOLERANCE='5%',
 MATERIAL='CHIP',
 PHYS_PAGE='166',
 XY='(-4950,5425)',
 ROT='0',
 VER='2',
 PACK_TYPE='0402LF',
 LOCATION='R944',
 CDS_LIB='pure_quanta',
 CDS_PART_NAME='Q_RES_0402LF-4.7K,5%,1/16W,CHIP,CS24702JB10',
 PART_NUMBER='CS24702JB10',
 VALUE='4.7K',
 PRIM_FILE='./archive_libs/logical/q_res/chips/chips.prt';

PART_NAME
 R945 'Q_RES_0402LF-4.7K,5%,1/16W,CHIP,CS24702JB10':;

SECTION_NUMBER 1
 '@T6G_MB_LIB.T6G(SCH_1):PAGE143_I18@PURE_QUANTA.Q_RES(CHIPS)':
 C_PATH='@t6g_mb_lib.t6g(sch_1):page143_i18@pure_quanta.q_res(chips)',
 P_PATH='@t6g_mb_lib.t6g(sch_1):page166_i18@pure_quanta.q_res(chips)',
 PATH='I18',
 DRAWING='@T6G_MB_LIB.T6G(SCH_1):PAGE143',
 BOM_COST='OCP3.0 ',
 WATTAGE='1/16W',
 TOLERANCE='5%',
 MATERIAL='CHIP',
 PHYS_PAGE='166',
 XY='(-5100,3800)',
 ROT='0',
 VER='2',
 PACK_TYPE='0402LF',
 LOCATION='R945',
 CDS_LIB='pure_quanta',
 CDS_PART_NAME='Q_RES_0402LF-4.7K,5%,1/16W,CHIP,CS24702JB10',
 PART_NUMBER='CS24702JB10',
 VALUE='4.7K',
 PRIM_FILE='./archive_libs/logical/q_res/chips/chips.prt';

PART_NAME
 R946 'Q_RES_0402LF-4.7K,5%,1/16W,CHIP,CS24702JB10':;

SECTION_NUMBER 1
 '@T6G_MB_LIB.T6G(SCH_1):PAGE143_I5@PURE_QUANTA.Q_RES(CHIPS)':
 C_PATH='@t6g_mb_lib.t6g(sch_1):page143_i5@pure_quanta.q_res(chips)',
 P_PATH='@t6g_mb_lib.t6g(sch_1):page166_i5@pure_quanta.q_res(chips)',
 PATH='I5',
 DRAWING='@T6G_MB_LIB.T6G(SCH_1):PAGE143',
 BOM_COST='OCP3.0 ',
 WATTAGE='1/16W',
 TOLERANCE='5%',
 MATERIAL='CHIP',
 PHYS_PAGE='166',
 XY='(-3950,5425)',
 ROT='0',
 VER='2',
 PACK_TYPE='0402LF',
 LOCATION='R946',
 CDS_LIB='pure_quanta',
 CDS_PART_NAME='Q_RES_0402LF-4.7K,5%,1/16W,CHIP,CS24702JB10',
 PART_NUMBER='CS24702JB10',
 VALUE='4.7K',
 PRIM_FILE='./archive_libs/logical/q_res/chips/chips.prt';

PART_NAME
 R947 'Q_RES_0402LF-4.7K,5%,1/16W,CHIP,CS24702JB10':;

SECTION_NUMBER 1
 '@T6G_MB_LIB.T6G(SCH_1):PAGE143_I11@PURE_QUANTA.Q_RES(CHIPS)':
 C_PATH='@t6g_mb_lib.t6g(sch_1):page143_i11@pure_quanta.q_res(chips)',
 P_PATH='@t6g_mb_lib.t6g(sch_1):page166_i11@pure_quanta.q_res(chips)',
 PATH='I11',
 DRAWING='@T6G_MB_LIB.T6G(SCH_1):PAGE143',
 BOM_COST='OCP3.0 ',
 WATTAGE='1/16W',
 TOLERANCE='5%',
 MATERIAL='CHIP',
 PHYS_PAGE='166',
 XY='(-4100,3800)',
 ROT='0',
 VER='2',
 PACK_TYPE='0402LF',
 LOCATION='R947',
 CDS_LIB='pure_quanta',
 CDS_PART_NAME='Q_RES_0402LF-4.7K,5%,1/16W,CHIP,CS24702JB10',
 PART_NUMBER='CS24702JB10',
 VALUE='4.7K',
 PRIM_FILE='./archive_libs/logical/q_res/chips/chips.prt';

PART_NAME
 R948 'Q_RES_0402LF-130,1%,1/16W,CHIP,CS11302FB03':;

SECTION_NUMBER 1
 '@T6G_MB_LIB.T6G(SCH_1):PAGE143_I7@PURE_QUANTA.Q_RES(CHIPS)':
 C_PATH='@t6g_mb_lib.t6g(sch_1):page143_i7@pure_quanta.q_res(chips)',
 P_PATH='@t6g_mb_lib.t6g(sch_1):page166_i7@pure_quanta.q_res(chips)',
 PATH='I7',
 DRAWING='@T6G_MB_LIB.T6G(SCH_1):PAGE143',
 WATTAGE='1/16W',
 TOLERANCE='1%',
 MATERIAL='CHIP',
 PHYS_PAGE='166',
 XY='(-2000,5075)',
 ROT='0',
 VER='1',
 PACK_TYPE='0402LF',
 LOCATION='R948',
 CDS_LIB='pure_quanta',
 CDS_PART_NAME='Q_RES_0402LF-130,1%,1/16W,CHIP,CS11302FB03',
 PART_NUMBER='CS11302FB03',
 VALUE='130',
 PRIM_FILE='./archive_libs/logical/q_res/chips/chips.prt';

PART_NAME
 R949 'Q_RES_0201LF-1K,1%,1/20W,CHIP,CS21001FE07':;

SECTION_NUMBER 1
 '@T6G_MB_LIB.T6G(SCH_1):PAGE462_I83@PURE_QUANTA.Q_RES(CHIPS)':
 C_PATH='@t6g_mb_lib.t6g(sch_1):page462_i83@pure_quanta.q_res(chips)',
 P_PATH='@t6g_mb_lib.t6g(sch_1):page353_i83@pure_quanta.q_res(chips)',
 PATH='I83',
 DRAWING='@T6G_MB_LIB.T6G(SCH_1):PAGE462',
 WATTAGE='1/20W',
 TOLERANCE='1%',
 MATERIAL='CHIP',
 PHYS_PAGE='353',
 XY='(-3025,5325)',
 ROT='0',
 VER='2',
 PACK_TYPE='0201LF',
 LOCATION='R949',
 CDS_LIB='pure_quanta',
 CDS_PART_NAME='Q_RES_0201LF-1K,1%,1/20W,CHIP,CS21001FE07',
 PART_NUMBER='CS21001FE07',
 VALUE='1K',
 PRIM_FILE='./archive_libs/logical/q_res/chips/chips.prt';

PART_NAME
 R950 'Q_RES_0402LF-249,1%,1/16W,CHIP,CS12492FB02':;

SECTION_NUMBER 1
 '@T6G_MB_LIB.T6G(SCH_1):PAGE143_I3@PURE_QUANTA.Q_RES(CHIPS)':
 C_PATH='@t6g_mb_lib.t6g(sch_1):page143_i3@pure_quanta.q_res(chips)',
 P_PATH='@t6g_mb_lib.t6g(sch_1):page166_i3@pure_quanta.q_res(chips)',
 PATH='I3',
 DRAWING='@T6G_MB_LIB.T6G(SCH_1):PAGE143',
 WATTAGE='1/16W',
 TOLERANCE='1%',
 MATERIAL='CHIP',
 PHYS_PAGE='166',
 XY='(-2250,3450)',
 ROT='0',
 VER='1',
 PACK_TYPE='0402LF',
 LOCATION='R950',
 CDS_LIB='pure_quanta',
 CDS_PART_NAME='Q_RES_0402LF-249,1%,1/16W,CHIP,CS12492FB02',
 PART_NUMBER='CS12492FB02',
 VALUE='249',
 PRIM_FILE='./archive_libs/logical/q_res/chips/chips.prt';

PART_NAME
 R951 'Q_RES_0402LF-0,5%,1/16W,EMPTY,CS00002JB13':;

SECTION_NUMBER 1
 '@T6G_MB_LIB.T6G(SCH_1):PAGE388_I5@PURE_QUANTA.Q_RES(CHIPS)':
 C_PATH='@t6g_mb_lib.t6g(sch_1):page388_i5@pure_quanta.q_res(chips)',
 P_PATH='@t6g_mb_lib.t6g(sch_1):page279_i5@pure_quanta.q_res(chips)',
 PATH='I5',
 DRAWING='@T6G_MB_LIB.T6G(SCH_1):PAGE388',
 SEC_TYPE='0402LF',
 WATTAGE='1/16W',
 TOLERANCE='5%',
 MATERIAL='EMPTY',
 PHYS_PAGE='279',
 XY='(-7700,3775)',
 ROT='0',
 VER='1',
 PACK_TYPE='0402LF',
 LOCATION='R951',
 SEC='1',
 CDS_LIB='pure_quanta',
 CDS_PART_NAME='Q_RES_0402LF-0,5%,1/16W,EMPTY,CS00002JB13',
 PART_NUMBER='CS00002JB13',
 VALUE='0',
 PRIM_FILE='./archive_libs/logical/q_res/chips/chips.prt';

PART_NAME
 R952 'Q_RES_0402LF-0,5%,1/16W,EMPTY,CS00002JB13':;

SECTION_NUMBER 1
 '@T6G_MB_LIB.T6G(SCH_1):PAGE388_I4@PURE_QUANTA.Q_RES(CHIPS)':
 C_PATH='@t6g_mb_lib.t6g(sch_1):page388_i4@pure_quanta.q_res(chips)',
 P_PATH='@t6g_mb_lib.t6g(sch_1):page279_i4@pure_quanta.q_res(chips)',
 PATH='I4',
 DRAWING='@T6G_MB_LIB.T6G(SCH_1):PAGE388',
 SEC_TYPE='0402LF',
 WATTAGE='1/16W',
 TOLERANCE='5%',
 MATERIAL='EMPTY',
 PHYS_PAGE='279',
 XY='(-7700,3575)',
 ROT='0',
 VER='1',
 PACK_TYPE='0402LF',
 LOCATION='R952',
 SEC='1',
 CDS_LIB='pure_quanta',
 CDS_PART_NAME='Q_RES_0402LF-0,5%,1/16W,EMPTY,CS00002JB13',
 PART_NUMBER='CS00002JB13',
 VALUE='0',
 PRIM_FILE='./archive_libs/logical/q_res/chips/chips.prt';

PART_NAME
 R953 'Q_RES_0201LF-0,5%,1/20W,CHIP,CS00001JE10':;

SECTION_NUMBER 1
 '@T6G_MB_LIB.T6G(SCH_1):PAGE385_I76@PURE_QUANTA.Q_RES(CHIPS)':
 C_PATH='@t6g_mb_lib.t6g(sch_1):page385_i76@pure_quanta.q_res(chips)',
 P_PATH='@t6g_mb_lib.t6g(sch_1):page276_i76@pure_quanta.q_res(chips)',
 PATH='I76',
 DRAWING='@T6G_MB_LIB.T6G(SCH_1):PAGE385',
 SEC_TYPE='0201LF',
 WATTAGE='1/20W',
 TOLERANCE='5%',
 MATERIAL='CHIP',
 PHYS_PAGE='276',
 XY='(-2575,2150)',
 ROT='0',
 VER='1',
 PACK_TYPE='0201LF',
 LOCATION='R953',
 SEC='1',
 CDS_LIB='pure_quanta',
 CDS_PART_NAME='Q_RES_0201LF-0,5%,1/20W,CHIP,CS00001JE10',
 PART_NUMBER='CS00001JE10',
 VALUE='0',
 PRIM_FILE='./archive_libs/logical/q_res/chips/chips.prt';

PART_NAME
 R954 'Q_RES_0402LF-11.5K,1%,1/16W,EMPTY,CS31152FB03':;

SECTION_NUMBER 1
 '@T6G_MB_LIB.T6G(SCH_1):PAGE146_I36@PURE_QUANTA.Q_RES(CHIPS)':
 C_PATH='@t6g_mb_lib.t6g(sch_1):page146_i36@pure_quanta.q_res(chips)',
 P_PATH='@t6g_mb_lib.t6g(sch_1):page169_i36@pure_quanta.q_res(chips)',
 PATH='I36',
 DRAWING='@T6G_MB_LIB.T6G(SCH_1):PAGE146',
 WATTAGE='1/16W',
 TOLERANCE='1%',
 MATERIAL='EMPTY',
 PHYS_PAGE='169',
 XY='(-9050,1025)',
 ROT='0',
 VER='2',
 PACK_TYPE='0402LF',
 LOCATION='R954',
 CDS_LIB='pure_quanta',
 CDS_PART_NAME='Q_RES_0402LF-11.5K,1%,1/16W,EMPTY,CS31152FB03',
 PART_NUMBER='CS31152FB03',
 VALUE='11.5K',
 PRIM_FILE='./archive_libs/logical/q_res/chips/chips.prt';

PART_NAME
 R955 'Q_RES_0402LF-0,5%,1/16W,CHIP,CS00002JB13':;

SECTION_NUMBER 1
 '@T6G_MB_LIB.T6G(SCH_1):PAGE297_I94@PURE_QUANTA.Q_RES(CHIPS)':
 C_PATH='@t6g_mb_lib.t6g(sch_1):page297_i94@pure_quanta.q_res(chips)',
 P_PATH='@t6g_mb_lib.t6g(sch_1):page145_i94@pure_quanta.q_res(chips)',
 PATH='I94',
 DRAWING='@T6G_MB_LIB.T6G(SCH_1):PAGE297',
 BOM_COST='OCP3.0 ',
 WATTAGE='1/16W',
 TOLERANCE='5%',
 MATERIAL='CHIP',
 PHYS_PAGE='145',
 XY='(-3125,400)',
 ROT='0',
 VER='1',
 PACK_TYPE='0402LF',
 LOCATION='R955',
 CDS_LIB='pure_quanta',
 CDS_PART_NAME='Q_RES_0402LF-0,5%,1/16W,CHIP,CS00002JB13',
 PART_NUMBER='CS00002JB13',
 VALUE='0',
 PRIM_FILE='./archive_libs/logical/q_res/chips/chips.prt';

PART_NAME
 R956 'Q_RES_0402LF-0,5%,1/16W,CHIP,CS00002JB13':;

SECTION_NUMBER 1
 '@T6G_MB_LIB.T6G(SCH_1):PAGE337_I81@PURE_QUANTA.Q_RES(CHIPS)':
 C_PATH='@t6g_mb_lib.t6g(sch_1):page337_i81@pure_quanta.q_res(chips)',
 P_PATH='@t6g_mb_lib.t6g(sch_1):page133_i81@pure_quanta.q_res(chips)',
 PATH='I81',
 DRAWING='@T6G_MB_LIB.T6G(SCH_1):PAGE337',
 BOM_COST='MEM',
 WATTAGE='1/16W',
 TOLERANCE='5%',
 MATERIAL='CHIP',
 PHYS_PAGE='133',
 XY='(-6975,6875)',
 ROT='0',
 VER='1',
 PACK_TYPE='0402LF',
 LOCATION='R956',
 CDS_LIB='pure_quanta',
 CDS_PART_NAME='Q_RES_0402LF-0,5%,1/16W,CHIP,CS00002JB13',
 PART_NUMBER='CS00002JB13',
 VALUE='0',
 PRIM_FILE='./archive_libs/logical/q_res/chips/chips.prt';

PART_NAME
 R957 'Q_RES_0402LF-33,5%,1/16W,CHIP,CS03302JB10':;

SECTION_NUMBER 1
 '@T6G_MB_LIB.T6G(SCH_1):PAGE80_I130@PURE_QUANTA.Q_RES(CHIPS)':
 C_PATH='@t6g_mb_lib.t6g(sch_1):page80_i130@pure_quanta.q_res(chips)',
 P_PATH='@t6g_mb_lib.t6g(sch_1):page81_i130@pure_quanta.q_res(chips)',
 PATH='I130',
 DRAWING='@T6G_MB_LIB.T6G(SCH_1):PAGE80',
 BOM_COST='MEM',
 WATTAGE='1/16W',
 TOLERANCE='5%',
 MATERIAL='CHIP',
 PHYS_PAGE='81',
 XY='(-2300,2775)',
 ROT='0',
 VER='1',
 PACK_TYPE='0402LF',
 LOCATION='R957',
 CDS_LIB='pure_quanta',
 CDS_PART_NAME='Q_RES_0402LF-33,5%,1/16W,CHIP,CS03302JB10',
 PART_NUMBER='CS03302JB10',
 VALUE='33',
 PRIM_FILE='./archive_libs/logical/q_res/chips/chips.prt';

PART_NAME
 R958 'Q_RES_0402LF-33,5%,1/16W,CHIP,CS03302JB10':;

SECTION_NUMBER 1
 '@T6G_MB_LIB.T6G(SCH_1):PAGE81_I86@PURE_QUANTA.Q_RES(CHIPS)':
 C_PATH='@t6g_mb_lib.t6g(sch_1):page81_i86@pure_quanta.q_res(chips)',
 P_PATH='@t6g_mb_lib.t6g(sch_1):page82_i86@pure_quanta.q_res(chips)',
 PATH='I86',
 DRAWING='@T6G_MB_LIB.T6G(SCH_1):PAGE81',
 BOM_COST='MEM',
 WATTAGE='1/16W',
 TOLERANCE='5%',
 MATERIAL='CHIP',
 PHYS_PAGE='82',
 XY='(-3250,3925)',
 ROT='2',
 VER='1',
 PACK_TYPE='0402LF',
 LOCATION='R958',
 CDS_LIB='pure_quanta',
 CDS_PART_NAME='Q_RES_0402LF-33,5%,1/16W,CHIP,CS03302JB10',
 PART_NUMBER='CS03302JB10',
 VALUE='33',
 PRIM_FILE='./archive_libs/logical/q_res/chips/chips.prt';

PART_NAME
 R959 'Q_RES_0402LF-33,5%,1/16W,CHIP,CS03302JB10':;

SECTION_NUMBER 1
 '@T6G_MB_LIB.T6G(SCH_1):PAGE81_I81@PURE_QUANTA.Q_RES(CHIPS)':
 C_PATH='@t6g_mb_lib.t6g(sch_1):page81_i81@pure_quanta.q_res(chips)',
 P_PATH='@t6g_mb_lib.t6g(sch_1):page82_i81@pure_quanta.q_res(chips)',
 PATH='I81',
 DRAWING='@T6G_MB_LIB.T6G(SCH_1):PAGE81',
 BOM_COST='MEM',
 WATTAGE='1/16W',
 TOLERANCE='5%',
 MATERIAL='CHIP',
 PHYS_PAGE='82',
 XY='(-3250,3475)',
 ROT='2',
 VER='1',
 PACK_TYPE='0402LF',
 LOCATION='R959',
 CDS_LIB='pure_quanta',
 CDS_PART_NAME='Q_RES_0402LF-33,5%,1/16W,CHIP,CS03302JB10',
 PART_NUMBER='CS03302JB10',
 VALUE='33',
 PRIM_FILE='./archive_libs/logical/q_res/chips/chips.prt';

PART_NAME
 R960 'Q_RES_0402LF-0,5%,1/16W,EMPTY,CS00002JB13':;

SECTION_NUMBER 1
 '@T6G_MB_LIB.T6G(SCH_1):PAGE388_I89@PURE_QUANTA.Q_RES(CHIPS)':
 C_PATH='@t6g_mb_lib.t6g(sch_1):page388_i89@pure_quanta.q_res(chips)',
 P_PATH='@t6g_mb_lib.t6g(sch_1):page279_i89@pure_quanta.q_res(chips)',
 PATH='I89',
 DRAWING='@T6G_MB_LIB.T6G(SCH_1):PAGE388',
 WATTAGE='1/16W',
 TOLERANCE='5%',
 MATERIAL='EMPTY',
 PHYS_PAGE='279',
 XY='(-8100,4100)',
 ROT='0',
 VER='2',
 PACK_TYPE='0402LF',
 LOCATION='R960',
 CDS_LIB='pure_quanta',
 CDS_PART_NAME='Q_RES_0402LF-0,5%,1/16W,EMPTY,CS00002JB13',
 PART_NUMBER='CS00002JB13',
 VALUE='0',
 PRIM_FILE='./archive_libs/logical/q_res/chips/chips.prt';

PART_NAME
 R961 'Q_RES_0603LF-0,5%,1/4W,EMPTY,CS00006J900':;

SECTION_NUMBER 1
 '@T6G_MB_LIB.T6G(SCH_1):PAGE388_I10@PURE_QUANTA.Q_RES(CHIPS)':
 C_PATH='@t6g_mb_lib.t6g(sch_1):page388_i10@pure_quanta.q_res(chips)',
 P_PATH='@t6g_mb_lib.t6g(sch_1):page279_i10@pure_quanta.q_res(chips)',
 PATH='I10',
 DRAWING='@T6G_MB_LIB.T6G(SCH_1):PAGE388',
 WATTAGE='1/4W',
 TOLERANCE='5%',
 MATERIAL='EMPTY',
 PHYS_PAGE='279',
 XY='(-4300,2775)',
 ROT='2',
 VER='2',
 PACK_TYPE='0603LF',
 LOCATION='R961',
 CDS_LIB='pure_quanta',
 CDS_PART_NAME='Q_RES_0603LF-0,5%,1/4W,EMPTY,CS00006J900',
 PART_NUMBER='CS00006J900',
 VALUE='0',
 PRIM_FILE='./archive_libs/logical/q_res/chips/chips.prt';

PART_NAME
 R962 'Q_RES_0603LF-0,5%,1/4W,CHIP,CS00006J900':;

SECTION_NUMBER 1
 '@T6G_MB_LIB.T6G(SCH_1):PAGE388_I11@PURE_QUANTA.Q_RES(CHIPS)':
 C_PATH='@t6g_mb_lib.t6g(sch_1):page388_i11@pure_quanta.q_res(chips)',
 P_PATH='@t6g_mb_lib.t6g(sch_1):page279_i11@pure_quanta.q_res(chips)',
 PATH='I11',
 DRAWING='@T6G_MB_LIB.T6G(SCH_1):PAGE388',
 WATTAGE='1/4W',
 TOLERANCE='5%',
 MATERIAL='CHIP',
 PHYS_PAGE='279',
 XY='(-3925,2500)',
 ROT='0',
 VER='1',
 PACK_TYPE='0603LF',
 LOCATION='R962',
 CDS_LIB='pure_quanta',
 CDS_PART_NAME='Q_RES_0603LF-0,5%,1/4W,CHIP,CS00006J900',
 PART_NUMBER='CS00006J900',
 VALUE='0',
 PRIM_FILE='./archive_libs/logical/q_res/chips/chips.prt';

PART_NAME
 R963 'Q_RES_0201LF-0,5%,1/20W,CHIP,CS00001JE10':;

SECTION_NUMBER 1
 '@T6G_MB_LIB.T6G(SCH_1):PAGE385_I77@PURE_QUANTA.Q_RES(CHIPS)':
 C_PATH='@t6g_mb_lib.t6g(sch_1):page385_i77@pure_quanta.q_res(chips)',
 P_PATH='@t6g_mb_lib.t6g(sch_1):page276_i77@pure_quanta.q_res(chips)',
 PATH='I77',
 DRAWING='@T6G_MB_LIB.T6G(SCH_1):PAGE385',
 WATTAGE='1/20W',
 TOLERANCE='5%',
 MATERIAL='CHIP',
 PHYS_PAGE='276',
 XY='(-2575,2050)',
 ROT='0',
 VER='1',
 PACK_TYPE='0201LF',
 LOCATION='R963',
 CDS_LIB='pure_quanta',
 CDS_PART_NAME='Q_RES_0201LF-0,5%,1/20W,CHIP,CS00001JE10',
 PART_NUMBER='CS00001JE10',
 VALUE='0',
 PRIM_FILE='./archive_libs/logical/q_res/chips/chips.prt';

PART_NAME
 R964 'Q_RES_0201LF-1K,1%,1/20W,CHIP,CS21001FE07':;

SECTION_NUMBER 1
 '@T6G_MB_LIB.T6G(SCH_1):PAGE385_I88@PURE_QUANTA.Q_RES(CHIPS)':
 C_PATH='@t6g_mb_lib.t6g(sch_1):page385_i88@pure_quanta.q_res(chips)',
 P_PATH='@t6g_mb_lib.t6g(sch_1):page276_i88@pure_quanta.q_res(chips)',
 PATH='I88',
 DRAWING='@T6G_MB_LIB.T6G(SCH_1):PAGE385',
 WATTAGE='1/20W',
 TOLERANCE='1%',
 MATERIAL='CHIP',
 PHYS_PAGE='276',
 XY='(-3475,5950)',
 ROT='0',
 VER='2',
 PACK_TYPE='0201LF',
 LOCATION='R964',
 CDS_LIB='pure_quanta',
 CDS_PART_NAME='Q_RES_0201LF-1K,1%,1/20W,CHIP,CS21001FE07',
 PART_NUMBER='CS21001FE07',
 VALUE='1K',
 PRIM_FILE='./archive_libs/logical/q_res/chips/chips.prt';

PART_NAME
 R965 'Q_RES_0201LF-1K,1%,1/20W,EMPTY,CS21001FE07':;

SECTION_NUMBER 1
 '@T6G_MB_LIB.T6G(SCH_1):PAGE385_I86@PURE_QUANTA.Q_RES(CHIPS)':
 C_PATH='@t6g_mb_lib.t6g(sch_1):page385_i86@pure_quanta.q_res(chips)',
 P_PATH='@t6g_mb_lib.t6g(sch_1):page276_i86@pure_quanta.q_res(chips)',
 PATH='I86',
 DRAWING='@T6G_MB_LIB.T6G(SCH_1):PAGE385',
 WATTAGE='1/20W',
 TOLERANCE='1%',
 MATERIAL='EMPTY',
 PHYS_PAGE='276',
 XY='(-3475,5175)',
 ROT='0',
 VER='2',
 PACK_TYPE='0201LF',
 LOCATION='R965',
 CDS_LIB='pure_quanta',
 CDS_PART_NAME='Q_RES_0201LF-1K,1%,1/20W,EMPTY,CS21001FE07',
 PART_NUMBER='CS21001FE07',
 VALUE='1K',
 PRIM_FILE='./archive_libs/logical/q_res/chips/chips.prt';

PART_NAME
 R966 'Q_RES_0201LF-1K,1%,1/20W,EMPTY,CS21001FE07':;

SECTION_NUMBER 1
 '@T6G_MB_LIB.T6G(SCH_1):PAGE385_I89@PURE_QUANTA.Q_RES(CHIPS)':
 C_PATH='@t6g_mb_lib.t6g(sch_1):page385_i89@pure_quanta.q_res(chips)',
 P_PATH='@t6g_mb_lib.t6g(sch_1):page276_i89@pure_quanta.q_res(chips)',
 PATH='I89',
 DRAWING='@T6G_MB_LIB.T6G(SCH_1):PAGE385',
 WATTAGE='1/20W',
 TOLERANCE='1%',
 MATERIAL='EMPTY',
 PHYS_PAGE='276',
 XY='(-3175,5950)',
 ROT='0',
 VER='2',
 PACK_TYPE='0201LF',
 LOCATION='R966',
 CDS_LIB='pure_quanta',
 CDS_PART_NAME='Q_RES_0201LF-1K,1%,1/20W,EMPTY,CS21001FE07',
 PART_NUMBER='CS21001FE07',
 VALUE='1K',
 PRIM_FILE='./archive_libs/logical/q_res/chips/chips.prt';

PART_NAME
 R967 'Q_RES_0201LF-20K,1%,1/20W,CHIP,CS32001FE00':;

SECTION_NUMBER 1
 '@T6G_MB_LIB.T6G(SCH_1):PAGE385_I87@PURE_QUANTA.Q_RES(CHIPS)':
 C_PATH='@t6g_mb_lib.t6g(sch_1):page385_i87@pure_quanta.q_res(chips)',
 P_PATH='@t6g_mb_lib.t6g(sch_1):page276_i87@pure_quanta.q_res(chips)',
 PATH='I87',
 DRAWING='@T6G_MB_LIB.T6G(SCH_1):PAGE385',
 WATTAGE='1/20W',
 TOLERANCE='1%',
 MATERIAL='CHIP',
 PHYS_PAGE='276',
 XY='(-3175,5175)',
 ROT='0',
 VER='2',
 PACK_TYPE='0201LF',
 LOCATION='R967',
 CDS_LIB='pure_quanta',
 CDS_PART_NAME='Q_RES_0201LF-20K,1%,1/20W,CHIP,CS32001FE00',
 PART_NUMBER='CS32001FE00',
 VALUE='20K',
 PRIM_FILE='./archive_libs/logical/q_res/chips/chips.prt';

PART_NAME
 R968 'Q_RES_0201LF-1K,1%,1/20W,EMPTY,CS21001FE07':;

SECTION_NUMBER 1
 '@T6G_MB_LIB.T6G(SCH_1):PAGE385_I91@PURE_QUANTA.Q_RES(CHIPS)':
 C_PATH='@t6g_mb_lib.t6g(sch_1):page385_i91@pure_quanta.q_res(chips)',
 P_PATH='@t6g_mb_lib.t6g(sch_1):page276_i91@pure_quanta.q_res(chips)',
 PATH='I91',
 DRAWING='@T6G_MB_LIB.T6G(SCH_1):PAGE385',
 WATTAGE='1/20W',
 TOLERANCE='1%',
 MATERIAL='EMPTY',
 PHYS_PAGE='276',
 XY='(-2825,5925)',
 ROT='0',
 VER='2',
 PACK_TYPE='0201LF',
 LOCATION='R968',
 CDS_LIB='pure_quanta',
 CDS_PART_NAME='Q_RES_0201LF-1K,1%,1/20W,EMPTY,CS21001FE07',
 PART_NUMBER='CS21001FE07',
 VALUE='1K',
 PRIM_FILE='./archive_libs/logical/q_res/chips/chips.prt';

PART_NAME
 R969 'Q_RES_0201LF-1K,1%,1/20W,CHIP,CS21001FE07':;

SECTION_NUMBER 1
 '@T6G_MB_LIB.T6G(SCH_1):PAGE385_I90@PURE_QUANTA.Q_RES(CHIPS)':
 C_PATH='@t6g_mb_lib.t6g(sch_1):page385_i90@pure_quanta.q_res(chips)',
 P_PATH='@t6g_mb_lib.t6g(sch_1):page276_i90@pure_quanta.q_res(chips)',
 PATH='I90',
 DRAWING='@T6G_MB_LIB.T6G(SCH_1):PAGE385',
 WATTAGE='1/20W',
 TOLERANCE='1%',
 MATERIAL='CHIP',
 PHYS_PAGE='276',
 XY='(-2825,5175)',
 ROT='0',
 VER='2',
 PACK_TYPE='0201LF',
 LOCATION='R969',
 CDS_LIB='pure_quanta',
 CDS_PART_NAME='Q_RES_0201LF-1K,1%,1/20W,CHIP,CS21001FE07',
 PART_NUMBER='CS21001FE07',
 VALUE='1K',
 PRIM_FILE='./archive_libs/logical/q_res/chips/chips.prt';

PART_NAME
 R970 'Q_RES_0201LF-10K,1%,1/20W,CHIP,CS31001FE17':;

SECTION_NUMBER 1
 '@T6G_MB_LIB.T6G(SCH_1):PAGE385_I97@PURE_QUANTA.Q_RES(CHIPS)':
 C_PATH='@t6g_mb_lib.t6g(sch_1):page385_i97@pure_quanta.q_res(chips)',
 P_PATH='@t6g_mb_lib.t6g(sch_1):page276_i97@pure_quanta.q_res(chips)',
 PATH='I97',
 DRAWING='@T6G_MB_LIB.T6G(SCH_1):PAGE385',
 WATTAGE='1/20W',
 TOLERANCE='1%',
 MATERIAL='CHIP',
 PHYS_PAGE='276',
 XY='(-1300,5175)',
 ROT='0',
 VER='2',
 PACK_TYPE='0201LF',
 LOCATION='R970',
 CDS_LIB='pure_quanta',
 CDS_PART_NAME='Q_RES_0201LF-10K,1%,1/20W,CHIP,CS31001FE17',
 PART_NUMBER='CS31001FE17',
 VALUE='10K',
 PRIM_FILE='./archive_libs/logical/q_res/chips/chips.prt';

PART_NAME
 R971 'Q_RES_0201LF-10K,1%,1/20W,CHIP,CS31001FE17':;

SECTION_NUMBER 1
 '@T6G_MB_LIB.T6G(SCH_1):PAGE385_I96@PURE_QUANTA.Q_RES(CHIPS)':
 C_PATH='@t6g_mb_lib.t6g(sch_1):page385_i96@pure_quanta.q_res(chips)',
 P_PATH='@t6g_mb_lib.t6g(sch_1):page276_i96@pure_quanta.q_res(chips)',
 PATH='I96',
 DRAWING='@T6G_MB_LIB.T6G(SCH_1):PAGE385',
 WATTAGE='1/20W',
 TOLERANCE='1%',
 MATERIAL='CHIP',
 PHYS_PAGE='276',
 XY='(-1475,5175)',
 ROT='2',
 VER='2',
 PACK_TYPE='0201LF',
 LOCATION='R971',
 CDS_LIB='pure_quanta',
 CDS_PART_NAME='Q_RES_0201LF-10K,1%,1/20W,CHIP,CS31001FE17',
 PART_NUMBER='CS31001FE17',
 VALUE='10K',
 PRIM_FILE='./archive_libs/logical/q_res/chips/chips.prt';

PART_NAME
 R972 'Q_RES_0201LF-4.7K,5%,1/20W,EMPTY,CS24701JE04':;

SECTION_NUMBER 1
 '@T6G_MB_LIB.T6G(SCH_1):PAGE385_I25@PURE_QUANTA.Q_RES(CHIPS)':
 C_PATH='@t6g_mb_lib.t6g(sch_1):page385_i25@pure_quanta.q_res(chips)',
 P_PATH='@t6g_mb_lib.t6g(sch_1):page276_i25@pure_quanta.q_res(chips)',
 PATH='I25',
 DRAWING='@T6G_MB_LIB.T6G(SCH_1):PAGE385',
 WATTAGE='1/20W',
 TOLERANCE='5%',
 MATERIAL='EMPTY',
 PHYS_PAGE='276',
 XY='(-8975,4075)',
 ROT='0',
 VER='2',
 PACK_TYPE='0201LF',
 LOCATION='R972',
 CDS_LIB='pure_quanta',
 CDS_PART_NAME='Q_RES_0201LF-4.7K,5%,1/20W,EMPTY,CS24701JE04',
 PART_NUMBER='CS24701JE04',
 VALUE='4.7K',
 PRIM_FILE='./archive_libs/logical/q_res/chips/chips.prt';

PART_NAME
 R973 'Q_RES_0201LF-200,1%,1/20W,CHIP,CS12001FE12':;

SECTION_NUMBER 1
 '@T6G_MB_LIB.T6G(SCH_1):PAGE385_I121@PURE_QUANTA.Q_RES(CHIPS)':
 C_PATH='@t6g_mb_lib.t6g(sch_1):page385_i121@pure_quanta.q_res(chips)',
 P_PATH='@t6g_mb_lib.t6g(sch_1):page276_i121@pure_quanta.q_res(chips)',
 PATH='I121',
 DRAWING='@T6G_MB_LIB.T6G(SCH_1):PAGE385',
 WATTAGE='1/20W',
 TOLERANCE='1%',
 MATERIAL='CHIP',
 PHYS_PAGE='276',
 XY='(-8975,3400)',
 ROT='0',
 VER='2',
 PACK_TYPE='0201LF',
 LOCATION='R973',
 CDS_LIB='pure_quanta',
 CDS_PART_NAME='Q_RES_0201LF-200,1%,1/20W,CHIP,CS12001FE12',
 PART_NUMBER='CS12001FE12',
 VALUE='200',
 PRIM_FILE='./archive_libs/logical/q_res/chips/chips.prt';

PART_NAME
 R974 'Q_RES_0201LF-4.7K,5%,1/20W,EMPTY,CS24701JE04':;

SECTION_NUMBER 1
 '@T6G_MB_LIB.T6G(SCH_1):PAGE385_I98@PURE_QUANTA.Q_RES(CHIPS)':
 C_PATH='@t6g_mb_lib.t6g(sch_1):page385_i98@pure_quanta.q_res(chips)',
 P_PATH='@t6g_mb_lib.t6g(sch_1):page276_i98@pure_quanta.q_res(chips)',
 PATH='I98',
 DRAWING='@T6G_MB_LIB.T6G(SCH_1):PAGE385',
 WATTAGE='1/20W',
 TOLERANCE='5%',
 MATERIAL='EMPTY',
 PHYS_PAGE='276',
 XY='(-1475,6000)',
 ROT='2',
 VER='2',
 PACK_TYPE='0201LF',
 LOCATION='R974',
 CDS_LIB='pure_quanta',
 CDS_PART_NAME='Q_RES_0201LF-4.7K,5%,1/20W,EMPTY,CS24701JE04',
 PART_NUMBER='CS24701JE04',
 VALUE='4.7K',
 PRIM_FILE='./archive_libs/logical/q_res/chips/chips.prt';

PART_NAME
 R975 'Q_RES_0201LF-4.7K,5%,1/20W,EMPTY,CS24701JE04':;

SECTION_NUMBER 1
 '@T6G_MB_LIB.T6G(SCH_1):PAGE385_I63@PURE_QUANTA.Q_RES(CHIPS)':
 C_PATH='@t6g_mb_lib.t6g(sch_1):page385_i63@pure_quanta.q_res(chips)',
 P_PATH='@t6g_mb_lib.t6g(sch_1):page276_i63@pure_quanta.q_res(chips)',
 PATH='I63',
 DRAWING='@T6G_MB_LIB.T6G(SCH_1):PAGE385',
 WATTAGE='1/20W',
 TOLERANCE='5%',
 MATERIAL='EMPTY',
 PHYS_PAGE='276',
 XY='(-7425,5950)',
 ROT='0',
 VER='2',
 PACK_TYPE='0201LF',
 LOCATION='R975',
 CDS_LIB='pure_quanta',
 CDS_PART_NAME='Q_RES_0201LF-4.7K,5%,1/20W,EMPTY,CS24701JE04',
 PART_NUMBER='CS24701JE04',
 VALUE='4.7K',
 PRIM_FILE='./archive_libs/logical/q_res/chips/chips.prt';

PART_NAME
 R976 'Q_RES_0201LF-0,5%,1/20W,CHIP,CS00001JE10':;

SECTION_NUMBER 1
 '@T6G_MB_LIB.T6G(SCH_1):PAGE385_I50@PURE_QUANTA.Q_RES(CHIPS)':
 C_PATH='@t6g_mb_lib.t6g(sch_1):page385_i50@pure_quanta.q_res(chips)',
 P_PATH='@t6g_mb_lib.t6g(sch_1):page276_i50@pure_quanta.q_res(chips)',
 PATH='I50',
 DRAWING='@T6G_MB_LIB.T6G(SCH_1):PAGE385',
 WATTAGE='1/20W',
 TOLERANCE='5%',
 MATERIAL='CHIP',
 PHYS_PAGE='276',
 XY='(-6350,2850)',
 ROT='0',
 VER='1',
 PACK_TYPE='0201LF',
 LOCATION='R976',
 CDS_LIB='pure_quanta',
 CDS_PART_NAME='Q_RES_0201LF-0,5%,1/20W,CHIP,CS00001JE10',
 PART_NUMBER='CS00001JE10',
 VALUE='0',
 PRIM_FILE='./archive_libs/logical/q_res/chips/chips.prt';

PART_NAME
 R977 'Q_RES_0201LF-0,5%,1/20W,CHIP,CS00001JE10':;

SECTION_NUMBER 1
 '@T6G_MB_LIB.T6G(SCH_1):PAGE385_I49@PURE_QUANTA.Q_RES(CHIPS)':
 C_PATH='@t6g_mb_lib.t6g(sch_1):page385_i49@pure_quanta.q_res(chips)',
 P_PATH='@t6g_mb_lib.t6g(sch_1):page276_i49@pure_quanta.q_res(chips)',
 PATH='I49',
 DRAWING='@T6G_MB_LIB.T6G(SCH_1):PAGE385',
 WATTAGE='1/20W',
 TOLERANCE='5%',
 MATERIAL='CHIP',
 PHYS_PAGE='276',
 XY='(-6350,2750)',
 ROT='0',
 VER='1',
 PACK_TYPE='0201LF',
 LOCATION='R977',
 CDS_LIB='pure_quanta',
 CDS_PART_NAME='Q_RES_0201LF-0,5%,1/20W,CHIP,CS00001JE10',
 PART_NUMBER='CS00001JE10',
 VALUE='0',
 PRIM_FILE='./archive_libs/logical/q_res/chips/chips.prt';

PART_NAME
 R978 'Q_RES_0201LF-4.7K,5%,1/20W,EMPTY,CS24701JE04':;

SECTION_NUMBER 1
 '@T6G_MB_LIB.T6G(SCH_1):PAGE385_I30@PURE_QUANTA.Q_RES(CHIPS)':
 C_PATH='@t6g_mb_lib.t6g(sch_1):page385_i30@pure_quanta.q_res(chips)',
 P_PATH='@t6g_mb_lib.t6g(sch_1):page276_i30@pure_quanta.q_res(chips)',
 PATH='I30',
 DRAWING='@T6G_MB_LIB.T6G(SCH_1):PAGE385',
 WATTAGE='1/20W',
 TOLERANCE='5%',
 MATERIAL='EMPTY',
 PHYS_PAGE='276',
 XY='(-8950,5950)',
 ROT='0',
 VER='2',
 PACK_TYPE='0201LF',
 LOCATION='R978',
 CDS_LIB='pure_quanta',
 CDS_PART_NAME='Q_RES_0201LF-4.7K,5%,1/20W,EMPTY,CS24701JE04',
 PART_NUMBER='CS24701JE04',
 VALUE='4.7K',
 PRIM_FILE='./archive_libs/logical/q_res/chips/chips.prt';

PART_NAME
 R979 'Q_RES_0201LF-10K,1%,1/20W,CHIP,CS31001FE17':;

SECTION_NUMBER 1
 '@T6G_MB_LIB.T6G(SCH_1):PAGE385_I27@PURE_QUANTA.Q_RES(CHIPS)':
 C_PATH='@t6g_mb_lib.t6g(sch_1):page385_i27@pure_quanta.q_res(chips)',
 P_PATH='@t6g_mb_lib.t6g(sch_1):page276_i27@pure_quanta.q_res(chips)',
 PATH='I27',
 DRAWING='@T6G_MB_LIB.T6G(SCH_1):PAGE385',
 WATTAGE='1/20W',
 TOLERANCE='1%',
 MATERIAL='CHIP',
 PHYS_PAGE='276',
 XY='(-8950,5000)',
 ROT='0',
 VER='2',
 PACK_TYPE='0201LF',
 LOCATION='R979',
 CDS_LIB='pure_quanta',
 CDS_PART_NAME='Q_RES_0201LF-10K,1%,1/20W,CHIP,CS31001FE17',
 PART_NUMBER='CS31001FE17',
 VALUE='10K',
 PRIM_FILE='./archive_libs/logical/q_res/chips/chips.prt';

PART_NAME
 R980 'Q_RES_0201LF-10K,1%,1/20W,CHIP,CS31001FE17':;

SECTION_NUMBER 1
 '@T6G_MB_LIB.T6G(SCH_1):PAGE385_I28@PURE_QUANTA.Q_RES(CHIPS)':
 C_PATH='@t6g_mb_lib.t6g(sch_1):page385_i28@pure_quanta.q_res(chips)',
 P_PATH='@t6g_mb_lib.t6g(sch_1):page276_i28@pure_quanta.q_res(chips)',
 PATH='I28',
 DRAWING='@T6G_MB_LIB.T6G(SCH_1):PAGE385',
 WATTAGE='1/20W',
 TOLERANCE='1%',
 MATERIAL='CHIP',
 PHYS_PAGE='276',
 XY='(-8650,5000)',
 ROT='0',
 VER='2',
 PACK_TYPE='0201LF',
 LOCATION='R980',
 CDS_LIB='pure_quanta',
 CDS_PART_NAME='Q_RES_0201LF-10K,1%,1/20W,CHIP,CS31001FE17',
 PART_NUMBER='CS31001FE17',
 VALUE='10K',
 PRIM_FILE='./archive_libs/logical/q_res/chips/chips.prt';

PART_NAME
 R981 'Q_RES_0201LF-4.7K,5%,1/20W,EMPTY,CS24701JE04':;

SECTION_NUMBER 1
 '@T6G_MB_LIB.T6G(SCH_1):PAGE385_I31@PURE_QUANTA.Q_RES(CHIPS)':
 C_PATH='@t6g_mb_lib.t6g(sch_1):page385_i31@pure_quanta.q_res(chips)',
 P_PATH='@t6g_mb_lib.t6g(sch_1):page276_i31@pure_quanta.q_res(chips)',
 PATH='I31',
 DRAWING='@T6G_MB_LIB.T6G(SCH_1):PAGE385',
 WATTAGE='1/20W',
 TOLERANCE='5%',
 MATERIAL='EMPTY',
 PHYS_PAGE='276',
 XY='(-8325,5950)',
 ROT='0',
 VER='2',
 PACK_TYPE='0201LF',
 LOCATION='R981',
 CDS_LIB='pure_quanta',
 CDS_PART_NAME='Q_RES_0201LF-4.7K,5%,1/20W,EMPTY,CS24701JE04',
 PART_NUMBER='CS24701JE04',
 VALUE='4.7K',
 PRIM_FILE='./archive_libs/logical/q_res/chips/chips.prt';

PART_NAME
 R982 'Q_RES_0201LF-4.7K,5%,1/20W,CHIP,CS24701JE04':;

SECTION_NUMBER 1
 '@T6G_MB_LIB.T6G(SCH_1):PAGE385_I29@PURE_QUANTA.Q_RES(CHIPS)':
 C_PATH='@t6g_mb_lib.t6g(sch_1):page385_i29@pure_quanta.q_res(chips)',
 P_PATH='@t6g_mb_lib.t6g(sch_1):page276_i29@pure_quanta.q_res(chips)',
 PATH='I29',
 DRAWING='@T6G_MB_LIB.T6G(SCH_1):PAGE385',
 WATTAGE='1/20W',
 TOLERANCE='5%',
 MATERIAL='CHIP',
 PHYS_PAGE='276',
 XY='(-8325,5000)',
 ROT='0',
 VER='2',
 PACK_TYPE='0201LF',
 LOCATION='R982',
 CDS_LIB='pure_quanta',
 CDS_PART_NAME='Q_RES_0201LF-4.7K,5%,1/20W,CHIP,CS24701JE04',
 PART_NUMBER='CS24701JE04',
 VALUE='4.7K',
 PRIM_FILE='./archive_libs/logical/q_res/chips/chips.prt';

PART_NAME
 R983 'Q_RES_0201LF-4.7K,5%,1/20W,EMPTY,CS24701JE04':;

SECTION_NUMBER 1
 '@T6G_MB_LIB.T6G(SCH_1):PAGE385_I61@PURE_QUANTA.Q_RES(CHIPS)':
 C_PATH='@t6g_mb_lib.t6g(sch_1):page385_i61@pure_quanta.q_res(chips)',
 P_PATH='@t6g_mb_lib.t6g(sch_1):page276_i61@pure_quanta.q_res(chips)',
 PATH='I61',
 DRAWING='@T6G_MB_LIB.T6G(SCH_1):PAGE385',
 WATTAGE='1/20W',
 TOLERANCE='5%',
 MATERIAL='EMPTY',
 PHYS_PAGE='276',
 XY='(-8025,5900)',
 ROT='0',
 VER='2',
 PACK_TYPE='0201LF',
 LOCATION='R983',
 CDS_LIB='pure_quanta',
 CDS_PART_NAME='Q_RES_0201LF-4.7K,5%,1/20W,EMPTY,CS24701JE04',
 PART_NUMBER='CS24701JE04',
 VALUE='4.7K',
 PRIM_FILE='./archive_libs/logical/q_res/chips/chips.prt';

PART_NAME
 R984 'Q_RES_0201LF-4.7K,5%,1/20W,CHIP,CS24701JE04':;

SECTION_NUMBER 1
 '@T6G_MB_LIB.T6G(SCH_1):PAGE385_I57@PURE_QUANTA.Q_RES(CHIPS)':
 C_PATH='@t6g_mb_lib.t6g(sch_1):page385_i57@pure_quanta.q_res(chips)',
 P_PATH='@t6g_mb_lib.t6g(sch_1):page276_i57@pure_quanta.q_res(chips)',
 PATH='I57',
 DRAWING='@T6G_MB_LIB.T6G(SCH_1):PAGE385',
 WATTAGE='1/20W',
 TOLERANCE='5%',
 MATERIAL='CHIP',
 PHYS_PAGE='276',
 XY='(-8025,4975)',
 ROT='0',
 VER='2',
 PACK_TYPE='0201LF',
 LOCATION='R984',
 CDS_LIB='pure_quanta',
 CDS_PART_NAME='Q_RES_0201LF-4.7K,5%,1/20W,CHIP,CS24701JE04',
 PART_NUMBER='CS24701JE04',
 VALUE='4.7K',
 PRIM_FILE='./archive_libs/logical/q_res/chips/chips.prt';

PART_NAME
 R985 'Q_RES_0201LF-4.7K,5%,1/20W,EMPTY,CS24701JE04':;

SECTION_NUMBER 1
 '@T6G_MB_LIB.T6G(SCH_1):PAGE385_I62@PURE_QUANTA.Q_RES(CHIPS)':
 C_PATH='@t6g_mb_lib.t6g(sch_1):page385_i62@pure_quanta.q_res(chips)',
 P_PATH='@t6g_mb_lib.t6g(sch_1):page276_i62@pure_quanta.q_res(chips)',
 PATH='I62',
 DRAWING='@T6G_MB_LIB.T6G(SCH_1):PAGE385',
 WATTAGE='1/20W',
 TOLERANCE='5%',
 MATERIAL='EMPTY',
 PHYS_PAGE='276',
 XY='(-7725,5925)',
 ROT='0',
 VER='2',
 PACK_TYPE='0201LF',
 LOCATION='R985',
 CDS_LIB='pure_quanta',
 CDS_PART_NAME='Q_RES_0201LF-4.7K,5%,1/20W,EMPTY,CS24701JE04',
 PART_NUMBER='CS24701JE04',
 VALUE='4.7K',
 PRIM_FILE='./archive_libs/logical/q_res/chips/chips.prt';

PART_NAME
 R986 'Q_RES_0402LF-0,5%,1/16W,EMPTY,CS00002JB13':;

SECTION_NUMBER 1
 '@T6G_MB_LIB.T6G(SCH_1):PAGE136_I135@PURE_QUANTA.Q_RES(CHIPS)':
 C_PATH='@t6g_mb_lib.t6g(sch_1):page136_i135@pure_quanta.q_res(chips)',
 P_PATH='@t6g_mb_lib.t6g(sch_1):page159_i135@pure_quanta.q_res(chips)',
 PATH='I135',
 DRAWING='@T6G_MB_LIB.T6G(SCH_1):PAGE136',
 WATTAGE='1/16W',
 TOLERANCE='5%',
 MATERIAL='EMPTY',
 PHYS_PAGE='159',
 XY='(-6050,3925)',
 ROT='0',
 VER='1',
 PACK_TYPE='0402LF',
 LOCATION='R986',
 CDS_LIB='pure_quanta',
 CDS_PART_NAME='Q_RES_0402LF-0,5%,1/16W,EMPTY,CS00002JB13',
 PART_NUMBER='CS00002JB13',
 VALUE='0',
 PRIM_FILE='./archive_libs/logical/q_res/chips/chips.prt';

PART_NAME
 R987 'Q_RES_0402LF-0,5%,1/16W,EMPTY,CS00002JB13':;

SECTION_NUMBER 1
 '@T6G_MB_LIB.T6G(SCH_1):PAGE136_I136@PURE_QUANTA.Q_RES(CHIPS)':
 C_PATH='@t6g_mb_lib.t6g(sch_1):page136_i136@pure_quanta.q_res(chips)',
 P_PATH='@t6g_mb_lib.t6g(sch_1):page159_i136@pure_quanta.q_res(chips)',
 PATH='I136',
 DRAWING='@T6G_MB_LIB.T6G(SCH_1):PAGE136',
 WATTAGE='1/16W',
 TOLERANCE='5%',
 MATERIAL='EMPTY',
 PHYS_PAGE='159',
 XY='(-6050,3875)',
 ROT='0',
 VER='1',
 PACK_TYPE='0402LF',
 LOCATION='R987',
 CDS_LIB='pure_quanta',
 CDS_PART_NAME='Q_RES_0402LF-0,5%,1/16W,EMPTY,CS00002JB13',
 PART_NUMBER='CS00002JB13',
 VALUE='0',
 PRIM_FILE='./archive_libs/logical/q_res/chips/chips.prt';

PART_NAME
 R988 'Q_RES_0402LF-0,5%,1/16W,EMPTY,CS00002JB13':;

SECTION_NUMBER 1
 '@T6G_MB_LIB.T6G(SCH_1):PAGE136_I138@PURE_QUANTA.Q_RES(CHIPS)':
 C_PATH='@t6g_mb_lib.t6g(sch_1):page136_i138@pure_quanta.q_res(chips)',
 P_PATH='@t6g_mb_lib.t6g(sch_1):page159_i138@pure_quanta.q_res(chips)',
 PATH='I138',
 DRAWING='@T6G_MB_LIB.T6G(SCH_1):PAGE136',
 WATTAGE='1/16W',
 TOLERANCE='5%',
 MATERIAL='EMPTY',
 PHYS_PAGE='159',
 XY='(-6000,2400)',
 ROT='0',
 VER='1',
 PACK_TYPE='0402LF',
 LOCATION='R988',
 CDS_LIB='pure_quanta',
 CDS_PART_NAME='Q_RES_0402LF-0,5%,1/16W,EMPTY,CS00002JB13',
 PART_NUMBER='CS00002JB13',
 VALUE='0',
 PRIM_FILE='./archive_libs/logical/q_res/chips/chips.prt';

PART_NAME
 R989 'Q_RES_0402LF-0,5%,1/16W,EMPTY,CS00002JB13':;

SECTION_NUMBER 1
 '@T6G_MB_LIB.T6G(SCH_1):PAGE136_I137@PURE_QUANTA.Q_RES(CHIPS)':
 C_PATH='@t6g_mb_lib.t6g(sch_1):page136_i137@pure_quanta.q_res(chips)',
 P_PATH='@t6g_mb_lib.t6g(sch_1):page159_i137@pure_quanta.q_res(chips)',
 PATH='I137',
 DRAWING='@T6G_MB_LIB.T6G(SCH_1):PAGE136',
 WATTAGE='1/16W',
 TOLERANCE='5%',
 MATERIAL='EMPTY',
 PHYS_PAGE='159',
 XY='(-6000,2350)',
 ROT='0',
 VER='1',
 PACK_TYPE='0402LF',
 LOCATION='R989',
 CDS_LIB='pure_quanta',
 CDS_PART_NAME='Q_RES_0402LF-0,5%,1/16W,EMPTY,CS00002JB13',
 PART_NUMBER='CS00002JB13',
 VALUE='0',
 PRIM_FILE='./archive_libs/logical/q_res/chips/chips.prt';

PART_NAME
 R990 'Q_RES_0402LF-0,5%,1/16W,EMPTY,CS00002JB13':;

SECTION_NUMBER 1
 '@T6G_MB_LIB.T6G(SCH_1):PAGE136_I142@PURE_QUANTA.Q_RES(CHIPS)':
 C_PATH='@t6g_mb_lib.t6g(sch_1):page136_i142@pure_quanta.q_res(chips)',
 P_PATH='@t6g_mb_lib.t6g(sch_1):page159_i142@pure_quanta.q_res(chips)',
 PATH='I142',
 DRAWING='@T6G_MB_LIB.T6G(SCH_1):PAGE136',
 WATTAGE='1/16W',
 TOLERANCE='5%',
 MATERIAL='EMPTY',
 PHYS_PAGE='159',
 XY='(-5950,950)',
 ROT='0',
 VER='1',
 PACK_TYPE='0402LF',
 LOCATION='R990',
 CDS_LIB='pure_quanta',
 CDS_PART_NAME='Q_RES_0402LF-0,5%,1/16W,EMPTY,CS00002JB13',
 PART_NUMBER='CS00002JB13',
 VALUE='0',
 PRIM_FILE='./archive_libs/logical/q_res/chips/chips.prt';

PART_NAME
 R991 'Q_RES_0402LF-0,5%,1/16W,EMPTY,CS00002JB13':;

SECTION_NUMBER 1
 '@T6G_MB_LIB.T6G(SCH_1):PAGE136_I141@PURE_QUANTA.Q_RES(CHIPS)':
 C_PATH='@t6g_mb_lib.t6g(sch_1):page136_i141@pure_quanta.q_res(chips)',
 P_PATH='@t6g_mb_lib.t6g(sch_1):page159_i141@pure_quanta.q_res(chips)',
 PATH='I141',
 DRAWING='@T6G_MB_LIB.T6G(SCH_1):PAGE136',
 WATTAGE='1/16W',
 TOLERANCE='5%',
 MATERIAL='EMPTY',
 PHYS_PAGE='159',
 XY='(-5950,900)',
 ROT='0',
 VER='1',
 PACK_TYPE='0402LF',
 LOCATION='R991',
 CDS_LIB='pure_quanta',
 CDS_PART_NAME='Q_RES_0402LF-0,5%,1/16W,EMPTY,CS00002JB13',
 PART_NUMBER='CS00002JB13',
 VALUE='0',
 PRIM_FILE='./archive_libs/logical/q_res/chips/chips.prt';

PART_NAME
 R992 'Q_RES_0402LF-33,5%,1/16W,CHIP,CS03302JB10':;

SECTION_NUMBER 1
 '@T6G_MB_LIB.T6G(SCH_1):PAGE79_I17@PURE_QUANTA.Q_RES(CHIPS)':
 C_PATH='@t6g_mb_lib.t6g(sch_1):page79_i17@pure_quanta.q_res(chips)',
 P_PATH='@t6g_mb_lib.t6g(sch_1):page80_i17@pure_quanta.q_res(chips)',
 PATH='I17',
 DRAWING='@T6G_MB_LIB.T6G(SCH_1):PAGE79',
 BOM_COST='MEM',
 WATTAGE='1/16W',
 TOLERANCE='5%',
 MATERIAL='CHIP',
 PHYS_PAGE='80',
 XY='(-6850,2750)',
 ROT='2',
 VER='1',
 PACK_TYPE='0402LF',
 LOCATION='R992',
 CDS_LIB='pure_quanta',
 CDS_PART_NAME='Q_RES_0402LF-33,5%,1/16W,CHIP,CS03302JB10',
 PART_NUMBER='CS03302JB10',
 VALUE='33',
 PRIM_FILE='./archive_libs/logical/q_res/chips/chips.prt';

PART_NAME
 R993 'Q_RES_0402LF-1K,1%,1/16W,CHIP,CS21002FB06':;

SECTION_NUMBER 1
 '@T6G_MB_LIB.T6G(SCH_1):PAGE82_I53@PURE_QUANTA.Q_RES(CHIPS)':
 C_PATH='@t6g_mb_lib.t6g(sch_1):page82_i53@pure_quanta.q_res(chips)',
 P_PATH='@t6g_mb_lib.t6g(sch_1):page83_i53@pure_quanta.q_res(chips)',
 PATH='I53',
 DRAWING='@T6G_MB_LIB.T6G(SCH_1):PAGE82',
 WATTAGE='1/16W',
 TOLERANCE='1%',
 MATERIAL='CHIP',
 PHYS_PAGE='83',
 XY='(-7050,4325)',
 ROT='0',
 VER='1',
 PACK_TYPE='0402LF',
 LOCATION='R993',
 CDS_LIB='pure_quanta',
 CDS_PART_NAME='Q_RES_0402LF-1K,1%,1/16W,CHIP,CS21002FB06',
 PART_NUMBER='CS21002FB06',
 VALUE='1K',
 PRIM_FILE='./archive_libs/logical/q_res/chips/chips.prt';

PART_NAME
 R994 'Q_RES_0402LF-10K,1%,1/16W,CHIP,CS31002FB08':;

SECTION_NUMBER 1
 '@T6G_MB_LIB.T6G(SCH_1):PAGE132_I7@PURE_QUANTA.Q_RES(CHIPS)':
 C_PATH='@t6g_mb_lib.t6g(sch_1):page132_i7@pure_quanta.q_res(chips)',
 P_PATH='@t6g_mb_lib.t6g(sch_1):page155_i7@pure_quanta.q_res(chips)',
 PATH='I7',
 DRAWING='@T6G_MB_LIB.T6G(SCH_1):PAGE132',
 WATTAGE='1/16W',
 TOLERANCE='1%',
 MATERIAL='CHIP',
 PHYS_PAGE='155',
 XY='(-4250,4675)',
 ROT='2',
 VER='2',
 PACK_TYPE='0402LF',
 LOCATION='R994',
 CDS_LIB='pure_quanta',
 CDS_PART_NAME='Q_RES_0402LF-10K,1%,1/16W,CHIP,CS31002FB08',
 PART_NUMBER='CS31002FB08',
 VALUE='10K',
 PRIM_FILE='./archive_libs/logical/q_res/chips/chips.prt';

PART_NAME
 R995 'Q_RES_0201LF-4.7K,5%,1/20W,CHIP,CS24701JE04':;

SECTION_NUMBER 1
 '@T6G_MB_LIB.T6G(SCH_1):PAGE385_I58@PURE_QUANTA.Q_RES(CHIPS)':
 C_PATH='@t6g_mb_lib.t6g(sch_1):page385_i58@pure_quanta.q_res(chips)',
 P_PATH='@t6g_mb_lib.t6g(sch_1):page276_i58@pure_quanta.q_res(chips)',
 PATH='I58',
 DRAWING='@T6G_MB_LIB.T6G(SCH_1):PAGE385',
 WATTAGE='1/20W',
 TOLERANCE='5%',
 MATERIAL='CHIP',
 PHYS_PAGE='276',
 XY='(-7725,4975)',
 ROT='0',
 VER='2',
 PACK_TYPE='0201LF',
 LOCATION='R995',
 CDS_LIB='pure_quanta',
 CDS_PART_NAME='Q_RES_0201LF-4.7K,5%,1/20W,CHIP,CS24701JE04',
 PART_NUMBER='CS24701JE04',
 VALUE='4.7K',
 PRIM_FILE='./archive_libs/logical/q_res/chips/chips.prt';

PART_NAME
 R996 'Q_RES_0402LF-4.7K,5%,1/16W,CHIP,CS24702JB10':;

SECTION_NUMBER 1
 '@T6G_MB_LIB.T6G(SCH_1):PAGE83_I22@PURE_QUANTA.Q_RES(CHIPS)':
 C_PATH='@t6g_mb_lib.t6g(sch_1):page83_i22@pure_quanta.q_res(chips)',
 P_PATH='@t6g_mb_lib.t6g(sch_1):page84_i22@pure_quanta.q_res(chips)',
 PATH='I22',
 DRAWING='@T6G_MB_LIB.T6G(SCH_1):PAGE83',
 BOM_COST='OCP3.0 ',
 WATTAGE='1/16W',
 TOLERANCE='5%',
 MATERIAL='CHIP',
 PHYS_PAGE='84',
 XY='(-2975,5850)',
 ROT='2',
 VER='2',
 PACK_TYPE='0402LF',
 LOCATION='R996',
 CDS_LIB='pure_quanta',
 CDS_PART_NAME='Q_RES_0402LF-4.7K,5%,1/16W,CHIP,CS24702JB10',
 PART_NUMBER='CS24702JB10',
 VALUE='4.7K',
 PRIM_FILE='./archive_libs/logical/q_res/chips/chips.prt';

PART_NAME
 R997 'Q_RES_0201LF-4.7K,5%,1/20W,CHIP,CS24701JE04':;

SECTION_NUMBER 1
 '@T6G_MB_LIB.T6G(SCH_1):PAGE385_I60@PURE_QUANTA.Q_RES(CHIPS)':
 C_PATH='@t6g_mb_lib.t6g(sch_1):page385_i60@pure_quanta.q_res(chips)',
 P_PATH='@t6g_mb_lib.t6g(sch_1):page276_i60@pure_quanta.q_res(chips)',
 PATH='I60',
 DRAWING='@T6G_MB_LIB.T6G(SCH_1):PAGE385',
 WATTAGE='1/20W',
 TOLERANCE='5%',
 MATERIAL='CHIP',
 PHYS_PAGE='276',
 XY='(-7425,4950)',
 ROT='0',
 VER='2',
 PACK_TYPE='0201LF',
 LOCATION='R997',
 CDS_LIB='pure_quanta',
 CDS_PART_NAME='Q_RES_0201LF-4.7K,5%,1/20W,CHIP,CS24701JE04',
 PART_NUMBER='CS24701JE04',
 VALUE='4.7K',
 PRIM_FILE='./archive_libs/logical/q_res/chips/chips.prt';

PART_NAME
 R998 'Q_RES_0201LF-4.7K,5%,1/20W,CHIP,CS24701JE04':;

SECTION_NUMBER 1
 '@T6G_MB_LIB.T6G(SCH_1):PAGE385_I72@PURE_QUANTA.Q_RES(CHIPS)':
 C_PATH='@t6g_mb_lib.t6g(sch_1):page385_i72@pure_quanta.q_res(chips)',
 P_PATH='@t6g_mb_lib.t6g(sch_1):page276_i72@pure_quanta.q_res(chips)',
 PATH='I72',
 DRAWING='@T6G_MB_LIB.T6G(SCH_1):PAGE385',
 WATTAGE='1/20W',
 TOLERANCE='5%',
 MATERIAL='CHIP',
 PHYS_PAGE='276',
 XY='(-5025,6025)',
 ROT='0',
 VER='2',
 PACK_TYPE='0201LF',
 LOCATION='R998',
 CDS_LIB='pure_quanta',
 CDS_PART_NAME='Q_RES_0201LF-4.7K,5%,1/20W,CHIP,CS24701JE04',
 PART_NUMBER='CS24701JE04',
 VALUE='4.7K',
 PRIM_FILE='./archive_libs/logical/q_res/chips/chips.prt';

PART_NAME
 R999 'Q_RES_0402LF-4.7K,5%,1/16W,CHIP,CS24702JB10':;

SECTION_NUMBER 1
 '@T6G_MB_LIB.T6G(SCH_1):PAGE297_I95@PURE_QUANTA.Q_RES(CHIPS)':
 C_PATH='@t6g_mb_lib.t6g(sch_1):page297_i95@pure_quanta.q_res(chips)',
 P_PATH='@t6g_mb_lib.t6g(sch_1):page145_i95@pure_quanta.q_res(chips)',
 PATH='I95',
 DRAWING='@T6G_MB_LIB.T6G(SCH_1):PAGE297',
 BOM_COST='OCP3.0 ',
 WATTAGE='1/16W',
 TOLERANCE='5%',
 MATERIAL='CHIP',
 PHYS_PAGE='145',
 XY='(-2875,125)',
 ROT='0',
 VER='2',
 PACK_TYPE='0402LF',
 LOCATION='R999',
 CDS_LIB='pure_quanta',
 CDS_PART_NAME='Q_RES_0402LF-4.7K,5%,1/16W,CHIP,CS24702JB10',
 PART_NUMBER='CS24702JB10',
 VALUE='4.7K',
 PRIM_FILE='./archive_libs/logical/q_res/chips/chips.prt';

PART_NAME
 R1000 'Q_RES_0402LF-4.7K,5%,1/16W,CHIP,CS24702JB10':;

SECTION_NUMBER 1
 '@T6G_MB_LIB.T6G(SCH_1):PAGE297_I102@PURE_QUANTA.Q_RES(CHIPS)':
 C_PATH='@t6g_mb_lib.t6g(sch_1):page297_i102@pure_quanta.q_res(chips)',
 P_PATH='@t6g_mb_lib.t6g(sch_1):page145_i102@pure_quanta.q_res(chips)',
 PATH='I102',
 DRAWING='@T6G_MB_LIB.T6G(SCH_1):PAGE297',
 BOM_COST='OCP3.0 ',
 WATTAGE='1/16W',
 TOLERANCE='5%',
 MATERIAL='CHIP',
 PHYS_PAGE='145',
 XY='(-700,125)',
 ROT='0',
 VER='2',
 PACK_TYPE='0402LF',
 LOCATION='R1000',
 CDS_LIB='pure_quanta',
 CDS_PART_NAME='Q_RES_0402LF-4.7K,5%,1/16W,CHIP,CS24702JB10',
 PART_NUMBER='CS24702JB10',
 VALUE='4.7K',
 PRIM_FILE='./archive_libs/logical/q_res/chips/chips.prt';

PART_NAME
 R1001 'Q_RES_0201LF-4.7K,5%,1/20W,EMPTY,CS24701JE04':;

SECTION_NUMBER 1
 '@T6G_MB_LIB.T6G(SCH_1):PAGE385_I71@PURE_QUANTA.Q_RES(CHIPS)':
 C_PATH='@t6g_mb_lib.t6g(sch_1):page385_i71@pure_quanta.q_res(chips)',
 P_PATH='@t6g_mb_lib.t6g(sch_1):page276_i71@pure_quanta.q_res(chips)',
 PATH='I71',
 DRAWING='@T6G_MB_LIB.T6G(SCH_1):PAGE385',
 WATTAGE='1/20W',
 TOLERANCE='5%',
 MATERIAL='EMPTY',
 PHYS_PAGE='276',
 XY='(-5025,5500)',
 ROT='0',
 VER='2',
 PACK_TYPE='0201LF',
 LOCATION='R1001',
 CDS_LIB='pure_quanta',
 CDS_PART_NAME='Q_RES_0201LF-4.7K,5%,1/20W,EMPTY,CS24701JE04',
 PART_NUMBER='CS24701JE04',
 VALUE='4.7K',
 PRIM_FILE='./archive_libs/logical/q_res/chips/chips.prt';

PART_NAME
 R1002 'Q_RES_0402LF-0,5%,1/16W,EMPTY,CS00002JB13':;

SECTION_NUMBER 1
 '@T6G_MB_LIB.T6G(SCH_1):PAGE411_I4@PURE_QUANTA.Q_RES(CHIPS)':
 C_PATH='@t6g_mb_lib.t6g(sch_1):page411_i4@pure_quanta.q_res(chips)',
 P_PATH='@t6g_mb_lib.t6g(sch_1):page290_i4@pure_quanta.q_res(chips)',
 PATH='I4',
 DRAWING='@T6G_MB_LIB.T6G(SCH_1):PAGE411',
 SEC_TYPE='0402LF',
 WATTAGE='1/16W',
 TOLERANCE='5%',
 MATERIAL='EMPTY',
 PHYS_PAGE='290',
 XY='(-7875,3475)',
 ROT='0',
 VER='1',
 PACK_TYPE='0402LF',
 LOCATION='R1002',
 SEC='1',
 CDS_LIB='pure_quanta',
 CDS_PART_NAME='Q_RES_0402LF-0,5%,1/16W,EMPTY,CS00002JB13',
 PART_NUMBER='CS00002JB13',
 VALUE='0',
 PRIM_FILE='./archive_libs/logical/q_res/chips/chips.prt';

PART_NAME
 R1003 'Q_RES_0402LF-0,5%,1/16W,EMPTY,CS00002JB13':;

SECTION_NUMBER 1
 '@T6G_MB_LIB.T6G(SCH_1):PAGE411_I2@PURE_QUANTA.Q_RES(CHIPS)':
 C_PATH='@t6g_mb_lib.t6g(sch_1):page411_i2@pure_quanta.q_res(chips)',
 P_PATH='@t6g_mb_lib.t6g(sch_1):page290_i2@pure_quanta.q_res(chips)',
 PATH='I2',
 DRAWING='@T6G_MB_LIB.T6G(SCH_1):PAGE411',
 SEC_TYPE='0402LF',
 WATTAGE='1/16W',
 TOLERANCE='5%',
 MATERIAL='EMPTY',
 PHYS_PAGE='290',
 XY='(-7875,3275)',
 ROT='0',
 VER='1',
 PACK_TYPE='0402LF',
 LOCATION='R1003',
 SEC='1',
 CDS_LIB='pure_quanta',
 CDS_PART_NAME='Q_RES_0402LF-0,5%,1/16W,EMPTY,CS00002JB13',
 PART_NUMBER='CS00002JB13',
 VALUE='0',
 PRIM_FILE='./archive_libs/logical/q_res/chips/chips.prt';

PART_NAME
 R1004 'Q_RES_0201LF-0,5%,1/20W,CHIP,CS00001JE10':;

SECTION_NUMBER 1
 '@T6G_MB_LIB.T6G(SCH_1):PAGE408_I56@PURE_QUANTA.Q_RES(CHIPS)':
 C_PATH='@t6g_mb_lib.t6g(sch_1):page408_i56@pure_quanta.q_res(chips)',
 P_PATH='@t6g_mb_lib.t6g(sch_1):page287_i56@pure_quanta.q_res(chips)',
 PATH='I56',
 DRAWING='@T6G_MB_LIB.T6G(SCH_1):PAGE408',
 SEC_TYPE='0201LF',
 WATTAGE='1/20W',
 TOLERANCE='5%',
 MATERIAL='CHIP',
 PHYS_PAGE='287',
 XY='(-2575,2200)',
 ROT='0',
 VER='1',
 PACK_TYPE='0201LF',
 LOCATION='R1004',
 SEC='1',
 CDS_LIB='pure_quanta',
 CDS_PART_NAME='Q_RES_0201LF-0,5%,1/20W,CHIP,CS00001JE10',
 PART_NUMBER='CS00001JE10',
 VALUE='0',
 PRIM_FILE='./archive_libs/logical/q_res/chips/chips.prt';

PART_NAME
 R1005 'Q_RES_0402LF-33,5%,1/16W,CHIP,CS03302JB10':;

SECTION_NUMBER 1
 '@T6G_MB_LIB.T6G(SCH_1):PAGE132_I4@PURE_QUANTA.Q_RES(CHIPS)':
 C_PATH='@t6g_mb_lib.t6g(sch_1):page132_i4@pure_quanta.q_res(chips)',
 P_PATH='@t6g_mb_lib.t6g(sch_1):page155_i4@pure_quanta.q_res(chips)',
 PATH='I4',
 DRAWING='@T6G_MB_LIB.T6G(SCH_1):PAGE132',
 WATTAGE='1/16W',
 TOLERANCE='5%',
 MATERIAL='CHIP',
 PHYS_PAGE='155',
 XY='(-5925,2975)',
 ROT='0',
 VER='1',
 PACK_TYPE='0402LF',
 LOCATION='R1005',
 CDS_LIB='pure_quanta',
 CDS_PART_NAME='Q_RES_0402LF-33,5%,1/16W,CHIP,CS03302JB10',
 PART_NUMBER='CS03302JB10',
 VALUE='33',
 PRIM_FILE='./archive_libs/logical/q_res/chips/chips.prt';

PART_NAME
 R1006 'Q_RES_0201LF-4.7K,5%,1/20W,EMPTY,CS24701JE04':;

SECTION_NUMBER 1
 '@T6G_MB_LIB.T6G(SCH_1):PAGE408_I50@PURE_QUANTA.Q_RES(CHIPS)':
 C_PATH='@t6g_mb_lib.t6g(sch_1):page408_i50@pure_quanta.q_res(chips)',
 P_PATH='@t6g_mb_lib.t6g(sch_1):page287_i50@pure_quanta.q_res(chips)',
 PATH='I50',
 DRAWING='@T6G_MB_LIB.T6G(SCH_1):PAGE408',
 WATTAGE='1/20W',
 TOLERANCE='5%',
 MATERIAL='EMPTY',
 PHYS_PAGE='287',
 XY='(-5025,5550)',
 ROT='0',
 VER='2',
 PACK_TYPE='0201LF',
 LOCATION='R1006',
 CDS_LIB='pure_quanta',
 CDS_PART_NAME='Q_RES_0201LF-4.7K,5%,1/20W,EMPTY,CS24701JE04',
 PART_NUMBER='CS24701JE04',
 VALUE='4.7K',
 PRIM_FILE='./archive_libs/logical/q_res/chips/chips.prt';

PART_NAME
 R1007 'Q_RES_0402LF-2K,1%,1/16W,EMPTY,CS22002FB07':;

SECTION_NUMBER 1
 '@T6G_MB_LIB.T6G(SCH_1):PAGE146_I11@PURE_QUANTA.Q_RES(CHIPS)':
 C_PATH='@t6g_mb_lib.t6g(sch_1):page146_i11@pure_quanta.q_res(chips)',
 P_PATH='@t6g_mb_lib.t6g(sch_1):page169_i11@pure_quanta.q_res(chips)',
 PATH='I11',
 DRAWING='@T6G_MB_LIB.T6G(SCH_1):PAGE146',
 WATTAGE='1/16W',
 TOLERANCE='1%',
 MATERIAL='EMPTY',
 PHYS_PAGE='169',
 XY='(-8025,5075)',
 ROT='0',
 VER='2',
 PACK_TYPE='0402LF',
 LOCATION='R1007',
 CDS_LIB='pure_quanta',
 CDS_PART_NAME='Q_RES_0402LF-2K,1%,1/16W,EMPTY,CS22002FB07',
 PART_NUMBER='CS22002FB07',
 VALUE='2K',
 PRIM_FILE='./archive_libs/logical/q_res/chips/chips.prt';

PART_NAME
 R1008 'Q_RES_0402LF-0,5%,1/16W,EMPTY,CS00002JB13':;

SECTION_NUMBER 1
 '@T6G_MB_LIB.T6G(SCH_1):PAGE411_I89@PURE_QUANTA.Q_RES(CHIPS)':
 C_PATH='@t6g_mb_lib.t6g(sch_1):page411_i89@pure_quanta.q_res(chips)',
 P_PATH='@t6g_mb_lib.t6g(sch_1):page290_i89@pure_quanta.q_res(chips)',
 PATH='I89',
 DRAWING='@T6G_MB_LIB.T6G(SCH_1):PAGE411',
 WATTAGE='1/16W',
 TOLERANCE='5%',
 MATERIAL='EMPTY',
 PHYS_PAGE='290',
 XY='(-8275,3800)',
 ROT='0',
 VER='2',
 PACK_TYPE='0402LF',
 LOCATION='R1008',
 CDS_LIB='pure_quanta',
 CDS_PART_NAME='Q_RES_0402LF-0,5%,1/16W,EMPTY,CS00002JB13',
 PART_NUMBER='CS00002JB13',
 VALUE='0',
 PRIM_FILE='./archive_libs/logical/q_res/chips/chips.prt';

PART_NAME
 R1009 'Q_RES_0402LF-10K,1%,1/16W,CHIP,CS31002FB08':;

SECTION_NUMBER 1
 '@T6G_MB_LIB.T6G(SCH_1):PAGE132_I10@PURE_QUANTA.Q_RES(CHIPS)':
 C_PATH='@t6g_mb_lib.t6g(sch_1):page132_i10@pure_quanta.q_res(chips)',
 P_PATH='@t6g_mb_lib.t6g(sch_1):page155_i10@pure_quanta.q_res(chips)',
 PATH='I10',
 DRAWING='@T6G_MB_LIB.T6G(SCH_1):PAGE132',
 WATTAGE='1/16W',
 TOLERANCE='1%',
 MATERIAL='CHIP',
 PHYS_PAGE='155',
 XY='(-3075,4125)',
 ROT='2',
 VER='1',
 PACK_TYPE='0402LF',
 LOCATION='R1009',
 CDS_LIB='pure_quanta',
 CDS_PART_NAME='Q_RES_0402LF-10K,1%,1/16W,CHIP,CS31002FB08',
 PART_NUMBER='CS31002FB08',
 VALUE='10K',
 PRIM_FILE='./archive_libs/logical/q_res/chips/chips.prt';

PART_NAME
 R1010 'Q_RES_0603LF-0,5%,1/4W,EMPTY,CS00006J900':;

SECTION_NUMBER 1
 '@T6G_MB_LIB.T6G(SCH_1):PAGE411_I10@PURE_QUANTA.Q_RES(CHIPS)':
 C_PATH='@t6g_mb_lib.t6g(sch_1):page411_i10@pure_quanta.q_res(chips)',
 P_PATH='@t6g_mb_lib.t6g(sch_1):page290_i10@pure_quanta.q_res(chips)',
 PATH='I10',
 DRAWING='@T6G_MB_LIB.T6G(SCH_1):PAGE411',
 WATTAGE='1/4W',
 TOLERANCE='5%',
 MATERIAL='EMPTY',
 PHYS_PAGE='290',
 XY='(-4475,2475)',
 ROT='2',
 VER='2',
 PACK_TYPE='0603LF',
 LOCATION='R1010',
 CDS_LIB='pure_quanta',
 CDS_PART_NAME='Q_RES_0603LF-0,5%,1/4W,EMPTY,CS00006J900',
 PART_NUMBER='CS00006J900',
 VALUE='0',
 PRIM_FILE='./archive_libs/logical/q_res/chips/chips.prt';

PART_NAME
 R1011 'Q_RES_0603LF-0,5%,1/4W,CHIP,CS00006J900':;

SECTION_NUMBER 1
 '@T6G_MB_LIB.T6G(SCH_1):PAGE411_I36@PURE_QUANTA.Q_RES(CHIPS)':
 C_PATH='@t6g_mb_lib.t6g(sch_1):page411_i36@pure_quanta.q_res(chips)',
 P_PATH='@t6g_mb_lib.t6g(sch_1):page290_i36@pure_quanta.q_res(chips)',
 PATH='I36',
 DRAWING='@T6G_MB_LIB.T6G(SCH_1):PAGE411',
 WATTAGE='1/4W',
 TOLERANCE='5%',
 MATERIAL='CHIP',
 PHYS_PAGE='290',
 XY='(-4100,2200)',
 ROT='0',
 VER='1',
 PACK_TYPE='0603LF',
 LOCATION='R1011',
 CDS_LIB='pure_quanta',
 CDS_PART_NAME='Q_RES_0603LF-0,5%,1/4W,CHIP,CS00006J900',
 PART_NUMBER='CS00006J900',
 VALUE='0',
 PRIM_FILE='./archive_libs/logical/q_res/chips/chips.prt';

PART_NAME
 R1012 'Q_RES_0201LF-0,5%,1/20W,CHIP,CS00001JE10':;

SECTION_NUMBER 1
 '@T6G_MB_LIB.T6G(SCH_1):PAGE408_I55@PURE_QUANTA.Q_RES(CHIPS)':
 C_PATH='@t6g_mb_lib.t6g(sch_1):page408_i55@pure_quanta.q_res(chips)',
 P_PATH='@t6g_mb_lib.t6g(sch_1):page287_i55@pure_quanta.q_res(chips)',
 PATH='I55',
 DRAWING='@T6G_MB_LIB.T6G(SCH_1):PAGE408',
 WATTAGE='1/20W',
 TOLERANCE='5%',
 MATERIAL='CHIP',
 PHYS_PAGE='287',
 XY='(-2575,2100)',
 ROT='0',
 VER='1',
 PACK_TYPE='0201LF',
 LOCATION='R1012',
 CDS_LIB='pure_quanta',
 CDS_PART_NAME='Q_RES_0201LF-0,5%,1/20W,CHIP,CS00001JE10',
 PART_NUMBER='CS00001JE10',
 VALUE='0',
 PRIM_FILE='./archive_libs/logical/q_res/chips/chips.prt';

PART_NAME
 R1013 'Q_RES_0201LF-1K,1%,1/20W,CHIP,CS21001FE07':;

SECTION_NUMBER 1
 '@T6G_MB_LIB.T6G(SCH_1):PAGE408_I66@PURE_QUANTA.Q_RES(CHIPS)':
 C_PATH='@t6g_mb_lib.t6g(sch_1):page408_i66@pure_quanta.q_res(chips)',
 P_PATH='@t6g_mb_lib.t6g(sch_1):page287_i66@pure_quanta.q_res(chips)',
 PATH='I66',
 DRAWING='@T6G_MB_LIB.T6G(SCH_1):PAGE408',
 WATTAGE='1/20W',
 TOLERANCE='1%',
 MATERIAL='CHIP',
 PHYS_PAGE='287',
 XY='(-3475,6000)',
 ROT='0',
 VER='2',
 PACK_TYPE='0201LF',
 LOCATION='R1013',
 CDS_LIB='pure_quanta',
 CDS_PART_NAME='Q_RES_0201LF-1K,1%,1/20W,CHIP,CS21001FE07',
 PART_NUMBER='CS21001FE07',
 VALUE='1K',
 PRIM_FILE='./archive_libs/logical/q_res/chips/chips.prt';

PART_NAME
 R1014 'Q_RES_0201LF-1K,1%,1/20W,EMPTY,CS21001FE07':;

SECTION_NUMBER 1
 '@T6G_MB_LIB.T6G(SCH_1):PAGE408_I64@PURE_QUANTA.Q_RES(CHIPS)':
 C_PATH='@t6g_mb_lib.t6g(sch_1):page408_i64@pure_quanta.q_res(chips)',
 P_PATH='@t6g_mb_lib.t6g(sch_1):page287_i64@pure_quanta.q_res(chips)',
 PATH='I64',
 DRAWING='@T6G_MB_LIB.T6G(SCH_1):PAGE408',
 WATTAGE='1/20W',
 TOLERANCE='1%',
 MATERIAL='EMPTY',
 PHYS_PAGE='287',
 XY='(-3475,5225)',
 ROT='0',
 VER='2',
 PACK_TYPE='0201LF',
 LOCATION='R1014',
 CDS_LIB='pure_quanta',
 CDS_PART_NAME='Q_RES_0201LF-1K,1%,1/20W,EMPTY,CS21001FE07',
 PART_NUMBER='CS21001FE07',
 VALUE='1K',
 PRIM_FILE='./archive_libs/logical/q_res/chips/chips.prt';

PART_NAME
 R1015 'Q_RES_0201LF-1K,1%,1/20W,EMPTY,CS21001FE07':;

SECTION_NUMBER 1
 '@T6G_MB_LIB.T6G(SCH_1):PAGE408_I67@PURE_QUANTA.Q_RES(CHIPS)':
 C_PATH='@t6g_mb_lib.t6g(sch_1):page408_i67@pure_quanta.q_res(chips)',
 P_PATH='@t6g_mb_lib.t6g(sch_1):page287_i67@pure_quanta.q_res(chips)',
 PATH='I67',
 DRAWING='@T6G_MB_LIB.T6G(SCH_1):PAGE408',
 WATTAGE='1/20W',
 TOLERANCE='1%',
 MATERIAL='EMPTY',
 PHYS_PAGE='287',
 XY='(-3175,6000)',
 ROT='0',
 VER='2',
 PACK_TYPE='0201LF',
 LOCATION='R1015',
 CDS_LIB='pure_quanta',
 CDS_PART_NAME='Q_RES_0201LF-1K,1%,1/20W,EMPTY,CS21001FE07',
 PART_NUMBER='CS21001FE07',
 VALUE='1K',
 PRIM_FILE='./archive_libs/logical/q_res/chips/chips.prt';

PART_NAME
 R1016 'Q_RES_0201LF-20K,1%,1/20W,CHIP,CS32001FE00':;

SECTION_NUMBER 1
 '@T6G_MB_LIB.T6G(SCH_1):PAGE408_I65@PURE_QUANTA.Q_RES(CHIPS)':
 C_PATH='@t6g_mb_lib.t6g(sch_1):page408_i65@pure_quanta.q_res(chips)',
 P_PATH='@t6g_mb_lib.t6g(sch_1):page287_i65@pure_quanta.q_res(chips)',
 PATH='I65',
 DRAWING='@T6G_MB_LIB.T6G(SCH_1):PAGE408',
 WATTAGE='1/20W',
 TOLERANCE='1%',
 MATERIAL='CHIP',
 PHYS_PAGE='287',
 XY='(-3175,5225)',
 ROT='0',
 VER='2',
 PACK_TYPE='0201LF',
 LOCATION='R1016',
 CDS_LIB='pure_quanta',
 CDS_PART_NAME='Q_RES_0201LF-20K,1%,1/20W,CHIP,CS32001FE00',
 PART_NUMBER='CS32001FE00',
 VALUE='20K',
 PRIM_FILE='./archive_libs/logical/q_res/chips/chips.prt';

PART_NAME
 R1017 'Q_RES_0201LF-1K,1%,1/20W,EMPTY,CS21001FE07':;

SECTION_NUMBER 1
 '@T6G_MB_LIB.T6G(SCH_1):PAGE408_I69@PURE_QUANTA.Q_RES(CHIPS)':
 C_PATH='@t6g_mb_lib.t6g(sch_1):page408_i69@pure_quanta.q_res(chips)',
 P_PATH='@t6g_mb_lib.t6g(sch_1):page287_i69@pure_quanta.q_res(chips)',
 PATH='I69',
 DRAWING='@T6G_MB_LIB.T6G(SCH_1):PAGE408',
 WATTAGE='1/20W',
 TOLERANCE='1%',
 MATERIAL='EMPTY',
 PHYS_PAGE='287',
 XY='(-2825,5975)',
 ROT='0',
 VER='2',
 PACK_TYPE='0201LF',
 LOCATION='R1017',
 CDS_LIB='pure_quanta',
 CDS_PART_NAME='Q_RES_0201LF-1K,1%,1/20W,EMPTY,CS21001FE07',
 PART_NUMBER='CS21001FE07',
 VALUE='1K',
 PRIM_FILE='./archive_libs/logical/q_res/chips/chips.prt';

PART_NAME
 R1018 'Q_RES_0201LF-1K,1%,1/20W,CHIP,CS21001FE07':;

SECTION_NUMBER 1
 '@T6G_MB_LIB.T6G(SCH_1):PAGE408_I68@PURE_QUANTA.Q_RES(CHIPS)':
 C_PATH='@t6g_mb_lib.t6g(sch_1):page408_i68@pure_quanta.q_res(chips)',
 P_PATH='@t6g_mb_lib.t6g(sch_1):page287_i68@pure_quanta.q_res(chips)',
 PATH='I68',
 DRAWING='@T6G_MB_LIB.T6G(SCH_1):PAGE408',
 WATTAGE='1/20W',
 TOLERANCE='1%',
 MATERIAL='CHIP',
 PHYS_PAGE='287',
 XY='(-2825,5225)',
 ROT='0',
 VER='2',
 PACK_TYPE='0201LF',
 LOCATION='R1018',
 CDS_LIB='pure_quanta',
 CDS_PART_NAME='Q_RES_0201LF-1K,1%,1/20W,CHIP,CS21001FE07',
 PART_NUMBER='CS21001FE07',
 VALUE='1K',
 PRIM_FILE='./archive_libs/logical/q_res/chips/chips.prt';

PART_NAME
 R1019 'Q_RES_0201LF-10K,1%,1/20W,CHIP,CS31001FE17':;

SECTION_NUMBER 1
 '@T6G_MB_LIB.T6G(SCH_1):PAGE408_I73@PURE_QUANTA.Q_RES(CHIPS)':
 C_PATH='@t6g_mb_lib.t6g(sch_1):page408_i73@pure_quanta.q_res(chips)',
 P_PATH='@t6g_mb_lib.t6g(sch_1):page287_i73@pure_quanta.q_res(chips)',
 PATH='I73',
 DRAWING='@T6G_MB_LIB.T6G(SCH_1):PAGE408',
 WATTAGE='1/20W',
 TOLERANCE='1%',
 MATERIAL='CHIP',
 PHYS_PAGE='287',
 XY='(-1300,5225)',
 ROT='0',
 VER='2',
 PACK_TYPE='0201LF',
 LOCATION='R1019',
 CDS_LIB='pure_quanta',
 CDS_PART_NAME='Q_RES_0201LF-10K,1%,1/20W,CHIP,CS31001FE17',
 PART_NUMBER='CS31001FE17',
 VALUE='10K',
 PRIM_FILE='./archive_libs/logical/q_res/chips/chips.prt';

PART_NAME
 R1020 'Q_RES_0201LF-10K,1%,1/20W,CHIP,CS31001FE17':;

SECTION_NUMBER 1
 '@T6G_MB_LIB.T6G(SCH_1):PAGE408_I74@PURE_QUANTA.Q_RES(CHIPS)':
 C_PATH='@t6g_mb_lib.t6g(sch_1):page408_i74@pure_quanta.q_res(chips)',
 P_PATH='@t6g_mb_lib.t6g(sch_1):page287_i74@pure_quanta.q_res(chips)',
 PATH='I74',
 DRAWING='@T6G_MB_LIB.T6G(SCH_1):PAGE408',
 WATTAGE='1/20W',
 TOLERANCE='1%',
 MATERIAL='CHIP',
 PHYS_PAGE='287',
 XY='(-1475,5225)',
 ROT='2',
 VER='2',
 PACK_TYPE='0201LF',
 LOCATION='R1020',
 CDS_LIB='pure_quanta',
 CDS_PART_NAME='Q_RES_0201LF-10K,1%,1/20W,CHIP,CS31001FE17',
 PART_NUMBER='CS31001FE17',
 VALUE='10K',
 PRIM_FILE='./archive_libs/logical/q_res/chips/chips.prt';

PART_NAME
 R1021 'Q_RES_0201LF-4.7K,5%,1/20W,EMPTY,CS24701JE04':;

SECTION_NUMBER 1
 '@T6G_MB_LIB.T6G(SCH_1):PAGE408_I5@PURE_QUANTA.Q_RES(CHIPS)':
 C_PATH='@t6g_mb_lib.t6g(sch_1):page408_i5@pure_quanta.q_res(chips)',
 P_PATH='@t6g_mb_lib.t6g(sch_1):page287_i5@pure_quanta.q_res(chips)',
 PATH='I5',
 DRAWING='@T6G_MB_LIB.T6G(SCH_1):PAGE408',
 WATTAGE='1/20W',
 TOLERANCE='5%',
 MATERIAL='EMPTY',
 PHYS_PAGE='287',
 XY='(-8975,4125)',
 ROT='0',
 VER='2',
 PACK_TYPE='0201LF',
 LOCATION='R1021',
 CDS_LIB='pure_quanta',
 CDS_PART_NAME='Q_RES_0201LF-4.7K,5%,1/20W,EMPTY,CS24701JE04',
 PART_NUMBER='CS24701JE04',
 VALUE='4.7K',
 PRIM_FILE='./archive_libs/logical/q_res/chips/chips.prt';

PART_NAME
 R1022 'Q_RES_0201LF-200,1%,1/20W,CHIP,CS12001FE12':;

SECTION_NUMBER 1
 '@T6G_MB_LIB.T6G(SCH_1):PAGE408_I102@PURE_QUANTA.Q_RES(CHIPS)':
 C_PATH='@t6g_mb_lib.t6g(sch_1):page408_i102@pure_quanta.q_res(chips)',
 P_PATH='@t6g_mb_lib.t6g(sch_1):page287_i102@pure_quanta.q_res(chips)',
 PATH='I102',
 DRAWING='@T6G_MB_LIB.T6G(SCH_1):PAGE408',
 WATTAGE='1/20W',
 TOLERANCE='1%',
 MATERIAL='CHIP',
 PHYS_PAGE='287',
 XY='(-8975,3450)',
 ROT='0',
 VER='2',
 PACK_TYPE='0201LF',
 LOCATION='R1022',
 CDS_LIB='pure_quanta',
 CDS_PART_NAME='Q_RES_0201LF-200,1%,1/20W,CHIP,CS12001FE12',
 PART_NUMBER='CS12001FE12',
 VALUE='200',
 PRIM_FILE='./archive_libs/logical/q_res/chips/chips.prt';

PART_NAME
 R1023 'Q_RES_0201LF-4.7K,5%,1/20W,EMPTY,CS24701JE04':;

SECTION_NUMBER 1
 '@T6G_MB_LIB.T6G(SCH_1):PAGE408_I78@PURE_QUANTA.Q_RES(CHIPS)':
 C_PATH='@t6g_mb_lib.t6g(sch_1):page408_i78@pure_quanta.q_res(chips)',
 P_PATH='@t6g_mb_lib.t6g(sch_1):page287_i78@pure_quanta.q_res(chips)',
 PATH='I78',
 DRAWING='@T6G_MB_LIB.T6G(SCH_1):PAGE408',
 WATTAGE='1/20W',
 TOLERANCE='5%',
 MATERIAL='EMPTY',
 PHYS_PAGE='287',
 XY='(-1475,6050)',
 ROT='2',
 VER='2',
 PACK_TYPE='0201LF',
 LOCATION='R1023',
 CDS_LIB='pure_quanta',
 CDS_PART_NAME='Q_RES_0201LF-4.7K,5%,1/20W,EMPTY,CS24701JE04',
 PART_NUMBER='CS24701JE04',
 VALUE='4.7K',
 PRIM_FILE='./archive_libs/logical/q_res/chips/chips.prt';

PART_NAME
 R1024 'Q_RES_0201LF-4.7K,5%,1/20W,EMPTY,CS24701JE04':;

SECTION_NUMBER 1
 '@T6G_MB_LIB.T6G(SCH_1):PAGE408_I42@PURE_QUANTA.Q_RES(CHIPS)':
 C_PATH='@t6g_mb_lib.t6g(sch_1):page408_i42@pure_quanta.q_res(chips)',
 P_PATH='@t6g_mb_lib.t6g(sch_1):page287_i42@pure_quanta.q_res(chips)',
 PATH='I42',
 DRAWING='@T6G_MB_LIB.T6G(SCH_1):PAGE408',
 WATTAGE='1/20W',
 TOLERANCE='5%',
 MATERIAL='EMPTY',
 PHYS_PAGE='287',
 XY='(-7425,6000)',
 ROT='0',
 VER='2',
 PACK_TYPE='0201LF',
 LOCATION='R1024',
 CDS_LIB='pure_quanta',
 CDS_PART_NAME='Q_RES_0201LF-4.7K,5%,1/20W,EMPTY,CS24701JE04',
 PART_NUMBER='CS24701JE04',
 VALUE='4.7K',
 PRIM_FILE='./archive_libs/logical/q_res/chips/chips.prt';

PART_NAME
 R1025 'Q_RES_0201LF-0,5%,1/20W,CHIP,CS00001JE10':;

SECTION_NUMBER 1
 '@T6G_MB_LIB.T6G(SCH_1):PAGE408_I30@PURE_QUANTA.Q_RES(CHIPS)':
 C_PATH='@t6g_mb_lib.t6g(sch_1):page408_i30@pure_quanta.q_res(chips)',
 P_PATH='@t6g_mb_lib.t6g(sch_1):page287_i30@pure_quanta.q_res(chips)',
 PATH='I30',
 DRAWING='@T6G_MB_LIB.T6G(SCH_1):PAGE408',
 WATTAGE='1/20W',
 TOLERANCE='5%',
 MATERIAL='CHIP',
 PHYS_PAGE='287',
 XY='(-6350,2900)',
 ROT='0',
 VER='1',
 PACK_TYPE='0201LF',
 LOCATION='R1025',
 CDS_LIB='pure_quanta',
 CDS_PART_NAME='Q_RES_0201LF-0,5%,1/20W,CHIP,CS00001JE10',
 PART_NUMBER='CS00001JE10',
 VALUE='0',
 PRIM_FILE='./archive_libs/logical/q_res/chips/chips.prt';

PART_NAME
 R1026 'Q_RES_0201LF-0,5%,1/20W,CHIP,CS00001JE10':;

SECTION_NUMBER 1
 '@T6G_MB_LIB.T6G(SCH_1):PAGE408_I29@PURE_QUANTA.Q_RES(CHIPS)':
 C_PATH='@t6g_mb_lib.t6g(sch_1):page408_i29@pure_quanta.q_res(chips)',
 P_PATH='@t6g_mb_lib.t6g(sch_1):page287_i29@pure_quanta.q_res(chips)',
 PATH='I29',
 DRAWING='@T6G_MB_LIB.T6G(SCH_1):PAGE408',
 WATTAGE='1/20W',
 TOLERANCE='5%',
 MATERIAL='CHIP',
 PHYS_PAGE='287',
 XY='(-6350,2800)',
 ROT='0',
 VER='1',
 PACK_TYPE='0201LF',
 LOCATION='R1026',
 CDS_LIB='pure_quanta',
 CDS_PART_NAME='Q_RES_0201LF-0,5%,1/20W,CHIP,CS00001JE10',
 PART_NUMBER='CS00001JE10',
 VALUE='0',
 PRIM_FILE='./archive_libs/logical/q_res/chips/chips.prt';

PART_NAME
 R1027 'Q_RES_0201LF-4.7K,5%,1/20W,EMPTY,CS24701JE04':;

SECTION_NUMBER 1
 '@T6G_MB_LIB.T6G(SCH_1):PAGE408_I10@PURE_QUANTA.Q_RES(CHIPS)':
 C_PATH='@t6g_mb_lib.t6g(sch_1):page408_i10@pure_quanta.q_res(chips)',
 P_PATH='@t6g_mb_lib.t6g(sch_1):page287_i10@pure_quanta.q_res(chips)',
 PATH='I10',
 DRAWING='@T6G_MB_LIB.T6G(SCH_1):PAGE408',
 WATTAGE='1/20W',
 TOLERANCE='5%',
 MATERIAL='EMPTY',
 PHYS_PAGE='287',
 XY='(-8950,6000)',
 ROT='0',
 VER='2',
 PACK_TYPE='0201LF',
 LOCATION='R1027',
 CDS_LIB='pure_quanta',
 CDS_PART_NAME='Q_RES_0201LF-4.7K,5%,1/20W,EMPTY,CS24701JE04',
 PART_NUMBER='CS24701JE04',
 VALUE='4.7K',
 PRIM_FILE='./archive_libs/logical/q_res/chips/chips.prt';

PART_NAME
 R1028 'Q_RES_0201LF-10K,1%,1/20W,CHIP,CS31001FE17':;

SECTION_NUMBER 1
 '@T6G_MB_LIB.T6G(SCH_1):PAGE408_I7@PURE_QUANTA.Q_RES(CHIPS)':
 C_PATH='@t6g_mb_lib.t6g(sch_1):page408_i7@pure_quanta.q_res(chips)',
 P_PATH='@t6g_mb_lib.t6g(sch_1):page287_i7@pure_quanta.q_res(chips)',
 PATH='I7',
 DRAWING='@T6G_MB_LIB.T6G(SCH_1):PAGE408',
 WATTAGE='1/20W',
 TOLERANCE='1%',
 MATERIAL='CHIP',
 PHYS_PAGE='287',
 XY='(-8950,5050)',
 ROT='0',
 VER='2',
 PACK_TYPE='0201LF',
 LOCATION='R1028',
 CDS_LIB='pure_quanta',
 CDS_PART_NAME='Q_RES_0201LF-10K,1%,1/20W,CHIP,CS31001FE17',
 PART_NUMBER='CS31001FE17',
 VALUE='10K',
 PRIM_FILE='./archive_libs/logical/q_res/chips/chips.prt';

PART_NAME
 R1029 'Q_RES_0201LF-10K,1%,1/20W,CHIP,CS31001FE17':;

SECTION_NUMBER 1
 '@T6G_MB_LIB.T6G(SCH_1):PAGE408_I8@PURE_QUANTA.Q_RES(CHIPS)':
 C_PATH='@t6g_mb_lib.t6g(sch_1):page408_i8@pure_quanta.q_res(chips)',
 P_PATH='@t6g_mb_lib.t6g(sch_1):page287_i8@pure_quanta.q_res(chips)',
 PATH='I8',
 DRAWING='@T6G_MB_LIB.T6G(SCH_1):PAGE408',
 WATTAGE='1/20W',
 TOLERANCE='1%',
 MATERIAL='CHIP',
 PHYS_PAGE='287',
 XY='(-8650,5050)',
 ROT='0',
 VER='2',
 PACK_TYPE='0201LF',
 LOCATION='R1029',
 CDS_LIB='pure_quanta',
 CDS_PART_NAME='Q_RES_0201LF-10K,1%,1/20W,CHIP,CS31001FE17',
 PART_NUMBER='CS31001FE17',
 VALUE='10K',
 PRIM_FILE='./archive_libs/logical/q_res/chips/chips.prt';

PART_NAME
 R1030 'Q_RES_0201LF-4.7K,5%,1/20W,EMPTY,CS24701JE04':;

SECTION_NUMBER 1
 '@T6G_MB_LIB.T6G(SCH_1):PAGE408_I11@PURE_QUANTA.Q_RES(CHIPS)':
 C_PATH='@t6g_mb_lib.t6g(sch_1):page408_i11@pure_quanta.q_res(chips)',
 P_PATH='@t6g_mb_lib.t6g(sch_1):page287_i11@pure_quanta.q_res(chips)',
 PATH='I11',
 DRAWING='@T6G_MB_LIB.T6G(SCH_1):PAGE408',
 WATTAGE='1/20W',
 TOLERANCE='5%',
 MATERIAL='EMPTY',
 PHYS_PAGE='287',
 XY='(-8325,6000)',
 ROT='0',
 VER='2',
 PACK_TYPE='0201LF',
 LOCATION='R1030',
 CDS_LIB='pure_quanta',
 CDS_PART_NAME='Q_RES_0201LF-4.7K,5%,1/20W,EMPTY,CS24701JE04',
 PART_NUMBER='CS24701JE04',
 VALUE='4.7K',
 PRIM_FILE='./archive_libs/logical/q_res/chips/chips.prt';

PART_NAME
 R1031 'Q_RES_0201LF-4.7K,5%,1/20W,CHIP,CS24701JE04':;

SECTION_NUMBER 1
 '@T6G_MB_LIB.T6G(SCH_1):PAGE408_I9@PURE_QUANTA.Q_RES(CHIPS)':
 C_PATH='@t6g_mb_lib.t6g(sch_1):page408_i9@pure_quanta.q_res(chips)',
 P_PATH='@t6g_mb_lib.t6g(sch_1):page287_i9@pure_quanta.q_res(chips)',
 PATH='I9',
 DRAWING='@T6G_MB_LIB.T6G(SCH_1):PAGE408',
 WATTAGE='1/20W',
 TOLERANCE='5%',
 MATERIAL='CHIP',
 PHYS_PAGE='287',
 XY='(-8325,5050)',
 ROT='0',
 VER='2',
 PACK_TYPE='0201LF',
 LOCATION='R1031',
 CDS_LIB='pure_quanta',
 CDS_PART_NAME='Q_RES_0201LF-4.7K,5%,1/20W,CHIP,CS24701JE04',
 PART_NUMBER='CS24701JE04',
 VALUE='4.7K',
 PRIM_FILE='./archive_libs/logical/q_res/chips/chips.prt';

PART_NAME
 R1032 'Q_RES_0201LF-4.7K,5%,1/20W,EMPTY,CS24701JE04':;

SECTION_NUMBER 1
 '@T6G_MB_LIB.T6G(SCH_1):PAGE408_I40@PURE_QUANTA.Q_RES(CHIPS)':
 C_PATH='@t6g_mb_lib.t6g(sch_1):page408_i40@pure_quanta.q_res(chips)',
 P_PATH='@t6g_mb_lib.t6g(sch_1):page287_i40@pure_quanta.q_res(chips)',
 PATH='I40',
 DRAWING='@T6G_MB_LIB.T6G(SCH_1):PAGE408',
 WATTAGE='1/20W',
 TOLERANCE='5%',
 MATERIAL='EMPTY',
 PHYS_PAGE='287',
 XY='(-8025,5950)',
 ROT='0',
 VER='2',
 PACK_TYPE='0201LF',
 LOCATION='R1032',
 CDS_LIB='pure_quanta',
 CDS_PART_NAME='Q_RES_0201LF-4.7K,5%,1/20W,EMPTY,CS24701JE04',
 PART_NUMBER='CS24701JE04',
 VALUE='4.7K',
 PRIM_FILE='./archive_libs/logical/q_res/chips/chips.prt';

PART_NAME
 R1033 'Q_RES_0201LF-4.7K,5%,1/20W,CHIP,CS24701JE04':;

SECTION_NUMBER 1
 '@T6G_MB_LIB.T6G(SCH_1):PAGE408_I36@PURE_QUANTA.Q_RES(CHIPS)':
 C_PATH='@t6g_mb_lib.t6g(sch_1):page408_i36@pure_quanta.q_res(chips)',
 P_PATH='@t6g_mb_lib.t6g(sch_1):page287_i36@pure_quanta.q_res(chips)',
 PATH='I36',
 DRAWING='@T6G_MB_LIB.T6G(SCH_1):PAGE408',
 WATTAGE='1/20W',
 TOLERANCE='5%',
 MATERIAL='CHIP',
 PHYS_PAGE='287',
 XY='(-8025,5025)',
 ROT='0',
 VER='2',
 PACK_TYPE='0201LF',
 LOCATION='R1033',
 CDS_LIB='pure_quanta',
 CDS_PART_NAME='Q_RES_0201LF-4.7K,5%,1/20W,CHIP,CS24701JE04',
 PART_NUMBER='CS24701JE04',
 VALUE='4.7K',
 PRIM_FILE='./archive_libs/logical/q_res/chips/chips.prt';

PART_NAME
 R1034 'Q_RES_0201LF-4.7K,5%,1/20W,EMPTY,CS24701JE04':;

SECTION_NUMBER 1
 '@T6G_MB_LIB.T6G(SCH_1):PAGE408_I41@PURE_QUANTA.Q_RES(CHIPS)':
 C_PATH='@t6g_mb_lib.t6g(sch_1):page408_i41@pure_quanta.q_res(chips)',
 P_PATH='@t6g_mb_lib.t6g(sch_1):page287_i41@pure_quanta.q_res(chips)',
 PATH='I41',
 DRAWING='@T6G_MB_LIB.T6G(SCH_1):PAGE408',
 WATTAGE='1/20W',
 TOLERANCE='5%',
 MATERIAL='EMPTY',
 PHYS_PAGE='287',
 XY='(-7725,5975)',
 ROT='0',
 VER='2',
 PACK_TYPE='0201LF',
 LOCATION='R1034',
 CDS_LIB='pure_quanta',
 CDS_PART_NAME='Q_RES_0201LF-4.7K,5%,1/20W,EMPTY,CS24701JE04',
 PART_NUMBER='CS24701JE04',
 VALUE='4.7K',
 PRIM_FILE='./archive_libs/logical/q_res/chips/chips.prt';

PART_NAME
 R1035 'Q_RES_0201LF-4.7K,5%,1/20W,CHIP,CS24701JE04':;

SECTION_NUMBER 1
 '@T6G_MB_LIB.T6G(SCH_1):PAGE408_I37@PURE_QUANTA.Q_RES(CHIPS)':
 C_PATH='@t6g_mb_lib.t6g(sch_1):page408_i37@pure_quanta.q_res(chips)',
 P_PATH='@t6g_mb_lib.t6g(sch_1):page287_i37@pure_quanta.q_res(chips)',
 PATH='I37',
 DRAWING='@T6G_MB_LIB.T6G(SCH_1):PAGE408',
 WATTAGE='1/20W',
 TOLERANCE='5%',
 MATERIAL='CHIP',
 PHYS_PAGE='287',
 XY='(-7725,5025)',
 ROT='0',
 VER='2',
 PACK_TYPE='0201LF',
 LOCATION='R1035',
 CDS_LIB='pure_quanta',
 CDS_PART_NAME='Q_RES_0201LF-4.7K,5%,1/20W,CHIP,CS24701JE04',
 PART_NUMBER='CS24701JE04',
 VALUE='4.7K',
 PRIM_FILE='./archive_libs/logical/q_res/chips/chips.prt';

PART_NAME
 R1036 'Q_RES_0402LF-0,5%,1/16W,CHIP,CS00002JB13':;

SECTION_NUMBER 1
 '@T6G_MB_LIB.T6G(SCH_1):PAGE84_I6@PURE_QUANTA.Q_RES(CHIPS)':
 C_PATH='@t6g_mb_lib.t6g(sch_1):page84_i6@pure_quanta.q_res(chips)',
 P_PATH='@t6g_mb_lib.t6g(sch_1):page85_i6@pure_quanta.q_res(chips)',
 PATH='I6',
 DRAWING='@T6G_MB_LIB.T6G(SCH_1):PAGE84',
 BOM_COST='OCP3.0 ',
 WATTAGE='1/16W',
 TOLERANCE='5%',
 MATERIAL='CHIP',
 PHYS_PAGE='85',
 XY='(-7625,1925)',
 ROT='0',
 VER='1',
 PACK_TYPE='0402LF',
 LOCATION='R1036',
 CDS_LIB='pure_quanta',
 CDS_PART_NAME='Q_RES_0402LF-0,5%,1/16W,CHIP,CS00002JB13',
 PART_NUMBER='CS00002JB13',
 VALUE='0',
 PRIM_FILE='./archive_libs/logical/q_res/chips/chips.prt';

PART_NAME
 R1037 'Q_RES_0201LF-4.7K,5%,1/20W,CHIP,CS24701JE04':;

SECTION_NUMBER 1
 '@T6G_MB_LIB.T6G(SCH_1):PAGE408_I39@PURE_QUANTA.Q_RES(CHIPS)':
 C_PATH='@t6g_mb_lib.t6g(sch_1):page408_i39@pure_quanta.q_res(chips)',
 P_PATH='@t6g_mb_lib.t6g(sch_1):page287_i39@pure_quanta.q_res(chips)',
 PATH='I39',
 DRAWING='@T6G_MB_LIB.T6G(SCH_1):PAGE408',
 WATTAGE='1/20W',
 TOLERANCE='5%',
 MATERIAL='CHIP',
 PHYS_PAGE='287',
 XY='(-7425,5000)',
 ROT='0',
 VER='2',
 PACK_TYPE='0201LF',
 LOCATION='R1037',
 CDS_LIB='pure_quanta',
 CDS_PART_NAME='Q_RES_0201LF-4.7K,5%,1/20W,CHIP,CS24701JE04',
 PART_NUMBER='CS24701JE04',
 VALUE='4.7K',
 PRIM_FILE='./archive_libs/logical/q_res/chips/chips.prt';

PART_NAME
 R1038 'Q_RES_0402LF-0,5%,1/16W,CHIP,CS00002JB13':;

SECTION_NUMBER 1
 '@T6G_MB_LIB.T6G(SCH_1):PAGE297_I101@PURE_QUANTA.Q_RES(CHIPS)':
 C_PATH='@t6g_mb_lib.t6g(sch_1):page297_i101@pure_quanta.q_res(chips)',
 P_PATH='@t6g_mb_lib.t6g(sch_1):page145_i101@pure_quanta.q_res(chips)',
 PATH='I101',
 DRAWING='@T6G_MB_LIB.T6G(SCH_1):PAGE297',
 BOM_COST='OCP3.0 ',
 WATTAGE='1/16W',
 TOLERANCE='5%',
 MATERIAL='CHIP',
 PHYS_PAGE='145',
 XY='(-825,400)',
 ROT='0',
 VER='1',
 PACK_TYPE='0402LF',
 LOCATION='R1038',
 CDS_LIB='pure_quanta',
 CDS_PART_NAME='Q_RES_0402LF-0,5%,1/16W,CHIP,CS00002JB13',
 PART_NUMBER='CS00002JB13',
 VALUE='0',
 PRIM_FILE='./archive_libs/logical/q_res/chips/chips.prt';

PART_NAME
 R1039 'Q_RES_0201LF-4.7K,5%,1/20W,CHIP,CS24701JE04':;

SECTION_NUMBER 1
 '@T6G_MB_LIB.T6G(SCH_1):PAGE408_I51@PURE_QUANTA.Q_RES(CHIPS)':
 C_PATH='@t6g_mb_lib.t6g(sch_1):page408_i51@pure_quanta.q_res(chips)',
 P_PATH='@t6g_mb_lib.t6g(sch_1):page287_i51@pure_quanta.q_res(chips)',
 PATH='I51',
 DRAWING='@T6G_MB_LIB.T6G(SCH_1):PAGE408',
 WATTAGE='1/20W',
 TOLERANCE='5%',
 MATERIAL='CHIP',
 PHYS_PAGE='287',
 XY='(-5025,6075)',
 ROT='0',
 VER='2',
 PACK_TYPE='0201LF',
 LOCATION='R1039',
 CDS_LIB='pure_quanta',
 CDS_PART_NAME='Q_RES_0201LF-4.7K,5%,1/20W,CHIP,CS24701JE04',
 PART_NUMBER='CS24701JE04',
 VALUE='4.7K',
 PRIM_FILE='./archive_libs/logical/q_res/chips/chips.prt';

PART_NAME
 R1040 'Q_RES_0201LF-1K,1%,1/20W,EMPTY,CS21001FE07':;

SECTION_NUMBER 1
 '@T6G_MB_LIB.T6G(SCH_1):PAGE409_I19@PURE_QUANTA.Q_RES(CHIPS)':
 C_PATH='@t6g_mb_lib.t6g(sch_1):page409_i19@pure_quanta.q_res(chips)',
 P_PATH='@t6g_mb_lib.t6g(sch_1):page288_i19@pure_quanta.q_res(chips)',
 PATH='I19',
 DRAWING='@T6G_MB_LIB.T6G(SCH_1):PAGE409',
 WATTAGE='1/20W',
 TOLERANCE='1%',
 MATERIAL='EMPTY',
 PHYS_PAGE='288',
 XY='(-8900,3900)',
 ROT='0',
 VER='2',
 PACK_TYPE='0201LF',
 LOCATION='R1040',
 CDS_LIB='pure_quanta',
 CDS_PART_NAME='Q_RES_0201LF-1K,1%,1/20W,EMPTY,CS21001FE07',
 PART_NUMBER='CS21001FE07',
 VALUE='1K',
 PRIM_FILE='./archive_libs/logical/q_res/chips/chips.prt';

PART_NAME
 R1041 'Q_RES_0201LF-200,1%,1/20W,CHIP,CS12001FE12':;

SECTION_NUMBER 1
 '@T6G_MB_LIB.T6G(SCH_1):PAGE409_I18@PURE_QUANTA.Q_RES(CHIPS)':
 C_PATH='@t6g_mb_lib.t6g(sch_1):page409_i18@pure_quanta.q_res(chips)',
 P_PATH='@t6g_mb_lib.t6g(sch_1):page288_i18@pure_quanta.q_res(chips)',
 PATH='I18',
 DRAWING='@T6G_MB_LIB.T6G(SCH_1):PAGE409',
 WATTAGE='1/20W',
 TOLERANCE='1%',
 MATERIAL='CHIP',
 PHYS_PAGE='288',
 XY='(-7875,3350)',
 ROT='0',
 VER='2',
 PACK_TYPE='0201LF',
 LOCATION='R1041',
 CDS_LIB='pure_quanta',
 CDS_PART_NAME='Q_RES_0201LF-200,1%,1/20W,CHIP,CS12001FE12',
 PART_NUMBER='CS12001FE12',
 VALUE='200',
 PRIM_FILE='./archive_libs/logical/q_res/chips/chips.prt';

PART_NAME
 R1042 'Q_RES_0201LF-0,5%,1/20W,CHIP,CS00001JE10':;

SECTION_NUMBER 1
 '@T6G_MB_LIB.T6G(SCH_1):PAGE409_I13@PURE_QUANTA.Q_RES(CHIPS)':
 C_PATH='@t6g_mb_lib.t6g(sch_1):page409_i13@pure_quanta.q_res(chips)',
 P_PATH='@t6g_mb_lib.t6g(sch_1):page288_i13@pure_quanta.q_res(chips)',
 PATH='I13',
 DRAWING='@T6G_MB_LIB.T6G(SCH_1):PAGE409',
 WATTAGE='1/20W',
 TOLERANCE='5%',
 MATERIAL='CHIP',
 PHYS_PAGE='288',
 XY='(-1675,1250)',
 ROT='0',
 VER='2',
 PACK_TYPE='0201LF',
 LOCATION='R1042',
 CDS_LIB='pure_quanta',
 CDS_PART_NAME='Q_RES_0201LF-0,5%,1/20W,CHIP,CS00001JE10',
 PART_NUMBER='CS00001JE10',
 VALUE='0',
 PRIM_FILE='./archive_libs/logical/q_res/chips/chips.prt';

PART_NAME
 R1043 'Q_RES_0201LF-0,5%,1/20W,CHIP,CS00001JE10':;

SECTION_NUMBER 1
 '@T6G_MB_LIB.T6G(SCH_1):PAGE409_I15@PURE_QUANTA.Q_RES(CHIPS)':
 C_PATH='@t6g_mb_lib.t6g(sch_1):page409_i15@pure_quanta.q_res(chips)',
 P_PATH='@t6g_mb_lib.t6g(sch_1):page288_i15@pure_quanta.q_res(chips)',
 PATH='I15',
 DRAWING='@T6G_MB_LIB.T6G(SCH_1):PAGE409',
 WATTAGE='1/20W',
 TOLERANCE='5%',
 MATERIAL='CHIP',
 PHYS_PAGE='288',
 XY='(-1525,1800)',
 ROT='0',
 VER='2',
 PACK_TYPE='0201LF',
 LOCATION='R1043',
 CDS_LIB='pure_quanta',
 CDS_PART_NAME='Q_RES_0201LF-0,5%,1/20W,CHIP,CS00001JE10',
 PART_NUMBER='CS00001JE10',
 VALUE='0',
 PRIM_FILE='./archive_libs/logical/q_res/chips/chips.prt';

PART_NAME
 R1044 'Q_RES_0201LF-1K,1%,1/20W,CHIP,CS21001FE07':;

SECTION_NUMBER 1
 '@T6G_MB_LIB.T6G(SCH_1):PAGE410_I20@PURE_QUANTA.Q_RES(CHIPS)':
 C_PATH='@t6g_mb_lib.t6g(sch_1):page410_i20@pure_quanta.q_res(chips)',
 P_PATH='@t6g_mb_lib.t6g(sch_1):page289_i20@pure_quanta.q_res(chips)',
 PATH='I20',
 DRAWING='@T6G_MB_LIB.T6G(SCH_1):PAGE410',
 WATTAGE='1/20W',
 TOLERANCE='1%',
 MATERIAL='CHIP',
 PHYS_PAGE='289',
 XY='(-3075,5375)',
 ROT='0',
 VER='2',
 PACK_TYPE='0201LF',
 LOCATION='R1044',
 CDS_LIB='pure_quanta',
 CDS_PART_NAME='Q_RES_0201LF-1K,1%,1/20W,CHIP,CS21001FE07',
 PART_NUMBER='CS21001FE07',
 VALUE='1K',
 PRIM_FILE='./archive_libs/logical/q_res/chips/chips.prt';

PART_NAME
 R1045 'Q_RES_0402LF-0,5%,1/16W,EMPTY,CS00002JB13':;

SECTION_NUMBER 1
 '@T6G_MB_LIB.T6G(SCH_1):PAGE422_I5@PURE_QUANTA.Q_RES(CHIPS)':
 C_PATH='@t6g_mb_lib.t6g(sch_1):page422_i5@pure_quanta.q_res(chips)',
 P_PATH='@t6g_mb_lib.t6g(sch_1):page301_i5@pure_quanta.q_res(chips)',
 PATH='I5',
 DRAWING='@T6G_MB_LIB.T6G(SCH_1):PAGE422',
 SEC_TYPE='0402LF',
 WATTAGE='1/16W',
 TOLERANCE='5%',
 MATERIAL='EMPTY',
 PHYS_PAGE='301',
 XY='(-7550,4050)',
 ROT='0',
 VER='1',
 PACK_TYPE='0402LF',
 LOCATION='R1045',
 SEC='1',
 CDS_LIB='pure_quanta',
 CDS_PART_NAME='Q_RES_0402LF-0,5%,1/16W,EMPTY,CS00002JB13',
 PART_NUMBER='CS00002JB13',
 VALUE='0',
 PRIM_FILE='./archive_libs/logical/q_res/chips/chips.prt';

PART_NAME
 R1046 'Q_RES_0402LF-0,5%,1/16W,EMPTY,CS00002JB13':;

SECTION_NUMBER 1
 '@T6G_MB_LIB.T6G(SCH_1):PAGE422_I4@PURE_QUANTA.Q_RES(CHIPS)':
 C_PATH='@t6g_mb_lib.t6g(sch_1):page422_i4@pure_quanta.q_res(chips)',
 P_PATH='@t6g_mb_lib.t6g(sch_1):page301_i4@pure_quanta.q_res(chips)',
 PATH='I4',
 DRAWING='@T6G_MB_LIB.T6G(SCH_1):PAGE422',
 SEC_TYPE='0402LF',
 WATTAGE='1/16W',
 TOLERANCE='5%',
 MATERIAL='EMPTY',
 PHYS_PAGE='301',
 XY='(-7550,3850)',
 ROT='0',
 VER='1',
 PACK_TYPE='0402LF',
 LOCATION='R1046',
 SEC='1',
 CDS_LIB='pure_quanta',
 CDS_PART_NAME='Q_RES_0402LF-0,5%,1/16W,EMPTY,CS00002JB13',
 PART_NUMBER='CS00002JB13',
 VALUE='0',
 PRIM_FILE='./archive_libs/logical/q_res/chips/chips.prt';

PART_NAME
 R1047 'Q_RES_0201LF-0,5%,1/20W,CHIP,CS00001JE10':;

SECTION_NUMBER 1
 '@T6G_MB_LIB.T6G(SCH_1):PAGE419_I56@PURE_QUANTA.Q_RES(CHIPS)':
 C_PATH='@t6g_mb_lib.t6g(sch_1):page419_i56@pure_quanta.q_res(chips)',
 P_PATH='@t6g_mb_lib.t6g(sch_1):page298_i56@pure_quanta.q_res(chips)',
 PATH='I56',
 DRAWING='@T6G_MB_LIB.T6G(SCH_1):PAGE419',
 SEC_TYPE='0201LF',
 WATTAGE='1/20W',
 TOLERANCE='5%',
 MATERIAL='CHIP',
 PHYS_PAGE='298',
 XY='(-2600,2100)',
 ROT='0',
 VER='1',
 PACK_TYPE='0201LF',
 LOCATION='R1047',
 SEC='1',
 CDS_LIB='pure_quanta',
 CDS_PART_NAME='Q_RES_0201LF-0,5%,1/20W,CHIP,CS00001JE10',
 PART_NUMBER='CS00001JE10',
 VALUE='0',
 PRIM_FILE='./archive_libs/logical/q_res/chips/chips.prt';

PART_NAME
 R1048 'Q_RES_0201LF-4.7K,5%,1/20W,EMPTY,CS24701JE04':;

SECTION_NUMBER 1
 '@T6G_MB_LIB.T6G(SCH_1):PAGE419_I50@PURE_QUANTA.Q_RES(CHIPS)':
 C_PATH='@t6g_mb_lib.t6g(sch_1):page419_i50@pure_quanta.q_res(chips)',
 P_PATH='@t6g_mb_lib.t6g(sch_1):page298_i50@pure_quanta.q_res(chips)',
 PATH='I50',
 DRAWING='@T6G_MB_LIB.T6G(SCH_1):PAGE419',
 WATTAGE='1/20W',
 TOLERANCE='5%',
 MATERIAL='EMPTY',
 PHYS_PAGE='298',
 XY='(-5050,5450)',
 ROT='0',
 VER='2',
 PACK_TYPE='0201LF',
 LOCATION='R1048',
 CDS_LIB='pure_quanta',
 CDS_PART_NAME='Q_RES_0201LF-4.7K,5%,1/20W,EMPTY,CS24701JE04',
 PART_NUMBER='CS24701JE04',
 VALUE='4.7K',
 PRIM_FILE='./archive_libs/logical/q_res/chips/chips.prt';

PART_NAME
 R1049 'Q_RES_0402LF-1K,1%,1/16W,EMPTY,CS21002FB06':;

SECTION_NUMBER 1
 '@T6G_MB_LIB.T6G(SCH_1):PAGE146_I12@PURE_QUANTA.Q_RES(CHIPS)':
 C_PATH='@t6g_mb_lib.t6g(sch_1):page146_i12@pure_quanta.q_res(chips)',
 P_PATH='@t6g_mb_lib.t6g(sch_1):page169_i12@pure_quanta.q_res(chips)',
 PATH='I12',
 DRAWING='@T6G_MB_LIB.T6G(SCH_1):PAGE146',
 WATTAGE='1/16W',
 TOLERANCE='1%',
 MATERIAL='EMPTY',
 PHYS_PAGE='169',
 XY='(-8025,3925)',
 ROT='0',
 VER='2',
 PACK_TYPE='0402LF',
 LOCATION='R1049',
 CDS_LIB='pure_quanta',
 CDS_PART_NAME='Q_RES_0402LF-1K,1%,1/16W,EMPTY,CS21002FB06',
 PART_NUMBER='CS21002FB06',
 VALUE='1K',
 PRIM_FILE='./archive_libs/logical/q_res/chips/chips.prt';

PART_NAME
 R1050 'Q_RES_0402LF-0,5%,1/16W,EMPTY,CS00002JB13':;

SECTION_NUMBER 1
 '@T6G_MB_LIB.T6G(SCH_1):PAGE422_I89@PURE_QUANTA.Q_RES(CHIPS)':
 C_PATH='@t6g_mb_lib.t6g(sch_1):page422_i89@pure_quanta.q_res(chips)',
 P_PATH='@t6g_mb_lib.t6g(sch_1):page301_i89@pure_quanta.q_res(chips)',
 PATH='I89',
 DRAWING='@T6G_MB_LIB.T6G(SCH_1):PAGE422',
 WATTAGE='1/16W',
 TOLERANCE='5%',
 MATERIAL='EMPTY',
 PHYS_PAGE='301',
 XY='(-7950,4375)',
 ROT='0',
 VER='2',
 PACK_TYPE='0402LF',
 LOCATION='R1050',
 CDS_LIB='pure_quanta',
 CDS_PART_NAME='Q_RES_0402LF-0,5%,1/16W,EMPTY,CS00002JB13',
 PART_NUMBER='CS00002JB13',
 VALUE='0',
 PRIM_FILE='./archive_libs/logical/q_res/chips/chips.prt';

PART_NAME
 R1051 'Q_RES_0603LF-0,5%,1/4W,EMPTY,CS00006J900':;

SECTION_NUMBER 1
 '@T6G_MB_LIB.T6G(SCH_1):PAGE422_I21@PURE_QUANTA.Q_RES(CHIPS)':
 C_PATH='@t6g_mb_lib.t6g(sch_1):page422_i21@pure_quanta.q_res(chips)',
 P_PATH='@t6g_mb_lib.t6g(sch_1):page301_i21@pure_quanta.q_res(chips)',
 PATH='I21',
 DRAWING='@T6G_MB_LIB.T6G(SCH_1):PAGE422',
 WATTAGE='1/4W',
 TOLERANCE='5%',
 MATERIAL='EMPTY',
 PHYS_PAGE='301',
 XY='(-4150,3050)',
 ROT='2',
 VER='2',
 PACK_TYPE='0603LF',
 LOCATION='R1051',
 CDS_LIB='pure_quanta',
 CDS_PART_NAME='Q_RES_0603LF-0,5%,1/4W,EMPTY,CS00006J900',
 PART_NUMBER='CS00006J900',
 VALUE='0',
 PRIM_FILE='./archive_libs/logical/q_res/chips/chips.prt';

PART_NAME
 R1052 'Q_RES_0402LF-1K,1%,1/16W,EMPTY,CS21002FB06':;

SECTION_NUMBER 1
 '@T6G_MB_LIB.T6G(SCH_1):PAGE146_I38@PURE_QUANTA.Q_RES(CHIPS)':
 C_PATH='@t6g_mb_lib.t6g(sch_1):page146_i38@pure_quanta.q_res(chips)',
 P_PATH='@t6g_mb_lib.t6g(sch_1):page169_i38@pure_quanta.q_res(chips)',
 PATH='I38',
 DRAWING='@T6G_MB_LIB.T6G(SCH_1):PAGE146',
 WATTAGE='1/16W',
 TOLERANCE='1%',
 MATERIAL='EMPTY',
 PHYS_PAGE='169',
 XY='(-7900,2200)',
 ROT='0',
 VER='2',
 PACK_TYPE='0402LF',
 LOCATION='R1052',
 CDS_LIB='pure_quanta',
 CDS_PART_NAME='Q_RES_0402LF-1K,1%,1/16W,EMPTY,CS21002FB06',
 PART_NUMBER='CS21002FB06',
 VALUE='1K',
 PRIM_FILE='./archive_libs/logical/q_res/chips/chips.prt';

PART_NAME
 R1053 'Q_RES_0603LF-0,5%,1/4W,CHIP,CS00006J900':;

SECTION_NUMBER 1
 '@T6G_MB_LIB.T6G(SCH_1):PAGE422_I22@PURE_QUANTA.Q_RES(CHIPS)':
 C_PATH='@t6g_mb_lib.t6g(sch_1):page422_i22@pure_quanta.q_res(chips)',
 P_PATH='@t6g_mb_lib.t6g(sch_1):page301_i22@pure_quanta.q_res(chips)',
 PATH='I22',
 DRAWING='@T6G_MB_LIB.T6G(SCH_1):PAGE422',
 WATTAGE='1/4W',
 TOLERANCE='5%',
 MATERIAL='CHIP',
 PHYS_PAGE='301',
 XY='(-3775,2775)',
 ROT='0',
 VER='1',
 PACK_TYPE='0603LF',
 LOCATION='R1053',
 CDS_LIB='pure_quanta',
 CDS_PART_NAME='Q_RES_0603LF-0,5%,1/4W,CHIP,CS00006J900',
 PART_NUMBER='CS00006J900',
 VALUE='0',
 PRIM_FILE='./archive_libs/logical/q_res/chips/chips.prt';

PART_NAME
 R1054 'Q_RES_0201LF-0,5%,1/20W,CHIP,CS00001JE10':;

SECTION_NUMBER 1
 '@T6G_MB_LIB.T6G(SCH_1):PAGE419_I55@PURE_QUANTA.Q_RES(CHIPS)':
 C_PATH='@t6g_mb_lib.t6g(sch_1):page419_i55@pure_quanta.q_res(chips)',
 P_PATH='@t6g_mb_lib.t6g(sch_1):page298_i55@pure_quanta.q_res(chips)',
 PATH='I55',
 DRAWING='@T6G_MB_LIB.T6G(SCH_1):PAGE419',
 WATTAGE='1/20W',
 TOLERANCE='5%',
 MATERIAL='CHIP',
 PHYS_PAGE='298',
 XY='(-2600,2000)',
 ROT='0',
 VER='1',
 PACK_TYPE='0201LF',
 LOCATION='R1054',
 CDS_LIB='pure_quanta',
 CDS_PART_NAME='Q_RES_0201LF-0,5%,1/20W,CHIP,CS00001JE10',
 PART_NUMBER='CS00001JE10',
 VALUE='0',
 PRIM_FILE='./archive_libs/logical/q_res/chips/chips.prt';

PART_NAME
 R1055 'Q_RES_0201LF-1K,1%,1/20W,CHIP,CS21001FE07':;

SECTION_NUMBER 1
 '@T6G_MB_LIB.T6G(SCH_1):PAGE419_I67@PURE_QUANTA.Q_RES(CHIPS)':
 C_PATH='@t6g_mb_lib.t6g(sch_1):page419_i67@pure_quanta.q_res(chips)',
 P_PATH='@t6g_mb_lib.t6g(sch_1):page298_i67@pure_quanta.q_res(chips)',
 PATH='I67',
 DRAWING='@T6G_MB_LIB.T6G(SCH_1):PAGE419',
 WATTAGE='1/20W',
 TOLERANCE='1%',
 MATERIAL='CHIP',
 PHYS_PAGE='298',
 XY='(-3500,5900)',
 ROT='0',
 VER='2',
 PACK_TYPE='0201LF',
 LOCATION='R1055',
 CDS_LIB='pure_quanta',
 CDS_PART_NAME='Q_RES_0201LF-1K,1%,1/20W,CHIP,CS21001FE07',
 PART_NUMBER='CS21001FE07',
 VALUE='1K',
 PRIM_FILE='./archive_libs/logical/q_res/chips/chips.prt';

PART_NAME
 R1056 'Q_RES_0201LF-1K,1%,1/20W,EMPTY,CS21001FE07':;

SECTION_NUMBER 1
 '@T6G_MB_LIB.T6G(SCH_1):PAGE419_I65@PURE_QUANTA.Q_RES(CHIPS)':
 C_PATH='@t6g_mb_lib.t6g(sch_1):page419_i65@pure_quanta.q_res(chips)',
 P_PATH='@t6g_mb_lib.t6g(sch_1):page298_i65@pure_quanta.q_res(chips)',
 PATH='I65',
 DRAWING='@T6G_MB_LIB.T6G(SCH_1):PAGE419',
 WATTAGE='1/20W',
 TOLERANCE='1%',
 MATERIAL='EMPTY',
 PHYS_PAGE='298',
 XY='(-3500,5125)',
 ROT='0',
 VER='2',
 PACK_TYPE='0201LF',
 LOCATION='R1056',
 CDS_LIB='pure_quanta',
 CDS_PART_NAME='Q_RES_0201LF-1K,1%,1/20W,EMPTY,CS21001FE07',
 PART_NUMBER='CS21001FE07',
 VALUE='1K',
 PRIM_FILE='./archive_libs/logical/q_res/chips/chips.prt';

PART_NAME
 R1057 'Q_RES_0201LF-1K,1%,1/20W,EMPTY,CS21001FE07':;

SECTION_NUMBER 1
 '@T6G_MB_LIB.T6G(SCH_1):PAGE419_I68@PURE_QUANTA.Q_RES(CHIPS)':
 C_PATH='@t6g_mb_lib.t6g(sch_1):page419_i68@pure_quanta.q_res(chips)',
 P_PATH='@t6g_mb_lib.t6g(sch_1):page298_i68@pure_quanta.q_res(chips)',
 PATH='I68',
 DRAWING='@T6G_MB_LIB.T6G(SCH_1):PAGE419',
 WATTAGE='1/20W',
 TOLERANCE='1%',
 MATERIAL='EMPTY',
 PHYS_PAGE='298',
 XY='(-3200,5900)',
 ROT='0',
 VER='2',
 PACK_TYPE='0201LF',
 LOCATION='R1057',
 CDS_LIB='pure_quanta',
 CDS_PART_NAME='Q_RES_0201LF-1K,1%,1/20W,EMPTY,CS21001FE07',
 PART_NUMBER='CS21001FE07',
 VALUE='1K',
 PRIM_FILE='./archive_libs/logical/q_res/chips/chips.prt';

PART_NAME
 R1058 'Q_RES_0201LF-20K,1%,1/20W,CHIP,CS32001FE00':;

SECTION_NUMBER 1
 '@T6G_MB_LIB.T6G(SCH_1):PAGE419_I66@PURE_QUANTA.Q_RES(CHIPS)':
 C_PATH='@t6g_mb_lib.t6g(sch_1):page419_i66@pure_quanta.q_res(chips)',
 P_PATH='@t6g_mb_lib.t6g(sch_1):page298_i66@pure_quanta.q_res(chips)',
 PATH='I66',
 DRAWING='@T6G_MB_LIB.T6G(SCH_1):PAGE419',
 WATTAGE='1/20W',
 TOLERANCE='1%',
 MATERIAL='CHIP',
 PHYS_PAGE='298',
 XY='(-3200,5125)',
 ROT='0',
 VER='2',
 PACK_TYPE='0201LF',
 LOCATION='R1058',
 CDS_LIB='pure_quanta',
 CDS_PART_NAME='Q_RES_0201LF-20K,1%,1/20W,CHIP,CS32001FE00',
 PART_NUMBER='CS32001FE00',
 VALUE='20K',
 PRIM_FILE='./archive_libs/logical/q_res/chips/chips.prt';

PART_NAME
 R1059 'Q_RES_0201LF-1K,1%,1/20W,EMPTY,CS21001FE07':;

SECTION_NUMBER 1
 '@T6G_MB_LIB.T6G(SCH_1):PAGE419_I70@PURE_QUANTA.Q_RES(CHIPS)':
 C_PATH='@t6g_mb_lib.t6g(sch_1):page419_i70@pure_quanta.q_res(chips)',
 P_PATH='@t6g_mb_lib.t6g(sch_1):page298_i70@pure_quanta.q_res(chips)',
 PATH='I70',
 DRAWING='@T6G_MB_LIB.T6G(SCH_1):PAGE419',
 WATTAGE='1/20W',
 TOLERANCE='1%',
 MATERIAL='EMPTY',
 PHYS_PAGE='298',
 XY='(-2850,5875)',
 ROT='0',
 VER='2',
 PACK_TYPE='0201LF',
 LOCATION='R1059',
 CDS_LIB='pure_quanta',
 CDS_PART_NAME='Q_RES_0201LF-1K,1%,1/20W,EMPTY,CS21001FE07',
 PART_NUMBER='CS21001FE07',
 VALUE='1K',
 PRIM_FILE='./archive_libs/logical/q_res/chips/chips.prt';

PART_NAME
 R1060 'Q_RES_0201LF-1K,1%,1/20W,CHIP,CS21001FE07':;

SECTION_NUMBER 1
 '@T6G_MB_LIB.T6G(SCH_1):PAGE419_I69@PURE_QUANTA.Q_RES(CHIPS)':
 C_PATH='@t6g_mb_lib.t6g(sch_1):page419_i69@pure_quanta.q_res(chips)',
 P_PATH='@t6g_mb_lib.t6g(sch_1):page298_i69@pure_quanta.q_res(chips)',
 PATH='I69',
 DRAWING='@T6G_MB_LIB.T6G(SCH_1):PAGE419',
 WATTAGE='1/20W',
 TOLERANCE='1%',
 MATERIAL='CHIP',
 PHYS_PAGE='298',
 XY='(-2850,5125)',
 ROT='0',
 VER='2',
 PACK_TYPE='0201LF',
 LOCATION='R1060',
 CDS_LIB='pure_quanta',
 CDS_PART_NAME='Q_RES_0201LF-1K,1%,1/20W,CHIP,CS21001FE07',
 PART_NUMBER='CS21001FE07',
 VALUE='1K',
 PRIM_FILE='./archive_libs/logical/q_res/chips/chips.prt';

PART_NAME
 R1061 'Q_RES_0201LF-10K,1%,1/20W,CHIP,CS31001FE17':;

SECTION_NUMBER 1
 '@T6G_MB_LIB.T6G(SCH_1):PAGE419_I77@PURE_QUANTA.Q_RES(CHIPS)':
 C_PATH='@t6g_mb_lib.t6g(sch_1):page419_i77@pure_quanta.q_res(chips)',
 P_PATH='@t6g_mb_lib.t6g(sch_1):page298_i77@pure_quanta.q_res(chips)',
 PATH='I77',
 DRAWING='@T6G_MB_LIB.T6G(SCH_1):PAGE419',
 WATTAGE='1/20W',
 TOLERANCE='1%',
 MATERIAL='CHIP',
 PHYS_PAGE='298',
 XY='(-1325,5125)',
 ROT='0',
 VER='2',
 PACK_TYPE='0201LF',
 LOCATION='R1061',
 CDS_LIB='pure_quanta',
 CDS_PART_NAME='Q_RES_0201LF-10K,1%,1/20W,CHIP,CS31001FE17',
 PART_NUMBER='CS31001FE17',
 VALUE='10K',
 PRIM_FILE='./archive_libs/logical/q_res/chips/chips.prt';

PART_NAME
 R1062 'Q_RES_0201LF-10K,1%,1/20W,CHIP,CS31001FE17':;

SECTION_NUMBER 1
 '@T6G_MB_LIB.T6G(SCH_1):PAGE419_I76@PURE_QUANTA.Q_RES(CHIPS)':
 C_PATH='@t6g_mb_lib.t6g(sch_1):page419_i76@pure_quanta.q_res(chips)',
 P_PATH='@t6g_mb_lib.t6g(sch_1):page298_i76@pure_quanta.q_res(chips)',
 PATH='I76',
 DRAWING='@T6G_MB_LIB.T6G(SCH_1):PAGE419',
 WATTAGE='1/20W',
 TOLERANCE='1%',
 MATERIAL='CHIP',
 PHYS_PAGE='298',
 XY='(-1500,5125)',
 ROT='2',
 VER='2',
 PACK_TYPE='0201LF',
 LOCATION='R1062',
 CDS_LIB='pure_quanta',
 CDS_PART_NAME='Q_RES_0201LF-10K,1%,1/20W,CHIP,CS31001FE17',
 PART_NUMBER='CS31001FE17',
 VALUE='10K',
 PRIM_FILE='./archive_libs/logical/q_res/chips/chips.prt';

PART_NAME
 R1063 'Q_RES_0201LF-4.7K,5%,1/20W,EMPTY,CS24701JE04':;

SECTION_NUMBER 1
 '@T6G_MB_LIB.T6G(SCH_1):PAGE419_I5@PURE_QUANTA.Q_RES(CHIPS)':
 C_PATH='@t6g_mb_lib.t6g(sch_1):page419_i5@pure_quanta.q_res(chips)',
 P_PATH='@t6g_mb_lib.t6g(sch_1):page298_i5@pure_quanta.q_res(chips)',
 PATH='I5',
 DRAWING='@T6G_MB_LIB.T6G(SCH_1):PAGE419',
 WATTAGE='1/20W',
 TOLERANCE='5%',
 MATERIAL='EMPTY',
 PHYS_PAGE='298',
 XY='(-9000,4025)',
 ROT='0',
 VER='2',
 PACK_TYPE='0201LF',
 LOCATION='R1063',
 CDS_LIB='pure_quanta',
 CDS_PART_NAME='Q_RES_0201LF-4.7K,5%,1/20W,EMPTY,CS24701JE04',
 PART_NUMBER='CS24701JE04',
 VALUE='4.7K',
 PRIM_FILE='./archive_libs/logical/q_res/chips/chips.prt';

PART_NAME
 R1064 'Q_RES_0201LF-200,1%,1/20W,CHIP,CS12001FE12':;

SECTION_NUMBER 1
 '@T6G_MB_LIB.T6G(SCH_1):PAGE419_I102@PURE_QUANTA.Q_RES(CHIPS)':
 C_PATH='@t6g_mb_lib.t6g(sch_1):page419_i102@pure_quanta.q_res(chips)',
 P_PATH='@t6g_mb_lib.t6g(sch_1):page298_i102@pure_quanta.q_res(chips)',
 PATH='I102',
 DRAWING='@T6G_MB_LIB.T6G(SCH_1):PAGE419',
 WATTAGE='1/20W',
 TOLERANCE='1%',
 MATERIAL='CHIP',
 PHYS_PAGE='298',
 XY='(-9000,3350)',
 ROT='0',
 VER='2',
 PACK_TYPE='0201LF',
 LOCATION='R1064',
 CDS_LIB='pure_quanta',
 CDS_PART_NAME='Q_RES_0201LF-200,1%,1/20W,CHIP,CS12001FE12',
 PART_NUMBER='CS12001FE12',
 VALUE='200',
 PRIM_FILE='./archive_libs/logical/q_res/chips/chips.prt';

PART_NAME
 R1065 'Q_RES_0201LF-4.7K,5%,1/20W,EMPTY,CS24701JE04':;

SECTION_NUMBER 1
 '@T6G_MB_LIB.T6G(SCH_1):PAGE419_I78@PURE_QUANTA.Q_RES(CHIPS)':
 C_PATH='@t6g_mb_lib.t6g(sch_1):page419_i78@pure_quanta.q_res(chips)',
 P_PATH='@t6g_mb_lib.t6g(sch_1):page298_i78@pure_quanta.q_res(chips)',
 PATH='I78',
 DRAWING='@T6G_MB_LIB.T6G(SCH_1):PAGE419',
 WATTAGE='1/20W',
 TOLERANCE='5%',
 MATERIAL='EMPTY',
 PHYS_PAGE='298',
 XY='(-1500,5950)',
 ROT='2',
 VER='2',
 PACK_TYPE='0201LF',
 LOCATION='R1065',
 CDS_LIB='pure_quanta',
 CDS_PART_NAME='Q_RES_0201LF-4.7K,5%,1/20W,EMPTY,CS24701JE04',
 PART_NUMBER='CS24701JE04',
 VALUE='4.7K',
 PRIM_FILE='./archive_libs/logical/q_res/chips/chips.prt';

PART_NAME
 R1066 'Q_RES_0201LF-4.7K,5%,1/20W,EMPTY,CS24701JE04':;

SECTION_NUMBER 1
 '@T6G_MB_LIB.T6G(SCH_1):PAGE419_I42@PURE_QUANTA.Q_RES(CHIPS)':
 C_PATH='@t6g_mb_lib.t6g(sch_1):page419_i42@pure_quanta.q_res(chips)',
 P_PATH='@t6g_mb_lib.t6g(sch_1):page298_i42@pure_quanta.q_res(chips)',
 PATH='I42',
 DRAWING='@T6G_MB_LIB.T6G(SCH_1):PAGE419',
 WATTAGE='1/20W',
 TOLERANCE='5%',
 MATERIAL='EMPTY',
 PHYS_PAGE='298',
 XY='(-7450,5900)',
 ROT='0',
 VER='2',
 PACK_TYPE='0201LF',
 LOCATION='R1066',
 CDS_LIB='pure_quanta',
 CDS_PART_NAME='Q_RES_0201LF-4.7K,5%,1/20W,EMPTY,CS24701JE04',
 PART_NUMBER='CS24701JE04',
 VALUE='4.7K',
 PRIM_FILE='./archive_libs/logical/q_res/chips/chips.prt';

PART_NAME
 R1067 'Q_RES_0201LF-0,5%,1/20W,CHIP,CS00001JE10':;

SECTION_NUMBER 1
 '@T6G_MB_LIB.T6G(SCH_1):PAGE419_I29@PURE_QUANTA.Q_RES(CHIPS)':
 C_PATH='@t6g_mb_lib.t6g(sch_1):page419_i29@pure_quanta.q_res(chips)',
 P_PATH='@t6g_mb_lib.t6g(sch_1):page298_i29@pure_quanta.q_res(chips)',
 PATH='I29',
 DRAWING='@T6G_MB_LIB.T6G(SCH_1):PAGE419',
 WATTAGE='1/20W',
 TOLERANCE='5%',
 MATERIAL='CHIP',
 PHYS_PAGE='298',
 XY='(-6375,2800)',
 ROT='0',
 VER='1',
 PACK_TYPE='0201LF',
 LOCATION='R1067',
 CDS_LIB='pure_quanta',
 CDS_PART_NAME='Q_RES_0201LF-0,5%,1/20W,CHIP,CS00001JE10',
 PART_NUMBER='CS00001JE10',
 VALUE='0',
 PRIM_FILE='./archive_libs/logical/q_res/chips/chips.prt';

PART_NAME
 R1068 'Q_RES_0201LF-0,5%,1/20W,CHIP,CS00001JE10':;

SECTION_NUMBER 1
 '@T6G_MB_LIB.T6G(SCH_1):PAGE419_I30@PURE_QUANTA.Q_RES(CHIPS)':
 C_PATH='@t6g_mb_lib.t6g(sch_1):page419_i30@pure_quanta.q_res(chips)',
 P_PATH='@t6g_mb_lib.t6g(sch_1):page298_i30@pure_quanta.q_res(chips)',
 PATH='I30',
 DRAWING='@T6G_MB_LIB.T6G(SCH_1):PAGE419',
 WATTAGE='1/20W',
 TOLERANCE='5%',
 MATERIAL='CHIP',
 PHYS_PAGE='298',
 XY='(-6375,2700)',
 ROT='0',
 VER='1',
 PACK_TYPE='0201LF',
 LOCATION='R1068',
 CDS_LIB='pure_quanta',
 CDS_PART_NAME='Q_RES_0201LF-0,5%,1/20W,CHIP,CS00001JE10',
 PART_NUMBER='CS00001JE10',
 VALUE='0',
 PRIM_FILE='./archive_libs/logical/q_res/chips/chips.prt';

PART_NAME
 R1069 'Q_RES_0201LF-4.7K,5%,1/20W,EMPTY,CS24701JE04':;

SECTION_NUMBER 1
 '@T6G_MB_LIB.T6G(SCH_1):PAGE419_I10@PURE_QUANTA.Q_RES(CHIPS)':
 C_PATH='@t6g_mb_lib.t6g(sch_1):page419_i10@pure_quanta.q_res(chips)',
 P_PATH='@t6g_mb_lib.t6g(sch_1):page298_i10@pure_quanta.q_res(chips)',
 PATH='I10',
 DRAWING='@T6G_MB_LIB.T6G(SCH_1):PAGE419',
 WATTAGE='1/20W',
 TOLERANCE='5%',
 MATERIAL='EMPTY',
 PHYS_PAGE='298',
 XY='(-8975,5900)',
 ROT='0',
 VER='2',
 PACK_TYPE='0201LF',
 LOCATION='R1069',
 CDS_LIB='pure_quanta',
 CDS_PART_NAME='Q_RES_0201LF-4.7K,5%,1/20W,EMPTY,CS24701JE04',
 PART_NUMBER='CS24701JE04',
 VALUE='4.7K',
 PRIM_FILE='./archive_libs/logical/q_res/chips/chips.prt';

PART_NAME
 R1070 'Q_RES_0201LF-10K,1%,1/20W,CHIP,CS31001FE17':;

SECTION_NUMBER 1
 '@T6G_MB_LIB.T6G(SCH_1):PAGE419_I7@PURE_QUANTA.Q_RES(CHIPS)':
 C_PATH='@t6g_mb_lib.t6g(sch_1):page419_i7@pure_quanta.q_res(chips)',
 P_PATH='@t6g_mb_lib.t6g(sch_1):page298_i7@pure_quanta.q_res(chips)',
 PATH='I7',
 DRAWING='@T6G_MB_LIB.T6G(SCH_1):PAGE419',
 WATTAGE='1/20W',
 TOLERANCE='1%',
 MATERIAL='CHIP',
 PHYS_PAGE='298',
 XY='(-8975,4950)',
 ROT='0',
 VER='2',
 PACK_TYPE='0201LF',
 LOCATION='R1070',
 CDS_LIB='pure_quanta',
 CDS_PART_NAME='Q_RES_0201LF-10K,1%,1/20W,CHIP,CS31001FE17',
 PART_NUMBER='CS31001FE17',
 VALUE='10K',
 PRIM_FILE='./archive_libs/logical/q_res/chips/chips.prt';

PART_NAME
 R1071 'Q_RES_0402LF-4.7K,5%,1/16W,EMPTY,CS24702JB10':;

SECTION_NUMBER 1
 '@T6G_MB_LIB.T6G(SCH_1):PAGE82_I38@PURE_QUANTA.Q_RES(CHIPS)':
 C_PATH='@t6g_mb_lib.t6g(sch_1):page82_i38@pure_quanta.q_res(chips)',
 P_PATH='@t6g_mb_lib.t6g(sch_1):page83_i38@pure_quanta.q_res(chips)',
 PATH='I38',
 DRAWING='@T6G_MB_LIB.T6G(SCH_1):PAGE82',
 WATTAGE='1/16W',
 TOLERANCE='5%',
 MATERIAL='EMPTY',
 PHYS_PAGE='83',
 XY='(-7050,3650)',
 ROT='0',
 VER='1',
 PACK_TYPE='0402LF',
 LOCATION='R1071',
 CDS_LIB='pure_quanta',
 CDS_PART_NAME='Q_RES_0402LF-4.7K,5%,1/16W,EMPTY,CS24702JB10',
 PART_NUMBER='CS24702JB10',
 VALUE='4.7K',
 PRIM_FILE='./archive_libs/logical/q_res/chips/chips.prt';

PART_NAME
 R1072 'Q_RES_0201LF-10K,1%,1/20W,CHIP,CS31001FE17':;

SECTION_NUMBER 1
 '@T6G_MB_LIB.T6G(SCH_1):PAGE419_I8@PURE_QUANTA.Q_RES(CHIPS)':
 C_PATH='@t6g_mb_lib.t6g(sch_1):page419_i8@pure_quanta.q_res(chips)',
 P_PATH='@t6g_mb_lib.t6g(sch_1):page298_i8@pure_quanta.q_res(chips)',
 PATH='I8',
 DRAWING='@T6G_MB_LIB.T6G(SCH_1):PAGE419',
 WATTAGE='1/20W',
 TOLERANCE='1%',
 MATERIAL='CHIP',
 PHYS_PAGE='298',
 XY='(-8675,4950)',
 ROT='0',
 VER='2',
 PACK_TYPE='0201LF',
 LOCATION='R1072',
 CDS_LIB='pure_quanta',
 CDS_PART_NAME='Q_RES_0201LF-10K,1%,1/20W,CHIP,CS31001FE17',
 PART_NUMBER='CS31001FE17',
 VALUE='10K',
 PRIM_FILE='./archive_libs/logical/q_res/chips/chips.prt';

PART_NAME
 R1073 'Q_RES_0201LF-4.7K,5%,1/20W,EMPTY,CS24701JE04':;

SECTION_NUMBER 1
 '@T6G_MB_LIB.T6G(SCH_1):PAGE419_I11@PURE_QUANTA.Q_RES(CHIPS)':
 C_PATH='@t6g_mb_lib.t6g(sch_1):page419_i11@pure_quanta.q_res(chips)',
 P_PATH='@t6g_mb_lib.t6g(sch_1):page298_i11@pure_quanta.q_res(chips)',
 PATH='I11',
 DRAWING='@T6G_MB_LIB.T6G(SCH_1):PAGE419',
 WATTAGE='1/20W',
 TOLERANCE='5%',
 MATERIAL='EMPTY',
 PHYS_PAGE='298',
 XY='(-8350,5900)',
 ROT='0',
 VER='2',
 PACK_TYPE='0201LF',
 LOCATION='R1073',
 CDS_LIB='pure_quanta',
 CDS_PART_NAME='Q_RES_0201LF-4.7K,5%,1/20W,EMPTY,CS24701JE04',
 PART_NUMBER='CS24701JE04',
 VALUE='4.7K',
 PRIM_FILE='./archive_libs/logical/q_res/chips/chips.prt';

PART_NAME
 R1074 'Q_RES_0201LF-4.7K,5%,1/20W,CHIP,CS24701JE04':;

SECTION_NUMBER 1
 '@T6G_MB_LIB.T6G(SCH_1):PAGE419_I9@PURE_QUANTA.Q_RES(CHIPS)':
 C_PATH='@t6g_mb_lib.t6g(sch_1):page419_i9@pure_quanta.q_res(chips)',
 P_PATH='@t6g_mb_lib.t6g(sch_1):page298_i9@pure_quanta.q_res(chips)',
 PATH='I9',
 DRAWING='@T6G_MB_LIB.T6G(SCH_1):PAGE419',
 WATTAGE='1/20W',
 TOLERANCE='5%',
 MATERIAL='CHIP',
 PHYS_PAGE='298',
 XY='(-8350,4950)',
 ROT='0',
 VER='2',
 PACK_TYPE='0201LF',
 LOCATION='R1074',
 CDS_LIB='pure_quanta',
 CDS_PART_NAME='Q_RES_0201LF-4.7K,5%,1/20W,CHIP,CS24701JE04',
 PART_NUMBER='CS24701JE04',
 VALUE='4.7K',
 PRIM_FILE='./archive_libs/logical/q_res/chips/chips.prt';

PART_NAME
 R1075 'Q_RES_0201LF-4.7K,5%,1/20W,EMPTY,CS24701JE04':;

SECTION_NUMBER 1
 '@T6G_MB_LIB.T6G(SCH_1):PAGE419_I40@PURE_QUANTA.Q_RES(CHIPS)':
 C_PATH='@t6g_mb_lib.t6g(sch_1):page419_i40@pure_quanta.q_res(chips)',
 P_PATH='@t6g_mb_lib.t6g(sch_1):page298_i40@pure_quanta.q_res(chips)',
 PATH='I40',
 DRAWING='@T6G_MB_LIB.T6G(SCH_1):PAGE419',
 WATTAGE='1/20W',
 TOLERANCE='5%',
 MATERIAL='EMPTY',
 PHYS_PAGE='298',
 XY='(-8050,5850)',
 ROT='0',
 VER='2',
 PACK_TYPE='0201LF',
 LOCATION='R1075',
 CDS_LIB='pure_quanta',
 CDS_PART_NAME='Q_RES_0201LF-4.7K,5%,1/20W,EMPTY,CS24701JE04',
 PART_NUMBER='CS24701JE04',
 VALUE='4.7K',
 PRIM_FILE='./archive_libs/logical/q_res/chips/chips.prt';

PART_NAME
 R1076 'Q_RES_0201LF-4.7K,5%,1/20W,CHIP,CS24701JE04':;

SECTION_NUMBER 1
 '@T6G_MB_LIB.T6G(SCH_1):PAGE419_I36@PURE_QUANTA.Q_RES(CHIPS)':
 C_PATH='@t6g_mb_lib.t6g(sch_1):page419_i36@pure_quanta.q_res(chips)',
 P_PATH='@t6g_mb_lib.t6g(sch_1):page298_i36@pure_quanta.q_res(chips)',
 PATH='I36',
 DRAWING='@T6G_MB_LIB.T6G(SCH_1):PAGE419',
 WATTAGE='1/20W',
 TOLERANCE='5%',
 MATERIAL='CHIP',
 PHYS_PAGE='298',
 XY='(-8050,4925)',
 ROT='0',
 VER='2',
 PACK_TYPE='0201LF',
 LOCATION='R1076',
 CDS_LIB='pure_quanta',
 CDS_PART_NAME='Q_RES_0201LF-4.7K,5%,1/20W,CHIP,CS24701JE04',
 PART_NUMBER='CS24701JE04',
 VALUE='4.7K',
 PRIM_FILE='./archive_libs/logical/q_res/chips/chips.prt';

PART_NAME
 R1077 'Q_RES_0201LF-4.7K,5%,1/20W,EMPTY,CS24701JE04':;

SECTION_NUMBER 1
 '@T6G_MB_LIB.T6G(SCH_1):PAGE419_I41@PURE_QUANTA.Q_RES(CHIPS)':
 C_PATH='@t6g_mb_lib.t6g(sch_1):page419_i41@pure_quanta.q_res(chips)',
 P_PATH='@t6g_mb_lib.t6g(sch_1):page298_i41@pure_quanta.q_res(chips)',
 PATH='I41',
 DRAWING='@T6G_MB_LIB.T6G(SCH_1):PAGE419',
 WATTAGE='1/20W',
 TOLERANCE='5%',
 MATERIAL='EMPTY',
 PHYS_PAGE='298',
 XY='(-7750,5875)',
 ROT='0',
 VER='2',
 PACK_TYPE='0201LF',
 LOCATION='R1077',
 CDS_LIB='pure_quanta',
 CDS_PART_NAME='Q_RES_0201LF-4.7K,5%,1/20W,EMPTY,CS24701JE04',
 PART_NUMBER='CS24701JE04',
 VALUE='4.7K',
 PRIM_FILE='./archive_libs/logical/q_res/chips/chips.prt';

PART_NAME
 R1078 'Q_RES_0201LF-4.7K,5%,1/20W,CHIP,CS24701JE04':;

SECTION_NUMBER 1
 '@T6G_MB_LIB.T6G(SCH_1):PAGE419_I37@PURE_QUANTA.Q_RES(CHIPS)':
 C_PATH='@t6g_mb_lib.t6g(sch_1):page419_i37@pure_quanta.q_res(chips)',
 P_PATH='@t6g_mb_lib.t6g(sch_1):page298_i37@pure_quanta.q_res(chips)',
 PATH='I37',
 DRAWING='@T6G_MB_LIB.T6G(SCH_1):PAGE419',
 WATTAGE='1/20W',
 TOLERANCE='5%',
 MATERIAL='CHIP',
 PHYS_PAGE='298',
 XY='(-7750,4925)',
 ROT='0',
 VER='2',
 PACK_TYPE='0201LF',
 LOCATION='R1078',
 CDS_LIB='pure_quanta',
 CDS_PART_NAME='Q_RES_0201LF-4.7K,5%,1/20W,CHIP,CS24701JE04',
 PART_NUMBER='CS24701JE04',
 VALUE='4.7K',
 PRIM_FILE='./archive_libs/logical/q_res/chips/chips.prt';

PART_NAME
 R1079 'Q_RES_0201LF-4.7K,5%,1/20W,CHIP,CS24701JE04':;

SECTION_NUMBER 1
 '@T6G_MB_LIB.T6G(SCH_1):PAGE419_I39@PURE_QUANTA.Q_RES(CHIPS)':
 C_PATH='@t6g_mb_lib.t6g(sch_1):page419_i39@pure_quanta.q_res(chips)',
 P_PATH='@t6g_mb_lib.t6g(sch_1):page298_i39@pure_quanta.q_res(chips)',
 PATH='I39',
 DRAWING='@T6G_MB_LIB.T6G(SCH_1):PAGE419',
 WATTAGE='1/20W',
 TOLERANCE='5%',
 MATERIAL='CHIP',
 PHYS_PAGE='298',
 XY='(-7450,4900)',
 ROT='0',
 VER='2',
 PACK_TYPE='0201LF',
 LOCATION='R1079',
 CDS_LIB='pure_quanta',
 CDS_PART_NAME='Q_RES_0201LF-4.7K,5%,1/20W,CHIP,CS24701JE04',
 PART_NUMBER='CS24701JE04',
 VALUE='4.7K',
 PRIM_FILE='./archive_libs/logical/q_res/chips/chips.prt';

PART_NAME
 R1080 'Q_RES_0201LF-4.7K,5%,1/20W,CHIP,CS24701JE04':;

SECTION_NUMBER 1
 '@T6G_MB_LIB.T6G(SCH_1):PAGE419_I51@PURE_QUANTA.Q_RES(CHIPS)':
 C_PATH='@t6g_mb_lib.t6g(sch_1):page419_i51@pure_quanta.q_res(chips)',
 P_PATH='@t6g_mb_lib.t6g(sch_1):page298_i51@pure_quanta.q_res(chips)',
 PATH='I51',
 DRAWING='@T6G_MB_LIB.T6G(SCH_1):PAGE419',
 WATTAGE='1/20W',
 TOLERANCE='5%',
 MATERIAL='CHIP',
 PHYS_PAGE='298',
 XY='(-5050,5975)',
 ROT='0',
 VER='2',
 PACK_TYPE='0201LF',
 LOCATION='R1080',
 CDS_LIB='pure_quanta',
 CDS_PART_NAME='Q_RES_0201LF-4.7K,5%,1/20W,CHIP,CS24701JE04',
 PART_NUMBER='CS24701JE04',
 VALUE='4.7K',
 PRIM_FILE='./archive_libs/logical/q_res/chips/chips.prt';

PART_NAME
 R1081 'Q_RES_0201LF-1K,1%,1/20W,EMPTY,CS21001FE07':;

SECTION_NUMBER 1
 '@T6G_MB_LIB.T6G(SCH_1):PAGE420_I19@PURE_QUANTA.Q_RES(CHIPS)':
 C_PATH='@t6g_mb_lib.t6g(sch_1):page420_i19@pure_quanta.q_res(chips)',
 P_PATH='@t6g_mb_lib.t6g(sch_1):page299_i19@pure_quanta.q_res(chips)',
 PATH='I19',
 DRAWING='@T6G_MB_LIB.T6G(SCH_1):PAGE420',
 WATTAGE='1/20W',
 TOLERANCE='1%',
 MATERIAL='EMPTY',
 PHYS_PAGE='299',
 XY='(-8700,3725)',
 ROT='0',
 VER='2',
 PACK_TYPE='0201LF',
 LOCATION='R1081',
 CDS_LIB='pure_quanta',
 CDS_PART_NAME='Q_RES_0201LF-1K,1%,1/20W,EMPTY,CS21001FE07',
 PART_NUMBER='CS21001FE07',
 VALUE='1K',
 PRIM_FILE='./archive_libs/logical/q_res/chips/chips.prt';

PART_NAME
 R1082 'Q_RES_0201LF-200,1%,1/20W,CHIP,CS12001FE12':;

SECTION_NUMBER 1
 '@T6G_MB_LIB.T6G(SCH_1):PAGE420_I18@PURE_QUANTA.Q_RES(CHIPS)':
 C_PATH='@t6g_mb_lib.t6g(sch_1):page420_i18@pure_quanta.q_res(chips)',
 P_PATH='@t6g_mb_lib.t6g(sch_1):page299_i18@pure_quanta.q_res(chips)',
 PATH='I18',
 DRAWING='@T6G_MB_LIB.T6G(SCH_1):PAGE420',
 WATTAGE='1/20W',
 TOLERANCE='1%',
 MATERIAL='CHIP',
 PHYS_PAGE='299',
 XY='(-7675,3175)',
 ROT='0',
 VER='2',
 PACK_TYPE='0201LF',
 LOCATION='R1082',
 CDS_LIB='pure_quanta',
 CDS_PART_NAME='Q_RES_0201LF-200,1%,1/20W,CHIP,CS12001FE12',
 PART_NUMBER='CS12001FE12',
 VALUE='200',
 PRIM_FILE='./archive_libs/logical/q_res/chips/chips.prt';

PART_NAME
 R1083 'Q_RES_0201LF-0,5%,1/20W,CHIP,CS00001JE10':;

SECTION_NUMBER 1
 '@T6G_MB_LIB.T6G(SCH_1):PAGE420_I13@PURE_QUANTA.Q_RES(CHIPS)':
 C_PATH='@t6g_mb_lib.t6g(sch_1):page420_i13@pure_quanta.q_res(chips)',
 P_PATH='@t6g_mb_lib.t6g(sch_1):page299_i13@pure_quanta.q_res(chips)',
 PATH='I13',
 DRAWING='@T6G_MB_LIB.T6G(SCH_1):PAGE420',
 WATTAGE='1/20W',
 TOLERANCE='5%',
 MATERIAL='CHIP',
 PHYS_PAGE='299',
 XY='(-1475,1075)',
 ROT='0',
 VER='2',
 PACK_TYPE='0201LF',
 LOCATION='R1083',
 CDS_LIB='pure_quanta',
 CDS_PART_NAME='Q_RES_0201LF-0,5%,1/20W,CHIP,CS00001JE10',
 PART_NUMBER='CS00001JE10',
 VALUE='0',
 PRIM_FILE='./archive_libs/logical/q_res/chips/chips.prt';

PART_NAME
 R1084 'Q_RES_0201LF-0,5%,1/20W,CHIP,CS00001JE10':;

SECTION_NUMBER 1
 '@T6G_MB_LIB.T6G(SCH_1):PAGE420_I14@PURE_QUANTA.Q_RES(CHIPS)':
 C_PATH='@t6g_mb_lib.t6g(sch_1):page420_i14@pure_quanta.q_res(chips)',
 P_PATH='@t6g_mb_lib.t6g(sch_1):page299_i14@pure_quanta.q_res(chips)',
 PATH='I14',
 DRAWING='@T6G_MB_LIB.T6G(SCH_1):PAGE420',
 WATTAGE='1/20W',
 TOLERANCE='5%',
 MATERIAL='CHIP',
 PHYS_PAGE='299',
 XY='(-1325,1625)',
 ROT='0',
 VER='2',
 PACK_TYPE='0201LF',
 LOCATION='R1084',
 CDS_LIB='pure_quanta',
 CDS_PART_NAME='Q_RES_0201LF-0,5%,1/20W,CHIP,CS00001JE10',
 PART_NUMBER='CS00001JE10',
 VALUE='0',
 PRIM_FILE='./archive_libs/logical/q_res/chips/chips.prt';

PART_NAME
 R1085 'Q_RES_0201LF-1K,1%,1/20W,CHIP,CS21001FE07':;

SECTION_NUMBER 1
 '@T6G_MB_LIB.T6G(SCH_1):PAGE421_I18@PURE_QUANTA.Q_RES(CHIPS)':
 C_PATH='@t6g_mb_lib.t6g(sch_1):page421_i18@pure_quanta.q_res(chips)',
 P_PATH='@t6g_mb_lib.t6g(sch_1):page300_i18@pure_quanta.q_res(chips)',
 PATH='I18',
 DRAWING='@T6G_MB_LIB.T6G(SCH_1):PAGE421',
 WATTAGE='1/20W',
 TOLERANCE='1%',
 MATERIAL='CHIP',
 PHYS_PAGE='300',
 XY='(-4100,5450)',
 ROT='0',
 VER='2',
 PACK_TYPE='0201LF',
 LOCATION='R1085',
 CDS_LIB='pure_quanta',
 CDS_PART_NAME='Q_RES_0201LF-1K,1%,1/20W,CHIP,CS21001FE07',
 PART_NUMBER='CS21001FE07',
 VALUE='1K',
 PRIM_FILE='./archive_libs/logical/q_res/chips/chips.prt';

PART_NAME
 R1086 'Q_RES_0402LF-0,5%,1/16W,EMPTY,CS00002JB13':;

SECTION_NUMBER 1
 '@T6G_MB_LIB.T6G(SCH_1):PAGE433_I2@PURE_QUANTA.Q_RES(CHIPS)':
 C_PATH='@t6g_mb_lib.t6g(sch_1):page433_i2@pure_quanta.q_res(chips)',
 P_PATH='@t6g_mb_lib.t6g(sch_1):page312_i2@pure_quanta.q_res(chips)',
 PATH='I2',
 DRAWING='@T6G_MB_LIB.T6G(SCH_1):PAGE433',
 SEC_TYPE='0402LF',
 WATTAGE='1/16W',
 TOLERANCE='5%',
 MATERIAL='EMPTY',
 PHYS_PAGE='312',
 XY='(-7850,3950)',
 ROT='0',
 VER='1',
 PACK_TYPE='0402LF',
 LOCATION='R1086',
 SEC='1',
 CDS_LIB='pure_quanta',
 CDS_PART_NAME='Q_RES_0402LF-0,5%,1/16W,EMPTY,CS00002JB13',
 PART_NUMBER='CS00002JB13',
 VALUE='0',
 PRIM_FILE='./archive_libs/logical/q_res/chips/chips.prt';

PART_NAME
 R1087 'Q_RES_0402LF-0,5%,1/16W,EMPTY,CS00002JB13':;

SECTION_NUMBER 1
 '@T6G_MB_LIB.T6G(SCH_1):PAGE433_I1@PURE_QUANTA.Q_RES(CHIPS)':
 C_PATH='@t6g_mb_lib.t6g(sch_1):page433_i1@pure_quanta.q_res(chips)',
 P_PATH='@t6g_mb_lib.t6g(sch_1):page312_i1@pure_quanta.q_res(chips)',
 PATH='I1',
 DRAWING='@T6G_MB_LIB.T6G(SCH_1):PAGE433',
 SEC_TYPE='0402LF',
 WATTAGE='1/16W',
 TOLERANCE='5%',
 MATERIAL='EMPTY',
 PHYS_PAGE='312',
 XY='(-7850,3750)',
 ROT='0',
 VER='1',
 PACK_TYPE='0402LF',
 LOCATION='R1087',
 SEC='1',
 CDS_LIB='pure_quanta',
 CDS_PART_NAME='Q_RES_0402LF-0,5%,1/16W,EMPTY,CS00002JB13',
 PART_NUMBER='CS00002JB13',
 VALUE='0',
 PRIM_FILE='./archive_libs/logical/q_res/chips/chips.prt';

PART_NAME
 R1088 'Q_RES_0201LF-0,5%,1/20W,CHIP,CS00001JE10':;

SECTION_NUMBER 1
 '@T6G_MB_LIB.T6G(SCH_1):PAGE430_I56@PURE_QUANTA.Q_RES(CHIPS)':
 C_PATH='@t6g_mb_lib.t6g(sch_1):page430_i56@pure_quanta.q_res(chips)',
 P_PATH='@t6g_mb_lib.t6g(sch_1):page309_i56@pure_quanta.q_res(chips)',
 PATH='I56',
 DRAWING='@T6G_MB_LIB.T6G(SCH_1):PAGE430',
 SEC_TYPE='0201LF',
 WATTAGE='1/20W',
 TOLERANCE='5%',
 MATERIAL='CHIP',
 PHYS_PAGE='309',
 XY='(-2575,2200)',
 ROT='0',
 VER='1',
 PACK_TYPE='0201LF',
 LOCATION='R1088',
 SEC='1',
 CDS_LIB='pure_quanta',
 CDS_PART_NAME='Q_RES_0201LF-0,5%,1/20W,CHIP,CS00001JE10',
 PART_NUMBER='CS00001JE10',
 VALUE='0',
 PRIM_FILE='./archive_libs/logical/q_res/chips/chips.prt';

PART_NAME
 R1089 'Q_RES_0402LF-2.2K,5%,1/16W,CHIP,CS22202JB07':;

SECTION_NUMBER 1
 '@T6G_MB_LIB.T6G(SCH_1):PAGE252_I37@PURE_QUANTA.Q_RES(CHIPS)':
 C_PATH='@t6g_mb_lib.t6g(sch_1):page252_i37@pure_quanta.q_res(chips)',
 P_PATH='@t6g_mb_lib.t6g(sch_1):page250_i37@pure_quanta.q_res(chips)',
 PATH='I37',
 DRAWING='@T6G_MB_LIB.T6G(SCH_1):PAGE252',
 WATTAGE='1/16W',
 TOLERANCE='5%',
 MATERIAL='CHIP',
 PHYS_PAGE='250',
 XY='(-2125,575)',
 ROT='0',
 VER='1',
 PACK_TYPE='0402LF',
 LOCATION='R1089',
 CDS_LIB='pure_quanta',
 CDS_PART_NAME='Q_RES_0402LF-2.2K,5%,1/16W,CHIP,CS22202JB07',
 PART_NUMBER='CS22202JB07',
 VALUE='2.2K',
 PRIM_FILE='./archive_libs/logical/q_res/chips/chips.prt';

PART_NAME
 R1090 'Q_RES_0402LF-2.2K,5%,1/16W,CHIP,CS22202JB07':;

SECTION_NUMBER 1
 '@T6G_MB_LIB.T6G(SCH_1):PAGE252_I38@PURE_QUANTA.Q_RES(CHIPS)':
 C_PATH='@t6g_mb_lib.t6g(sch_1):page252_i38@pure_quanta.q_res(chips)',
 P_PATH='@t6g_mb_lib.t6g(sch_1):page250_i38@pure_quanta.q_res(chips)',
 PATH='I38',
 DRAWING='@T6G_MB_LIB.T6G(SCH_1):PAGE252',
 WATTAGE='1/16W',
 TOLERANCE='5%',
 MATERIAL='CHIP',
 PHYS_PAGE='250',
 XY='(-2125,525)',
 ROT='0',
 VER='1',
 PACK_TYPE='0402LF',
 LOCATION='R1090',
 CDS_LIB='pure_quanta',
 CDS_PART_NAME='Q_RES_0402LF-2.2K,5%,1/16W,CHIP,CS22202JB07',
 PART_NUMBER='CS22202JB07',
 VALUE='2.2K',
 PRIM_FILE='./archive_libs/logical/q_res/chips/chips.prt';

PART_NAME
 R1091 'Q_RES_0201LF-4.7K,5%,1/20W,EMPTY,CS24701JE04':;

SECTION_NUMBER 1
 '@T6G_MB_LIB.T6G(SCH_1):PAGE430_I50@PURE_QUANTA.Q_RES(CHIPS)':
 C_PATH='@t6g_mb_lib.t6g(sch_1):page430_i50@pure_quanta.q_res(chips)',
 P_PATH='@t6g_mb_lib.t6g(sch_1):page309_i50@pure_quanta.q_res(chips)',
 PATH='I50',
 DRAWING='@T6G_MB_LIB.T6G(SCH_1):PAGE430',
 WATTAGE='1/20W',
 TOLERANCE='5%',
 MATERIAL='EMPTY',
 PHYS_PAGE='309',
 XY='(-5025,5550)',
 ROT='0',
 VER='2',
 PACK_TYPE='0201LF',
 LOCATION='R1091',
 CDS_LIB='pure_quanta',
 CDS_PART_NAME='Q_RES_0201LF-4.7K,5%,1/20W,EMPTY,CS24701JE04',
 PART_NUMBER='CS24701JE04',
 VALUE='4.7K',
 PRIM_FILE='./archive_libs/logical/q_res/chips/chips.prt';

PART_NAME
 R1092 'Q_RES_0402LF-10M,1%,1/16W,EMPTY,CS61002FB02':;

SECTION_NUMBER 1
 '@T6G_MB_LIB.T6G(SCH_1):PAGE146_I39@PURE_QUANTA.Q_RES(CHIPS)':
 C_PATH='@t6g_mb_lib.t6g(sch_1):page146_i39@pure_quanta.q_res(chips)',
 P_PATH='@t6g_mb_lib.t6g(sch_1):page169_i39@pure_quanta.q_res(chips)',
 PATH='I39',
 DRAWING='@T6G_MB_LIB.T6G(SCH_1):PAGE146',
 WATTAGE='1/16W',
 TOLERANCE='1%',
 MATERIAL='EMPTY',
 PHYS_PAGE='169',
 XY='(-7900,1050)',
 ROT='0',
 VER='2',
 PACK_TYPE='0402LF',
 LOCATION='R1092',
 CDS_LIB='pure_quanta',
 CDS_PART_NAME='Q_RES_0402LF-10M,1%,1/16W,EMPTY,CS61002FB02',
 PART_NUMBER='CS61002FB02',
 VALUE='10M',
 PRIM_FILE='./archive_libs/logical/q_res/chips/chips.prt';

PART_NAME
 R1093 'Q_RES_0402LF-0,5%,1/16W,EMPTY,CS00002JB13':;

SECTION_NUMBER 1
 '@T6G_MB_LIB.T6G(SCH_1):PAGE433_I89@PURE_QUANTA.Q_RES(CHIPS)':
 C_PATH='@t6g_mb_lib.t6g(sch_1):page433_i89@pure_quanta.q_res(chips)',
 P_PATH='@t6g_mb_lib.t6g(sch_1):page312_i89@pure_quanta.q_res(chips)',
 PATH='I89',
 DRAWING='@T6G_MB_LIB.T6G(SCH_1):PAGE433',
 WATTAGE='1/16W',
 TOLERANCE='5%',
 MATERIAL='EMPTY',
 PHYS_PAGE='312',
 XY='(-8250,4275)',
 ROT='0',
 VER='2',
 PACK_TYPE='0402LF',
 LOCATION='R1093',
 CDS_LIB='pure_quanta',
 CDS_PART_NAME='Q_RES_0402LF-0,5%,1/16W,EMPTY,CS00002JB13',
 PART_NUMBER='CS00002JB13',
 VALUE='0',
 PRIM_FILE='./archive_libs/logical/q_res/chips/chips.prt';

PART_NAME
 R1094 'Q_RES_0603LF-0,5%,1/4W,EMPTY,CS00006J900':;

SECTION_NUMBER 1
 '@T6G_MB_LIB.T6G(SCH_1):PAGE433_I7@PURE_QUANTA.Q_RES(CHIPS)':
 C_PATH='@t6g_mb_lib.t6g(sch_1):page433_i7@pure_quanta.q_res(chips)',
 P_PATH='@t6g_mb_lib.t6g(sch_1):page312_i7@pure_quanta.q_res(chips)',
 PATH='I7',
 DRAWING='@T6G_MB_LIB.T6G(SCH_1):PAGE433',
 WATTAGE='1/4W',
 TOLERANCE='5%',
 MATERIAL='EMPTY',
 PHYS_PAGE='312',
 XY='(-4450,2950)',
 ROT='2',
 VER='2',
 PACK_TYPE='0603LF',
 LOCATION='R1094',
 CDS_LIB='pure_quanta',
 CDS_PART_NAME='Q_RES_0603LF-0,5%,1/4W,EMPTY,CS00006J900',
 PART_NUMBER='CS00006J900',
 VALUE='0',
 PRIM_FILE='./archive_libs/logical/q_res/chips/chips.prt';

PART_NAME
 R1095 'Q_RES_0603LF-0,5%,1/4W,CHIP,CS00006J900':;

SECTION_NUMBER 1
 '@T6G_MB_LIB.T6G(SCH_1):PAGE433_I36@PURE_QUANTA.Q_RES(CHIPS)':
 C_PATH='@t6g_mb_lib.t6g(sch_1):page433_i36@pure_quanta.q_res(chips)',
 P_PATH='@t6g_mb_lib.t6g(sch_1):page312_i36@pure_quanta.q_res(chips)',
 PATH='I36',
 DRAWING='@T6G_MB_LIB.T6G(SCH_1):PAGE433',
 WATTAGE='1/4W',
 TOLERANCE='5%',
 MATERIAL='CHIP',
 PHYS_PAGE='312',
 XY='(-4075,2675)',
 ROT='0',
 VER='1',
 PACK_TYPE='0603LF',
 LOCATION='R1095',
 CDS_LIB='pure_quanta',
 CDS_PART_NAME='Q_RES_0603LF-0,5%,1/4W,CHIP,CS00006J900',
 PART_NUMBER='CS00006J900',
 VALUE='0',
 PRIM_FILE='./archive_libs/logical/q_res/chips/chips.prt';

PART_NAME
 R1096 'Q_RES_0201LF-0,5%,1/20W,CHIP,CS00001JE10':;

SECTION_NUMBER 1
 '@T6G_MB_LIB.T6G(SCH_1):PAGE430_I55@PURE_QUANTA.Q_RES(CHIPS)':
 C_PATH='@t6g_mb_lib.t6g(sch_1):page430_i55@pure_quanta.q_res(chips)',
 P_PATH='@t6g_mb_lib.t6g(sch_1):page309_i55@pure_quanta.q_res(chips)',
 PATH='I55',
 DRAWING='@T6G_MB_LIB.T6G(SCH_1):PAGE430',
 WATTAGE='1/20W',
 TOLERANCE='5%',
 MATERIAL='CHIP',
 PHYS_PAGE='309',
 XY='(-2575,2100)',
 ROT='0',
 VER='1',
 PACK_TYPE='0201LF',
 LOCATION='R1096',
 CDS_LIB='pure_quanta',
 CDS_PART_NAME='Q_RES_0201LF-0,5%,1/20W,CHIP,CS00001JE10',
 PART_NUMBER='CS00001JE10',
 VALUE='0',
 PRIM_FILE='./archive_libs/logical/q_res/chips/chips.prt';

PART_NAME
 R1097 'Q_RES_0201LF-1K,1%,1/20W,CHIP,CS21001FE07':;

SECTION_NUMBER 1
 '@T6G_MB_LIB.T6G(SCH_1):PAGE430_I67@PURE_QUANTA.Q_RES(CHIPS)':
 C_PATH='@t6g_mb_lib.t6g(sch_1):page430_i67@pure_quanta.q_res(chips)',
 P_PATH='@t6g_mb_lib.t6g(sch_1):page309_i67@pure_quanta.q_res(chips)',
 PATH='I67',
 DRAWING='@T6G_MB_LIB.T6G(SCH_1):PAGE430',
 WATTAGE='1/20W',
 TOLERANCE='1%',
 MATERIAL='CHIP',
 PHYS_PAGE='309',
 XY='(-3475,6000)',
 ROT='0',
 VER='2',
 PACK_TYPE='0201LF',
 LOCATION='R1097',
 CDS_LIB='pure_quanta',
 CDS_PART_NAME='Q_RES_0201LF-1K,1%,1/20W,CHIP,CS21001FE07',
 PART_NUMBER='CS21001FE07',
 VALUE='1K',
 PRIM_FILE='./archive_libs/logical/q_res/chips/chips.prt';

PART_NAME
 R1098 'Q_RES_0201LF-1K,1%,1/20W,EMPTY,CS21001FE07':;

SECTION_NUMBER 1
 '@T6G_MB_LIB.T6G(SCH_1):PAGE430_I65@PURE_QUANTA.Q_RES(CHIPS)':
 C_PATH='@t6g_mb_lib.t6g(sch_1):page430_i65@pure_quanta.q_res(chips)',
 P_PATH='@t6g_mb_lib.t6g(sch_1):page309_i65@pure_quanta.q_res(chips)',
 PATH='I65',
 DRAWING='@T6G_MB_LIB.T6G(SCH_1):PAGE430',
 WATTAGE='1/20W',
 TOLERANCE='1%',
 MATERIAL='EMPTY',
 PHYS_PAGE='309',
 XY='(-3475,5225)',
 ROT='0',
 VER='2',
 PACK_TYPE='0201LF',
 LOCATION='R1098',
 CDS_LIB='pure_quanta',
 CDS_PART_NAME='Q_RES_0201LF-1K,1%,1/20W,EMPTY,CS21001FE07',
 PART_NUMBER='CS21001FE07',
 VALUE='1K',
 PRIM_FILE='./archive_libs/logical/q_res/chips/chips.prt';

PART_NAME
 R1099 'Q_RES_0201LF-1K,1%,1/20W,EMPTY,CS21001FE07':;

SECTION_NUMBER 1
 '@T6G_MB_LIB.T6G(SCH_1):PAGE430_I68@PURE_QUANTA.Q_RES(CHIPS)':
 C_PATH='@t6g_mb_lib.t6g(sch_1):page430_i68@pure_quanta.q_res(chips)',
 P_PATH='@t6g_mb_lib.t6g(sch_1):page309_i68@pure_quanta.q_res(chips)',
 PATH='I68',
 DRAWING='@T6G_MB_LIB.T6G(SCH_1):PAGE430',
 WATTAGE='1/20W',
 TOLERANCE='1%',
 MATERIAL='EMPTY',
 PHYS_PAGE='309',
 XY='(-3175,6000)',
 ROT='0',
 VER='2',
 PACK_TYPE='0201LF',
 LOCATION='R1099',
 CDS_LIB='pure_quanta',
 CDS_PART_NAME='Q_RES_0201LF-1K,1%,1/20W,EMPTY,CS21001FE07',
 PART_NUMBER='CS21001FE07',
 VALUE='1K',
 PRIM_FILE='./archive_libs/logical/q_res/chips/chips.prt';

PART_NAME
 R1100 'Q_RES_0201LF-20K,1%,1/20W,CHIP,CS32001FE00':;

SECTION_NUMBER 1
 '@T6G_MB_LIB.T6G(SCH_1):PAGE430_I66@PURE_QUANTA.Q_RES(CHIPS)':
 C_PATH='@t6g_mb_lib.t6g(sch_1):page430_i66@pure_quanta.q_res(chips)',
 P_PATH='@t6g_mb_lib.t6g(sch_1):page309_i66@pure_quanta.q_res(chips)',
 PATH='I66',
 DRAWING='@T6G_MB_LIB.T6G(SCH_1):PAGE430',
 WATTAGE='1/20W',
 TOLERANCE='1%',
 MATERIAL='CHIP',
 PHYS_PAGE='309',
 XY='(-3175,5225)',
 ROT='0',
 VER='2',
 PACK_TYPE='0201LF',
 LOCATION='R1100',
 CDS_LIB='pure_quanta',
 CDS_PART_NAME='Q_RES_0201LF-20K,1%,1/20W,CHIP,CS32001FE00',
 PART_NUMBER='CS32001FE00',
 VALUE='20K',
 PRIM_FILE='./archive_libs/logical/q_res/chips/chips.prt';

PART_NAME
 R1101 'Q_RES_0201LF-1K,1%,1/20W,EMPTY,CS21001FE07':;

SECTION_NUMBER 1
 '@T6G_MB_LIB.T6G(SCH_1):PAGE430_I70@PURE_QUANTA.Q_RES(CHIPS)':
 C_PATH='@t6g_mb_lib.t6g(sch_1):page430_i70@pure_quanta.q_res(chips)',
 P_PATH='@t6g_mb_lib.t6g(sch_1):page309_i70@pure_quanta.q_res(chips)',
 PATH='I70',
 DRAWING='@T6G_MB_LIB.T6G(SCH_1):PAGE430',
 WATTAGE='1/20W',
 TOLERANCE='1%',
 MATERIAL='EMPTY',
 PHYS_PAGE='309',
 XY='(-2825,5975)',
 ROT='0',
 VER='2',
 PACK_TYPE='0201LF',
 LOCATION='R1101',
 CDS_LIB='pure_quanta',
 CDS_PART_NAME='Q_RES_0201LF-1K,1%,1/20W,EMPTY,CS21001FE07',
 PART_NUMBER='CS21001FE07',
 VALUE='1K',
 PRIM_FILE='./archive_libs/logical/q_res/chips/chips.prt';

PART_NAME
 R1102 'Q_RES_0201LF-1K,1%,1/20W,CHIP,CS21001FE07':;

SECTION_NUMBER 1
 '@T6G_MB_LIB.T6G(SCH_1):PAGE430_I69@PURE_QUANTA.Q_RES(CHIPS)':
 C_PATH='@t6g_mb_lib.t6g(sch_1):page430_i69@pure_quanta.q_res(chips)',
 P_PATH='@t6g_mb_lib.t6g(sch_1):page309_i69@pure_quanta.q_res(chips)',
 PATH='I69',
 DRAWING='@T6G_MB_LIB.T6G(SCH_1):PAGE430',
 WATTAGE='1/20W',
 TOLERANCE='1%',
 MATERIAL='CHIP',
 PHYS_PAGE='309',
 XY='(-2825,5225)',
 ROT='0',
 VER='2',
 PACK_TYPE='0201LF',
 LOCATION='R1102',
 CDS_LIB='pure_quanta',
 CDS_PART_NAME='Q_RES_0201LF-1K,1%,1/20W,CHIP,CS21001FE07',
 PART_NUMBER='CS21001FE07',
 VALUE='1K',
 PRIM_FILE='./archive_libs/logical/q_res/chips/chips.prt';

PART_NAME
 R1103 'Q_RES_0201LF-10K,1%,1/20W,CHIP,CS31001FE17':;

SECTION_NUMBER 1
 '@T6G_MB_LIB.T6G(SCH_1):PAGE430_I74@PURE_QUANTA.Q_RES(CHIPS)':
 C_PATH='@t6g_mb_lib.t6g(sch_1):page430_i74@pure_quanta.q_res(chips)',
 P_PATH='@t6g_mb_lib.t6g(sch_1):page309_i74@pure_quanta.q_res(chips)',
 PATH='I74',
 DRAWING='@T6G_MB_LIB.T6G(SCH_1):PAGE430',
 WATTAGE='1/20W',
 TOLERANCE='1%',
 MATERIAL='CHIP',
 PHYS_PAGE='309',
 XY='(-1300,5225)',
 ROT='0',
 VER='2',
 PACK_TYPE='0201LF',
 LOCATION='R1103',
 CDS_LIB='pure_quanta',
 CDS_PART_NAME='Q_RES_0201LF-10K,1%,1/20W,CHIP,CS31001FE17',
 PART_NUMBER='CS31001FE17',
 VALUE='10K',
 PRIM_FILE='./archive_libs/logical/q_res/chips/chips.prt';

PART_NAME
 R1104 'Q_RES_0201LF-10K,1%,1/20W,CHIP,CS31001FE17':;

SECTION_NUMBER 1
 '@T6G_MB_LIB.T6G(SCH_1):PAGE430_I75@PURE_QUANTA.Q_RES(CHIPS)':
 C_PATH='@t6g_mb_lib.t6g(sch_1):page430_i75@pure_quanta.q_res(chips)',
 P_PATH='@t6g_mb_lib.t6g(sch_1):page309_i75@pure_quanta.q_res(chips)',
 PATH='I75',
 DRAWING='@T6G_MB_LIB.T6G(SCH_1):PAGE430',
 WATTAGE='1/20W',
 TOLERANCE='1%',
 MATERIAL='CHIP',
 PHYS_PAGE='309',
 XY='(-1475,5225)',
 ROT='2',
 VER='2',
 PACK_TYPE='0201LF',
 LOCATION='R1104',
 CDS_LIB='pure_quanta',
 CDS_PART_NAME='Q_RES_0201LF-10K,1%,1/20W,CHIP,CS31001FE17',
 PART_NUMBER='CS31001FE17',
 VALUE='10K',
 PRIM_FILE='./archive_libs/logical/q_res/chips/chips.prt';

PART_NAME
 R1105 'Q_RES_0201LF-4.7K,5%,1/20W,EMPTY,CS24701JE04':;

SECTION_NUMBER 1
 '@T6G_MB_LIB.T6G(SCH_1):PAGE430_I5@PURE_QUANTA.Q_RES(CHIPS)':
 C_PATH='@t6g_mb_lib.t6g(sch_1):page430_i5@pure_quanta.q_res(chips)',
 P_PATH='@t6g_mb_lib.t6g(sch_1):page309_i5@pure_quanta.q_res(chips)',
 PATH='I5',
 DRAWING='@T6G_MB_LIB.T6G(SCH_1):PAGE430',
 WATTAGE='1/20W',
 TOLERANCE='5%',
 MATERIAL='EMPTY',
 PHYS_PAGE='309',
 XY='(-8975,4125)',
 ROT='0',
 VER='2',
 PACK_TYPE='0201LF',
 LOCATION='R1105',
 CDS_LIB='pure_quanta',
 CDS_PART_NAME='Q_RES_0201LF-4.7K,5%,1/20W,EMPTY,CS24701JE04',
 PART_NUMBER='CS24701JE04',
 VALUE='4.7K',
 PRIM_FILE='./archive_libs/logical/q_res/chips/chips.prt';

PART_NAME
 R1106 'Q_RES_0201LF-200,1%,1/20W,CHIP,CS12001FE12':;

SECTION_NUMBER 1
 '@T6G_MB_LIB.T6G(SCH_1):PAGE430_I102@PURE_QUANTA.Q_RES(CHIPS)':
 C_PATH='@t6g_mb_lib.t6g(sch_1):page430_i102@pure_quanta.q_res(chips)',
 P_PATH='@t6g_mb_lib.t6g(sch_1):page309_i102@pure_quanta.q_res(chips)',
 PATH='I102',
 DRAWING='@T6G_MB_LIB.T6G(SCH_1):PAGE430',
 WATTAGE='1/20W',
 TOLERANCE='1%',
 MATERIAL='CHIP',
 PHYS_PAGE='309',
 XY='(-8975,3450)',
 ROT='0',
 VER='2',
 PACK_TYPE='0201LF',
 LOCATION='R1106',
 CDS_LIB='pure_quanta',
 CDS_PART_NAME='Q_RES_0201LF-200,1%,1/20W,CHIP,CS12001FE12',
 PART_NUMBER='CS12001FE12',
 VALUE='200',
 PRIM_FILE='./archive_libs/logical/q_res/chips/chips.prt';

PART_NAME
 R1107 'Q_RES_0201LF-4.7K,5%,1/20W,EMPTY,CS24701JE04':;

SECTION_NUMBER 1
 '@T6G_MB_LIB.T6G(SCH_1):PAGE430_I79@PURE_QUANTA.Q_RES(CHIPS)':
 C_PATH='@t6g_mb_lib.t6g(sch_1):page430_i79@pure_quanta.q_res(chips)',
 P_PATH='@t6g_mb_lib.t6g(sch_1):page309_i79@pure_quanta.q_res(chips)',
 PATH='I79',
 DRAWING='@T6G_MB_LIB.T6G(SCH_1):PAGE430',
 WATTAGE='1/20W',
 TOLERANCE='5%',
 MATERIAL='EMPTY',
 PHYS_PAGE='309',
 XY='(-1475,6050)',
 ROT='2',
 VER='2',
 PACK_TYPE='0201LF',
 LOCATION='R1107',
 CDS_LIB='pure_quanta',
 CDS_PART_NAME='Q_RES_0201LF-4.7K,5%,1/20W,EMPTY,CS24701JE04',
 PART_NUMBER='CS24701JE04',
 VALUE='4.7K',
 PRIM_FILE='./archive_libs/logical/q_res/chips/chips.prt';

PART_NAME
 R1108 'Q_RES_0201LF-4.7K,5%,1/20W,EMPTY,CS24701JE04':;

SECTION_NUMBER 1
 '@T6G_MB_LIB.T6G(SCH_1):PAGE430_I42@PURE_QUANTA.Q_RES(CHIPS)':
 C_PATH='@t6g_mb_lib.t6g(sch_1):page430_i42@pure_quanta.q_res(chips)',
 P_PATH='@t6g_mb_lib.t6g(sch_1):page309_i42@pure_quanta.q_res(chips)',
 PATH='I42',
 DRAWING='@T6G_MB_LIB.T6G(SCH_1):PAGE430',
 WATTAGE='1/20W',
 TOLERANCE='5%',
 MATERIAL='EMPTY',
 PHYS_PAGE='309',
 XY='(-7425,6000)',
 ROT='0',
 VER='2',
 PACK_TYPE='0201LF',
 LOCATION='R1108',
 CDS_LIB='pure_quanta',
 CDS_PART_NAME='Q_RES_0201LF-4.7K,5%,1/20W,EMPTY,CS24701JE04',
 PART_NUMBER='CS24701JE04',
 VALUE='4.7K',
 PRIM_FILE='./archive_libs/logical/q_res/chips/chips.prt';

PART_NAME
 R1109 'Q_RES_0201LF-0,5%,1/20W,CHIP,CS00001JE10':;

SECTION_NUMBER 1
 '@T6G_MB_LIB.T6G(SCH_1):PAGE430_I32@PURE_QUANTA.Q_RES(CHIPS)':
 C_PATH='@t6g_mb_lib.t6g(sch_1):page430_i32@pure_quanta.q_res(chips)',
 P_PATH='@t6g_mb_lib.t6g(sch_1):page309_i32@pure_quanta.q_res(chips)',
 PATH='I32',
 DRAWING='@T6G_MB_LIB.T6G(SCH_1):PAGE430',
 WATTAGE='1/20W',
 TOLERANCE='5%',
 MATERIAL='CHIP',
 PHYS_PAGE='309',
 XY='(-6350,2900)',
 ROT='0',
 VER='1',
 PACK_TYPE='0201LF',
 LOCATION='R1109',
 CDS_LIB='pure_quanta',
 CDS_PART_NAME='Q_RES_0201LF-0,5%,1/20W,CHIP,CS00001JE10',
 PART_NUMBER='CS00001JE10',
 VALUE='0',
 PRIM_FILE='./archive_libs/logical/q_res/chips/chips.prt';

PART_NAME
 R1110 'Q_RES_0201LF-0,5%,1/20W,CHIP,CS00001JE10':;

SECTION_NUMBER 1
 '@T6G_MB_LIB.T6G(SCH_1):PAGE430_I33@PURE_QUANTA.Q_RES(CHIPS)':
 C_PATH='@t6g_mb_lib.t6g(sch_1):page430_i33@pure_quanta.q_res(chips)',
 P_PATH='@t6g_mb_lib.t6g(sch_1):page309_i33@pure_quanta.q_res(chips)',
 PATH='I33',
 DRAWING='@T6G_MB_LIB.T6G(SCH_1):PAGE430',
 WATTAGE='1/20W',
 TOLERANCE='5%',
 MATERIAL='CHIP',
 PHYS_PAGE='309',
 XY='(-6350,2800)',
 ROT='0',
 VER='1',
 PACK_TYPE='0201LF',
 LOCATION='R1110',
 CDS_LIB='pure_quanta',
 CDS_PART_NAME='Q_RES_0201LF-0,5%,1/20W,CHIP,CS00001JE10',
 PART_NUMBER='CS00001JE10',
 VALUE='0',
 PRIM_FILE='./archive_libs/logical/q_res/chips/chips.prt';

PART_NAME
 R1111 'Q_RES_0201LF-4.7K,5%,1/20W,EMPTY,CS24701JE04':;

SECTION_NUMBER 1
 '@T6G_MB_LIB.T6G(SCH_1):PAGE430_I10@PURE_QUANTA.Q_RES(CHIPS)':
 C_PATH='@t6g_mb_lib.t6g(sch_1):page430_i10@pure_quanta.q_res(chips)',
 P_PATH='@t6g_mb_lib.t6g(sch_1):page309_i10@pure_quanta.q_res(chips)',
 PATH='I10',
 DRAWING='@T6G_MB_LIB.T6G(SCH_1):PAGE430',
 WATTAGE='1/20W',
 TOLERANCE='5%',
 MATERIAL='EMPTY',
 PHYS_PAGE='309',
 XY='(-8950,6000)',
 ROT='0',
 VER='2',
 PACK_TYPE='0201LF',
 LOCATION='R1111',
 CDS_LIB='pure_quanta',
 CDS_PART_NAME='Q_RES_0201LF-4.7K,5%,1/20W,EMPTY,CS24701JE04',
 PART_NUMBER='CS24701JE04',
 VALUE='4.7K',
 PRIM_FILE='./archive_libs/logical/q_res/chips/chips.prt';

PART_NAME
 R1112 'Q_RES_0201LF-10K,1%,1/20W,CHIP,CS31001FE17':;

SECTION_NUMBER 1
 '@T6G_MB_LIB.T6G(SCH_1):PAGE430_I7@PURE_QUANTA.Q_RES(CHIPS)':
 C_PATH='@t6g_mb_lib.t6g(sch_1):page430_i7@pure_quanta.q_res(chips)',
 P_PATH='@t6g_mb_lib.t6g(sch_1):page309_i7@pure_quanta.q_res(chips)',
 PATH='I7',
 DRAWING='@T6G_MB_LIB.T6G(SCH_1):PAGE430',
 WATTAGE='1/20W',
 TOLERANCE='1%',
 MATERIAL='CHIP',
 PHYS_PAGE='309',
 XY='(-8950,5050)',
 ROT='0',
 VER='2',
 PACK_TYPE='0201LF',
 LOCATION='R1112',
 CDS_LIB='pure_quanta',
 CDS_PART_NAME='Q_RES_0201LF-10K,1%,1/20W,CHIP,CS31001FE17',
 PART_NUMBER='CS31001FE17',
 VALUE='10K',
 PRIM_FILE='./archive_libs/logical/q_res/chips/chips.prt';

PART_NAME
 R1113 'Q_RES_0201LF-10K,1%,1/20W,CHIP,CS31001FE17':;

SECTION_NUMBER 1
 '@T6G_MB_LIB.T6G(SCH_1):PAGE430_I8@PURE_QUANTA.Q_RES(CHIPS)':
 C_PATH='@t6g_mb_lib.t6g(sch_1):page430_i8@pure_quanta.q_res(chips)',
 P_PATH='@t6g_mb_lib.t6g(sch_1):page309_i8@pure_quanta.q_res(chips)',
 PATH='I8',
 DRAWING='@T6G_MB_LIB.T6G(SCH_1):PAGE430',
 WATTAGE='1/20W',
 TOLERANCE='1%',
 MATERIAL='CHIP',
 PHYS_PAGE='309',
 XY='(-8650,5050)',
 ROT='0',
 VER='2',
 PACK_TYPE='0201LF',
 LOCATION='R1113',
 CDS_LIB='pure_quanta',
 CDS_PART_NAME='Q_RES_0201LF-10K,1%,1/20W,CHIP,CS31001FE17',
 PART_NUMBER='CS31001FE17',
 VALUE='10K',
 PRIM_FILE='./archive_libs/logical/q_res/chips/chips.prt';

PART_NAME
 R1114 'Q_RES_0201LF-4.7K,5%,1/20W,EMPTY,CS24701JE04':;

SECTION_NUMBER 1
 '@T6G_MB_LIB.T6G(SCH_1):PAGE430_I11@PURE_QUANTA.Q_RES(CHIPS)':
 C_PATH='@t6g_mb_lib.t6g(sch_1):page430_i11@pure_quanta.q_res(chips)',
 P_PATH='@t6g_mb_lib.t6g(sch_1):page309_i11@pure_quanta.q_res(chips)',
 PATH='I11',
 DRAWING='@T6G_MB_LIB.T6G(SCH_1):PAGE430',
 WATTAGE='1/20W',
 TOLERANCE='5%',
 MATERIAL='EMPTY',
 PHYS_PAGE='309',
 XY='(-8325,6000)',
 ROT='0',
 VER='2',
 PACK_TYPE='0201LF',
 LOCATION='R1114',
 CDS_LIB='pure_quanta',
 CDS_PART_NAME='Q_RES_0201LF-4.7K,5%,1/20W,EMPTY,CS24701JE04',
 PART_NUMBER='CS24701JE04',
 VALUE='4.7K',
 PRIM_FILE='./archive_libs/logical/q_res/chips/chips.prt';

PART_NAME
 R1115 'Q_RES_0201LF-4.7K,5%,1/20W,CHIP,CS24701JE04':;

SECTION_NUMBER 1
 '@T6G_MB_LIB.T6G(SCH_1):PAGE430_I9@PURE_QUANTA.Q_RES(CHIPS)':
 C_PATH='@t6g_mb_lib.t6g(sch_1):page430_i9@pure_quanta.q_res(chips)',
 P_PATH='@t6g_mb_lib.t6g(sch_1):page309_i9@pure_quanta.q_res(chips)',
 PATH='I9',
 DRAWING='@T6G_MB_LIB.T6G(SCH_1):PAGE430',
 WATTAGE='1/20W',
 TOLERANCE='5%',
 MATERIAL='CHIP',
 PHYS_PAGE='309',
 XY='(-8325,5050)',
 ROT='0',
 VER='2',
 PACK_TYPE='0201LF',
 LOCATION='R1115',
 CDS_LIB='pure_quanta',
 CDS_PART_NAME='Q_RES_0201LF-4.7K,5%,1/20W,CHIP,CS24701JE04',
 PART_NUMBER='CS24701JE04',
 VALUE='4.7K',
 PRIM_FILE='./archive_libs/logical/q_res/chips/chips.prt';

PART_NAME
 R1116 'Q_RES_0201LF-4.7K,5%,1/20W,EMPTY,CS24701JE04':;

SECTION_NUMBER 1
 '@T6G_MB_LIB.T6G(SCH_1):PAGE430_I40@PURE_QUANTA.Q_RES(CHIPS)':
 C_PATH='@t6g_mb_lib.t6g(sch_1):page430_i40@pure_quanta.q_res(chips)',
 P_PATH='@t6g_mb_lib.t6g(sch_1):page309_i40@pure_quanta.q_res(chips)',
 PATH='I40',
 DRAWING='@T6G_MB_LIB.T6G(SCH_1):PAGE430',
 WATTAGE='1/20W',
 TOLERANCE='5%',
 MATERIAL='EMPTY',
 PHYS_PAGE='309',
 XY='(-8025,5950)',
 ROT='0',
 VER='2',
 PACK_TYPE='0201LF',
 LOCATION='R1116',
 CDS_LIB='pure_quanta',
 CDS_PART_NAME='Q_RES_0201LF-4.7K,5%,1/20W,EMPTY,CS24701JE04',
 PART_NUMBER='CS24701JE04',
 VALUE='4.7K',
 PRIM_FILE='./archive_libs/logical/q_res/chips/chips.prt';

PART_NAME
 R1117 'Q_RES_0402LF-6.19K,1%,1/16W,CHIP,CS26192FB03':
 ROOM='HSC BOM1';

SECTION_NUMBER 1
 '@T6G_MB_LIB.T6G(SCH_1):PAGE267_I22@PURE_QUANTA.Q_RES(CHIPS)':
 C_PATH='@t6g_mb_lib.t6g(sch_1):page267_i22@pure_quanta.q_res(chips)',
 P_PATH='@t6g_mb_lib.t6g(sch_1):page262_i22@pure_quanta.q_res(chips)',
 PATH='I22',
 DRAWING='@T6G_MB_LIB.T6G(SCH_1):PAGE267',
 WATTAGE='1/16W',
 TOLERANCE='1%',
 MATERIAL='CHIP',
 PHYS_PAGE='262',
 XY='(-9975,1450)',
 ROT='0',
 VER='2',
 PACK_TYPE='0402LF',
 LOCATION='R1117',
 CDS_LIB='pure_quanta',
 CDS_PART_NAME='Q_RES_0402LF-6.19K,1%,1/16W,CHIP,CS26192FB03',
 ROOM='HSC BOM1',
 PART_NUMBER='CS26192FB03',
 VALUE='6.19K',
 PRIM_FILE='./archive_libs/logical/q_res/chips/chips.prt';

PART_NAME
 R1118 'Q_RES_0201LF-4.7K,5%,1/20W,CHIP,CS24701JE04':;

SECTION_NUMBER 1
 '@T6G_MB_LIB.T6G(SCH_1):PAGE430_I36@PURE_QUANTA.Q_RES(CHIPS)':
 C_PATH='@t6g_mb_lib.t6g(sch_1):page430_i36@pure_quanta.q_res(chips)',
 P_PATH='@t6g_mb_lib.t6g(sch_1):page309_i36@pure_quanta.q_res(chips)',
 PATH='I36',
 DRAWING='@T6G_MB_LIB.T6G(SCH_1):PAGE430',
 WATTAGE='1/20W',
 TOLERANCE='5%',
 MATERIAL='CHIP',
 PHYS_PAGE='309',
 XY='(-8025,5025)',
 ROT='0',
 VER='2',
 PACK_TYPE='0201LF',
 LOCATION='R1118',
 CDS_LIB='pure_quanta',
 CDS_PART_NAME='Q_RES_0201LF-4.7K,5%,1/20W,CHIP,CS24701JE04',
 PART_NUMBER='CS24701JE04',
 VALUE='4.7K',
 PRIM_FILE='./archive_libs/logical/q_res/chips/chips.prt';

PART_NAME
 R1119 'Q_RES_0201LF-4.7K,5%,1/20W,EMPTY,CS24701JE04':;

SECTION_NUMBER 1
 '@T6G_MB_LIB.T6G(SCH_1):PAGE430_I41@PURE_QUANTA.Q_RES(CHIPS)':
 C_PATH='@t6g_mb_lib.t6g(sch_1):page430_i41@pure_quanta.q_res(chips)',
 P_PATH='@t6g_mb_lib.t6g(sch_1):page309_i41@pure_quanta.q_res(chips)',
 PATH='I41',
 DRAWING='@T6G_MB_LIB.T6G(SCH_1):PAGE430',
 WATTAGE='1/20W',
 TOLERANCE='5%',
 MATERIAL='EMPTY',
 PHYS_PAGE='309',
 XY='(-7725,5975)',
 ROT='0',
 VER='2',
 PACK_TYPE='0201LF',
 LOCATION='R1119',
 CDS_LIB='pure_quanta',
 CDS_PART_NAME='Q_RES_0201LF-4.7K,5%,1/20W,EMPTY,CS24701JE04',
 PART_NUMBER='CS24701JE04',
 VALUE='4.7K',
 PRIM_FILE='./archive_libs/logical/q_res/chips/chips.prt';

PART_NAME
 R1120 'Q_RES_0201LF-4.7K,5%,1/20W,CHIP,CS24701JE04':;

SECTION_NUMBER 1
 '@T6G_MB_LIB.T6G(SCH_1):PAGE430_I37@PURE_QUANTA.Q_RES(CHIPS)':
 C_PATH='@t6g_mb_lib.t6g(sch_1):page430_i37@pure_quanta.q_res(chips)',
 P_PATH='@t6g_mb_lib.t6g(sch_1):page309_i37@pure_quanta.q_res(chips)',
 PATH='I37',
 DRAWING='@T6G_MB_LIB.T6G(SCH_1):PAGE430',
 WATTAGE='1/20W',
 TOLERANCE='5%',
 MATERIAL='CHIP',
 PHYS_PAGE='309',
 XY='(-7725,5025)',
 ROT='0',
 VER='2',
 PACK_TYPE='0201LF',
 LOCATION='R1120',
 CDS_LIB='pure_quanta',
 CDS_PART_NAME='Q_RES_0201LF-4.7K,5%,1/20W,CHIP,CS24701JE04',
 PART_NUMBER='CS24701JE04',
 VALUE='4.7K',
 PRIM_FILE='./archive_libs/logical/q_res/chips/chips.prt';

PART_NAME
 R1121 'Q_RES_0201LF-4.7K,5%,1/20W,CHIP,CS24701JE04':;

SECTION_NUMBER 1
 '@T6G_MB_LIB.T6G(SCH_1):PAGE430_I39@PURE_QUANTA.Q_RES(CHIPS)':
 C_PATH='@t6g_mb_lib.t6g(sch_1):page430_i39@pure_quanta.q_res(chips)',
 P_PATH='@t6g_mb_lib.t6g(sch_1):page309_i39@pure_quanta.q_res(chips)',
 PATH='I39',
 DRAWING='@T6G_MB_LIB.T6G(SCH_1):PAGE430',
 WATTAGE='1/20W',
 TOLERANCE='5%',
 MATERIAL='CHIP',
 PHYS_PAGE='309',
 XY='(-7425,5000)',
 ROT='0',
 VER='2',
 PACK_TYPE='0201LF',
 LOCATION='R1121',
 CDS_LIB='pure_quanta',
 CDS_PART_NAME='Q_RES_0201LF-4.7K,5%,1/20W,CHIP,CS24701JE04',
 PART_NUMBER='CS24701JE04',
 VALUE='4.7K',
 PRIM_FILE='./archive_libs/logical/q_res/chips/chips.prt';

PART_NAME
 R1122 'Q_RES_0201LF-4.7K,5%,1/20W,CHIP,CS24701JE04':;

SECTION_NUMBER 1
 '@T6G_MB_LIB.T6G(SCH_1):PAGE430_I51@PURE_QUANTA.Q_RES(CHIPS)':
 C_PATH='@t6g_mb_lib.t6g(sch_1):page430_i51@pure_quanta.q_res(chips)',
 P_PATH='@t6g_mb_lib.t6g(sch_1):page309_i51@pure_quanta.q_res(chips)',
 PATH='I51',
 DRAWING='@T6G_MB_LIB.T6G(SCH_1):PAGE430',
 WATTAGE='1/20W',
 TOLERANCE='5%',
 MATERIAL='CHIP',
 PHYS_PAGE='309',
 XY='(-5025,6075)',
 ROT='0',
 VER='2',
 PACK_TYPE='0201LF',
 LOCATION='R1122',
 CDS_LIB='pure_quanta',
 CDS_PART_NAME='Q_RES_0201LF-4.7K,5%,1/20W,CHIP,CS24701JE04',
 PART_NUMBER='CS24701JE04',
 VALUE='4.7K',
 PRIM_FILE='./archive_libs/logical/q_res/chips/chips.prt';

PART_NAME
 R1123 'Q_RES_0201LF-1K,1%,1/20W,EMPTY,CS21001FE07':;

SECTION_NUMBER 1
 '@T6G_MB_LIB.T6G(SCH_1):PAGE431_I19@PURE_QUANTA.Q_RES(CHIPS)':
 C_PATH='@t6g_mb_lib.t6g(sch_1):page431_i19@pure_quanta.q_res(chips)',
 P_PATH='@t6g_mb_lib.t6g(sch_1):page310_i19@pure_quanta.q_res(chips)',
 PATH='I19',
 DRAWING='@T6G_MB_LIB.T6G(SCH_1):PAGE431',
 WATTAGE='1/20W',
 TOLERANCE='1%',
 MATERIAL='EMPTY',
 PHYS_PAGE='310',
 XY='(-8575,3850)',
 ROT='0',
 VER='2',
 PACK_TYPE='0201LF',
 LOCATION='R1123',
 CDS_LIB='pure_quanta',
 CDS_PART_NAME='Q_RES_0201LF-1K,1%,1/20W,EMPTY,CS21001FE07',
 PART_NUMBER='CS21001FE07',
 VALUE='1K',
 PRIM_FILE='./archive_libs/logical/q_res/chips/chips.prt';

PART_NAME
 R1124 'Q_RES_0201LF-200,1%,1/20W,CHIP,CS12001FE12':;

SECTION_NUMBER 1
 '@T6G_MB_LIB.T6G(SCH_1):PAGE431_I18@PURE_QUANTA.Q_RES(CHIPS)':
 C_PATH='@t6g_mb_lib.t6g(sch_1):page431_i18@pure_quanta.q_res(chips)',
 P_PATH='@t6g_mb_lib.t6g(sch_1):page310_i18@pure_quanta.q_res(chips)',
 PATH='I18',
 DRAWING='@T6G_MB_LIB.T6G(SCH_1):PAGE431',
 WATTAGE='1/20W',
 TOLERANCE='1%',
 MATERIAL='CHIP',
 PHYS_PAGE='310',
 XY='(-7550,3300)',
 ROT='0',
 VER='2',
 PACK_TYPE='0201LF',
 LOCATION='R1124',
 CDS_LIB='pure_quanta',
 CDS_PART_NAME='Q_RES_0201LF-200,1%,1/20W,CHIP,CS12001FE12',
 PART_NUMBER='CS12001FE12',
 VALUE='200',
 PRIM_FILE='./archive_libs/logical/q_res/chips/chips.prt';

PART_NAME
 R1125 'Q_RES_0201LF-0,5%,1/20W,CHIP,CS00001JE10':;

SECTION_NUMBER 1
 '@T6G_MB_LIB.T6G(SCH_1):PAGE431_I13@PURE_QUANTA.Q_RES(CHIPS)':
 C_PATH='@t6g_mb_lib.t6g(sch_1):page431_i13@pure_quanta.q_res(chips)',
 P_PATH='@t6g_mb_lib.t6g(sch_1):page310_i13@pure_quanta.q_res(chips)',
 PATH='I13',
 DRAWING='@T6G_MB_LIB.T6G(SCH_1):PAGE431',
 WATTAGE='1/20W',
 TOLERANCE='5%',
 MATERIAL='CHIP',
 PHYS_PAGE='310',
 XY='(-1350,1200)',
 ROT='0',
 VER='2',
 PACK_TYPE='0201LF',
 LOCATION='R1125',
 CDS_LIB='pure_quanta',
 CDS_PART_NAME='Q_RES_0201LF-0,5%,1/20W,CHIP,CS00001JE10',
 PART_NUMBER='CS00001JE10',
 VALUE='0',
 PRIM_FILE='./archive_libs/logical/q_res/chips/chips.prt';

PART_NAME
 R1126 'Q_RES_0201LF-0,5%,1/20W,CHIP,CS00001JE10':;

SECTION_NUMBER 1
 '@T6G_MB_LIB.T6G(SCH_1):PAGE431_I14@PURE_QUANTA.Q_RES(CHIPS)':
 C_PATH='@t6g_mb_lib.t6g(sch_1):page431_i14@pure_quanta.q_res(chips)',
 P_PATH='@t6g_mb_lib.t6g(sch_1):page310_i14@pure_quanta.q_res(chips)',
 PATH='I14',
 DRAWING='@T6G_MB_LIB.T6G(SCH_1):PAGE431',
 WATTAGE='1/20W',
 TOLERANCE='5%',
 MATERIAL='CHIP',
 PHYS_PAGE='310',
 XY='(-1200,1750)',
 ROT='0',
 VER='2',
 PACK_TYPE='0201LF',
 LOCATION='R1126',
 CDS_LIB='pure_quanta',
 CDS_PART_NAME='Q_RES_0201LF-0,5%,1/20W,CHIP,CS00001JE10',
 PART_NUMBER='CS00001JE10',
 VALUE='0',
 PRIM_FILE='./archive_libs/logical/q_res/chips/chips.prt';

PART_NAME
 R1127 'Q_RES_0201LF-1K,1%,1/20W,CHIP,CS21001FE07':;

SECTION_NUMBER 1
 '@T6G_MB_LIB.T6G(SCH_1):PAGE432_I18@PURE_QUANTA.Q_RES(CHIPS)':
 C_PATH='@t6g_mb_lib.t6g(sch_1):page432_i18@pure_quanta.q_res(chips)',
 P_PATH='@t6g_mb_lib.t6g(sch_1):page311_i18@pure_quanta.q_res(chips)',
 PATH='I18',
 DRAWING='@T6G_MB_LIB.T6G(SCH_1):PAGE432',
 WATTAGE='1/20W',
 TOLERANCE='1%',
 MATERIAL='CHIP',
 PHYS_PAGE='311',
 XY='(-4175,5400)',
 ROT='0',
 VER='2',
 PACK_TYPE='0201LF',
 LOCATION='R1127',
 CDS_LIB='pure_quanta',
 CDS_PART_NAME='Q_RES_0201LF-1K,1%,1/20W,CHIP,CS21001FE07',
 PART_NUMBER='CS21001FE07',
 VALUE='1K',
 PRIM_FILE='./archive_libs/logical/q_res/chips/chips.prt';

PART_NAME
 R1128 'Q_RES_0402LF-1K,1%,1/16W,CHIP,CS21002FB06':;

SECTION_NUMBER 1
 '@T6G_MB_LIB.T6G(SCH_1):PAGE340_I34@PURE_QUANTA.Q_RES(CHIPS)':
 C_PATH='@t6g_mb_lib.t6g(sch_1):page340_i34@pure_quanta.q_res(chips)',
 P_PATH='@t6g_mb_lib.t6g(sch_1):page136_i34@pure_quanta.q_res(chips)',
 PATH='I34',
 DRAWING='@T6G_MB_LIB.T6G(SCH_1):PAGE340',
 WATTAGE='1/16W',
 TOLERANCE='1%',
 MATERIAL='CHIP',
 PHYS_PAGE='136',
 XY='(-3875,9500)',
 ROT='2',
 VER='2',
 PACK_TYPE='0402LF',
 LOCATION='R1128',
 CDS_LIB='pure_quanta',
 CDS_PART_NAME='Q_RES_0402LF-1K,1%,1/16W,CHIP,CS21002FB06',
 PART_NUMBER='CS21002FB06',
 VALUE='1K',
 PRIM_FILE='./archive_libs/logical/q_res/chips/chips.prt';

PART_NAME
 R1129 'Q_RES_0402LF-0,5%,1/16W,CHIP,CS00002JB13':;

SECTION_NUMBER 1
 '@T6G_MB_LIB.T6G(SCH_1):PAGE340_I57@PURE_QUANTA.Q_RES(CHIPS)':
 C_PATH='@t6g_mb_lib.t6g(sch_1):page340_i57@pure_quanta.q_res(chips)',
 P_PATH='@t6g_mb_lib.t6g(sch_1):page136_i57@pure_quanta.q_res(chips)',
 PATH='I57',
 DRAWING='@T6G_MB_LIB.T6G(SCH_1):PAGE340',
 WATTAGE='1/16W',
 TOLERANCE='5%',
 MATERIAL='CHIP',
 PHYS_PAGE='136',
 XY='(-3800,7450)',
 ROT='0',
 VER='1',
 PACK_TYPE='0402LF',
 LOCATION='R1129',
 CDS_LIB='pure_quanta',
 CDS_PART_NAME='Q_RES_0402LF-0,5%,1/16W,CHIP,CS00002JB13',
 PART_NUMBER='CS00002JB13',
 VALUE='0',
 PRIM_FILE='./archive_libs/logical/q_res/chips/chips.prt';

PART_NAME
 R1130 'Q_RES_0402LF-0,5%,1/16W,EMPTY,CS00002JB13':;

SECTION_NUMBER 1
 '@T6G_MB_LIB.T6G(SCH_1):PAGE340_I49@PURE_QUANTA.Q_RES(CHIPS)':
 C_PATH='@t6g_mb_lib.t6g(sch_1):page340_i49@pure_quanta.q_res(chips)',
 P_PATH='@t6g_mb_lib.t6g(sch_1):page136_i49@pure_quanta.q_res(chips)',
 PATH='I49',
 DRAWING='@T6G_MB_LIB.T6G(SCH_1):PAGE340',
 WATTAGE='1/16W',
 TOLERANCE='5%',
 MATERIAL='EMPTY',
 PHYS_PAGE='136',
 XY='(-2125,9300)',
 ROT='0',
 VER='1',
 PACK_TYPE='0402LF',
 LOCATION='R1130',
 CDS_LIB='pure_quanta',
 CDS_PART_NAME='Q_RES_0402LF-0,5%,1/16W,EMPTY,CS00002JB13',
 PART_NUMBER='CS00002JB13',
 VALUE='0',
 PRIM_FILE='./archive_libs/logical/q_res/chips/chips.prt';

PART_NAME
 R1131 'Q_RES_0402LF-1K,1%,1/16W,CHIP,CS21002FB06':;

SECTION_NUMBER 1
 '@T6G_MB_LIB.T6G(SCH_1):PAGE340_I44@PURE_QUANTA.Q_RES(CHIPS)':
 C_PATH='@t6g_mb_lib.t6g(sch_1):page340_i44@pure_quanta.q_res(chips)',
 P_PATH='@t6g_mb_lib.t6g(sch_1):page136_i44@pure_quanta.q_res(chips)',
 PATH='I44',
 DRAWING='@T6G_MB_LIB.T6G(SCH_1):PAGE340',
 WATTAGE='1/16W',
 TOLERANCE='1%',
 MATERIAL='CHIP',
 PHYS_PAGE='136',
 XY='(-1225,9725)',
 ROT='2',
 VER='2',
 PACK_TYPE='0402LF',
 LOCATION='R1131',
 CDS_LIB='pure_quanta',
 CDS_PART_NAME='Q_RES_0402LF-1K,1%,1/16W,CHIP,CS21002FB06',
 PART_NUMBER='CS21002FB06',
 VALUE='1K',
 PRIM_FILE='./archive_libs/logical/q_res/chips/chips.prt';

PART_NAME
 R1132 'Q_RES_0402LF-0,5%,1/16W,CHIP,CS00002JB13':;

SECTION_NUMBER 1
 '@T6G_MB_LIB.T6G(SCH_1):PAGE340_I58@PURE_QUANTA.Q_RES(CHIPS)':
 C_PATH='@t6g_mb_lib.t6g(sch_1):page340_i58@pure_quanta.q_res(chips)',
 P_PATH='@t6g_mb_lib.t6g(sch_1):page136_i58@pure_quanta.q_res(chips)',
 PATH='I58',
 DRAWING='@T6G_MB_LIB.T6G(SCH_1):PAGE340',
 WATTAGE='1/16W',
 TOLERANCE='5%',
 MATERIAL='CHIP',
 PHYS_PAGE='136',
 XY='(-1325,7450)',
 ROT='0',
 VER='1',
 PACK_TYPE='0402LF',
 LOCATION='R1132',
 CDS_LIB='pure_quanta',
 CDS_PART_NAME='Q_RES_0402LF-0,5%,1/16W,CHIP,CS00002JB13',
 PART_NUMBER='CS00002JB13',
 VALUE='0',
 PRIM_FILE='./archive_libs/logical/q_res/chips/chips.prt';

PART_NAME
 R1133 'Q_RES_0402LF-1K,1%,1/16W,CHIP,CS21002FB06':;

SECTION_NUMBER 1
 '@T6G_MB_LIB.T6G(SCH_1):PAGE340_I61@PURE_QUANTA.Q_RES(CHIPS)':
 C_PATH='@t6g_mb_lib.t6g(sch_1):page340_i61@pure_quanta.q_res(chips)',
 P_PATH='@t6g_mb_lib.t6g(sch_1):page136_i61@pure_quanta.q_res(chips)',
 PATH='I61',
 DRAWING='@T6G_MB_LIB.T6G(SCH_1):PAGE340',
 WATTAGE='1/16W',
 TOLERANCE='1%',
 MATERIAL='CHIP',
 PHYS_PAGE='136',
 XY='(-875,7800)',
 ROT='2',
 VER='2',
 PACK_TYPE='0402LF',
 LOCATION='R1133',
 CDS_LIB='pure_quanta',
 CDS_PART_NAME='Q_RES_0402LF-1K,1%,1/16W,CHIP,CS21002FB06',
 PART_NUMBER='CS21002FB06',
 VALUE='1K',
 PRIM_FILE='./archive_libs/logical/q_res/chips/chips.prt';

PART_NAME
 R1134 'Q_RES_0402LF-0,5%,1/16W,CHIP,CS00002JB13':;

SECTION_NUMBER 1
 '@T6G_MB_LIB.T6G(SCH_1):PAGE340_I47@PURE_QUANTA.Q_RES(CHIPS)':
 C_PATH='@t6g_mb_lib.t6g(sch_1):page340_i47@pure_quanta.q_res(chips)',
 P_PATH='@t6g_mb_lib.t6g(sch_1):page136_i47@pure_quanta.q_res(chips)',
 PATH='I47',
 DRAWING='@T6G_MB_LIB.T6G(SCH_1):PAGE340',
 WATTAGE='1/16W',
 TOLERANCE='5%',
 MATERIAL='CHIP',
 PHYS_PAGE='136',
 XY='(650,9150)',
 ROT='0',
 VER='1',
 PACK_TYPE='0402LF',
 LOCATION='R1134',
 CDS_LIB='pure_quanta',
 CDS_PART_NAME='Q_RES_0402LF-0,5%,1/16W,CHIP,CS00002JB13',
 PART_NUMBER='CS00002JB13',
 VALUE='0',
 PRIM_FILE='./archive_libs/logical/q_res/chips/chips.prt';

PART_NAME
 R1135 'Q_RES_0402LF-0,5%,1/16W,EMPTY,CS00002JB13':;

SECTION_NUMBER 1
 '@T6G_MB_LIB.T6G(SCH_1):PAGE248_I41@PURE_QUANTA.Q_RES(CHIPS)':
 C_PATH='@t6g_mb_lib.t6g(sch_1):page248_i41@pure_quanta.q_res(chips)',
 P_PATH='@t6g_mb_lib.t6g(sch_1):page247_i41@pure_quanta.q_res(chips)',
 PATH='I41',
 DRAWING='@T6G_MB_LIB.T6G(SCH_1):PAGE248',
 WATTAGE='1/16W',
 TOLERANCE='5%',
 MATERIAL='EMPTY',
 PHYS_PAGE='247',
 XY='(-3450,4650)',
 ROT='0',
 VER='1',
 PACK_TYPE='0402LF',
 LOCATION='R1135',
 CDS_LIB='pure_quanta',
 CDS_PART_NAME='Q_RES_0402LF-0,5%,1/16W,EMPTY,CS00002JB13',
 PART_NUMBER='CS00002JB13',
 VALUE='0',
 PRIM_FILE='./archive_libs/logical/q_res/chips/chips.prt';

PART_NAME
 R1136 'Q_RES_0402LF-0,5%,1/16W,EMPTY,CS00002JB13':
 ROOM='NIC_P3V3_BOM1';

SECTION_NUMBER 1
 '@T6G_MB_LIB.T6G(SCH_1):PAGE338_I133@PURE_QUANTA.Q_RES(CHIPS)':
 C_PATH='@t6g_mb_lib.t6g(sch_1):page338_i133@pure_quanta.q_res(chips)',
 P_PATH='@t6g_mb_lib.t6g(sch_1):page134_i133@pure_quanta.q_res(chips)',
 PATH='I133',
 DRAWING='@T6G_MB_LIB.T6G(SCH_1):PAGE338',
 WATTAGE='1/16W',
 TOLERANCE='5%',
 MATERIAL='EMPTY',
 PHYS_PAGE='134',
 XY='(3325,12225)',
 ROT='0',
 VER='1',
 PACK_TYPE='0402LF',
 LOCATION='R1136',
 CDS_LIB='pure_quanta',
 CDS_PART_NAME='Q_RES_0402LF-0,5%,1/16W,EMPTY,CS00002JB13',
 ROOM='NIC_P3V3_BOM1',
 PART_NUMBER='CS00002JB13',
 VALUE='0',
 PRIM_FILE='./archive_libs/logical/q_res/chips/chips.prt';

PART_NAME
 R1137 'Q_RES_0402LF-0,5%,1/16W,EMPTY,CS00002JB13':
 ROOM='NIC_P3V3_BOM2';

SECTION_NUMBER 1
 '@T6G_MB_LIB.T6G(SCH_1):PAGE339_I135@PURE_QUANTA.Q_RES(CHIPS)':
 C_PATH='@t6g_mb_lib.t6g(sch_1):page339_i135@pure_quanta.q_res(chips)',
 P_PATH='@t6g_mb_lib.t6g(sch_1):page135_i135@pure_quanta.q_res(chips)',
 PATH='I135',
 DRAWING='@T6G_MB_LIB.T6G(SCH_1):PAGE339',
 WATTAGE='1/16W',
 TOLERANCE='5%',
 MATERIAL='EMPTY',
 PHYS_PAGE='135',
 XY='(-4025,12900)',
 ROT='0',
 VER='1',
 PACK_TYPE='0402LF',
 LOCATION='R1137',
 CDS_LIB='pure_quanta',
 CDS_PART_NAME='Q_RES_0402LF-0,5%,1/16W,EMPTY,CS00002JB13',
 ROOM='NIC_P3V3_BOM2',
 PART_NUMBER='CS00002JB13',
 VALUE='0',
 PRIM_FILE='./archive_libs/logical/q_res/chips/chips.prt';

PART_NAME
 R1138 'Q_RES_0402LF-10K,1%,1/16W,CHIP,CS31002FB08':;

SECTION_NUMBER 1
 '@T6G_MB_LIB.T6G(SCH_1):PAGE337_I1@PURE_QUANTA.Q_RES(CHIPS)':
 C_PATH='@t6g_mb_lib.t6g(sch_1):page337_i1@pure_quanta.q_res(chips)',
 P_PATH='@t6g_mb_lib.t6g(sch_1):page133_i1@pure_quanta.q_res(chips)',
 PATH='I1',
 DRAWING='@T6G_MB_LIB.T6G(SCH_1):PAGE337',
 WATTAGE='1/16W',
 TOLERANCE='1%',
 MATERIAL='CHIP',
 PHYS_PAGE='133',
 XY='(-10225,2725)',
 ROT='2',
 VER='2',
 PACK_TYPE='0402LF',
 LOCATION='R1138',
 CDS_LIB='pure_quanta',
 CDS_PART_NAME='Q_RES_0402LF-10K,1%,1/16W,CHIP,CS31002FB08',
 PART_NUMBER='CS31002FB08',
 VALUE='10K',
 PRIM_FILE='./archive_libs/logical/q_res/chips/chips.prt';

PART_NAME
 R1139 'Q_RES_0402LF-0,5%,1/16W,CHIP,CS00002JB13':;

SECTION_NUMBER 1
 '@T6G_MB_LIB.T6G(SCH_1):PAGE337_I7@PURE_QUANTA.Q_RES(CHIPS)':
 C_PATH='@t6g_mb_lib.t6g(sch_1):page337_i7@pure_quanta.q_res(chips)',
 P_PATH='@t6g_mb_lib.t6g(sch_1):page133_i7@pure_quanta.q_res(chips)',
 PATH='I7',
 DRAWING='@T6G_MB_LIB.T6G(SCH_1):PAGE337',
 WATTAGE='1/16W',
 TOLERANCE='5%',
 MATERIAL='CHIP',
 PHYS_PAGE='133',
 XY='(-8150,2525)',
 ROT='0',
 VER='1',
 PACK_TYPE='0402LF',
 LOCATION='R1139',
 CDS_LIB='pure_quanta',
 CDS_PART_NAME='Q_RES_0402LF-0,5%,1/16W,CHIP,CS00002JB13',
 PART_NUMBER='CS00002JB13',
 VALUE='0',
 PRIM_FILE='./archive_libs/logical/q_res/chips/chips.prt';

PART_NAME
 R1140 'Q_RES_0402LF-27.4,1%,1/16W,CHIP,CS02742FB03':;

SECTION_NUMBER 1
 '@T6G_MB_LIB.T6G(SCH_1):PAGE337_I22@PURE_QUANTA.Q_RES(CHIPS)':
 C_PATH='@t6g_mb_lib.t6g(sch_1):page337_i22@pure_quanta.q_res(chips)',
 P_PATH='@t6g_mb_lib.t6g(sch_1):page133_i22@pure_quanta.q_res(chips)',
 PATH='I22',
 DRAWING='@T6G_MB_LIB.T6G(SCH_1):PAGE337',
 WATTAGE='1/16W',
 TOLERANCE='1%',
 MATERIAL='CHIP',
 PHYS_PAGE='133',
 XY='(-5550,2525)',
 ROT='0',
 VER='1',
 PACK_TYPE='0402LF',
 LOCATION='R1140',
 CDS_LIB='pure_quanta',
 CDS_PART_NAME='Q_RES_0402LF-27.4,1%,1/16W,CHIP,CS02742FB03',
 PART_NUMBER='CS02742FB03',
 VALUE='27.4',
 PRIM_FILE='./archive_libs/logical/q_res/chips/chips.prt';

PART_NAME
 R1141 'Q_RES_0402LF-27.4,1%,1/16W,CHIP,CS02742FB03':;

SECTION_NUMBER 1
 '@T6G_MB_LIB.T6G(SCH_1):PAGE337_I21@PURE_QUANTA.Q_RES(CHIPS)':
 C_PATH='@t6g_mb_lib.t6g(sch_1):page337_i21@pure_quanta.q_res(chips)',
 P_PATH='@t6g_mb_lib.t6g(sch_1):page133_i21@pure_quanta.q_res(chips)',
 PATH='I21',
 DRAWING='@T6G_MB_LIB.T6G(SCH_1):PAGE337',
 WATTAGE='1/16W',
 TOLERANCE='1%',
 MATERIAL='CHIP',
 PHYS_PAGE='133',
 XY='(-5550,2475)',
 ROT='0',
 VER='1',
 PACK_TYPE='0402LF',
 LOCATION='R1141',
 CDS_LIB='pure_quanta',
 CDS_PART_NAME='Q_RES_0402LF-27.4,1%,1/16W,CHIP,CS02742FB03',
 PART_NUMBER='CS02742FB03',
 VALUE='27.4',
 PRIM_FILE='./archive_libs/logical/q_res/chips/chips.prt';

PART_NAME
 R1142 'Q_RES_0402LF-0,5%,1/16W,CHIP,CS00002JB13':;

SECTION_NUMBER 1
 '@T6G_MB_LIB.T6G(SCH_1):PAGE340_I71@PURE_QUANTA.Q_RES(CHIPS)':
 C_PATH='@t6g_mb_lib.t6g(sch_1):page340_i71@pure_quanta.q_res(chips)',
 P_PATH='@t6g_mb_lib.t6g(sch_1):page136_i71@pure_quanta.q_res(chips)',
 PATH='I71',
 DRAWING='@T6G_MB_LIB.T6G(SCH_1):PAGE340',
 WATTAGE='1/16W',
 TOLERANCE='5%',
 MATERIAL='CHIP',
 PHYS_PAGE='136',
 XY='(-450,8225)',
 ROT='0',
 VER='1',
 PACK_TYPE='0402LF',
 LOCATION='R1142',
 CDS_LIB='pure_quanta',
 CDS_PART_NAME='Q_RES_0402LF-0,5%,1/16W,CHIP,CS00002JB13',
 PART_NUMBER='CS00002JB13',
 VALUE='0',
 PRIM_FILE='./archive_libs/logical/q_res/chips/chips.prt';

PART_NAME
 R1143 'Q_RES_0402LF-0,5%,1/16W,CHIP,CS00002JB13':;

SECTION_NUMBER 1
 '@T6G_MB_LIB.T6G(SCH_1):PAGE340_I65@PURE_QUANTA.Q_RES(CHIPS)':
 C_PATH='@t6g_mb_lib.t6g(sch_1):page340_i65@pure_quanta.q_res(chips)',
 P_PATH='@t6g_mb_lib.t6g(sch_1):page136_i65@pure_quanta.q_res(chips)',
 PATH='I65',
 DRAWING='@T6G_MB_LIB.T6G(SCH_1):PAGE340',
 WATTAGE='1/16W',
 TOLERANCE='5%',
 MATERIAL='CHIP',
 PHYS_PAGE='136',
 XY='(1975,8225)',
 ROT='0',
 VER='1',
 PACK_TYPE='0402LF',
 LOCATION='R1143',
 CDS_LIB='pure_quanta',
 CDS_PART_NAME='Q_RES_0402LF-0,5%,1/16W,CHIP,CS00002JB13',
 PART_NUMBER='CS00002JB13',
 VALUE='0',
 PRIM_FILE='./archive_libs/logical/q_res/chips/chips.prt';

PART_NAME
 R1144 'Q_RES_0402LF-1K,1%,1/16W,CHIP,CS21002FB06':;

SECTION_NUMBER 1
 '@T6G_MB_LIB.T6G(SCH_1):PAGE340_I64@PURE_QUANTA.Q_RES(CHIPS)':
 C_PATH='@t6g_mb_lib.t6g(sch_1):page340_i64@pure_quanta.q_res(chips)',
 P_PATH='@t6g_mb_lib.t6g(sch_1):page136_i64@pure_quanta.q_res(chips)',
 PATH='I64',
 DRAWING='@T6G_MB_LIB.T6G(SCH_1):PAGE340',
 WATTAGE='1/16W',
 TOLERANCE='1%',
 MATERIAL='CHIP',
 PHYS_PAGE='136',
 XY='(2475,8575)',
 ROT='2',
 VER='2',
 PACK_TYPE='0402LF',
 LOCATION='R1144',
 CDS_LIB='pure_quanta',
 CDS_PART_NAME='Q_RES_0402LF-1K,1%,1/16W,CHIP,CS21002FB06',
 PART_NUMBER='CS21002FB06',
 VALUE='1K',
 PRIM_FILE='./archive_libs/logical/q_res/chips/chips.prt';

PART_NAME
 R1145 'Q_RES_0402LF-10K,5%,1/16W,EMPTY,CS31002JB08':;

SECTION_NUMBER 1
 '@T6G_MB_LIB.T6G(SCH_1):PAGE340_I76@PURE_QUANTA.Q_RES(CHIPS)':
 C_PATH='@t6g_mb_lib.t6g(sch_1):page340_i76@pure_quanta.q_res(chips)',
 P_PATH='@t6g_mb_lib.t6g(sch_1):page136_i76@pure_quanta.q_res(chips)',
 PATH='I76',
 DRAWING='@T6G_MB_LIB.T6G(SCH_1):PAGE340',
 WATTAGE='1/16W',
 TOLERANCE='5%',
 MATERIAL='EMPTY',
 PHYS_PAGE='136',
 XY='(2700,5850)',
 ROT='0',
 VER='2',
 PACK_TYPE='0402LF',
 LOCATION='R1145',
 CDS_LIB='pure_quanta',
 CDS_PART_NAME='Q_RES_0402LF-10K,5%,1/16W,EMPTY,CS31002JB08',
 PART_NUMBER='CS31002JB08',
 VALUE='10K',
 PRIM_FILE='./archive_libs/logical/q_res/chips/chips.prt';

PART_NAME
 R1146 'Q_RES_0402LF-0,5%,1/16W,EMPTY,CS00002JB13':;

SECTION_NUMBER 1
 '@T6G_MB_LIB.T6G(SCH_1):PAGE257_I41@PURE_QUANTA.Q_RES(CHIPS)':
 C_PATH='@t6g_mb_lib.t6g(sch_1):page257_i41@pure_quanta.q_res(chips)',
 P_PATH='@t6g_mb_lib.t6g(sch_1):page142_i41@pure_quanta.q_res(chips)',
 PATH='I41',
 DRAWING='@T6G_MB_LIB.T6G(SCH_1):PAGE257',
 BOM_COST='MEM',
 WATTAGE='1/16W',
 TOLERANCE='5%',
 MATERIAL='EMPTY',
 PHYS_PAGE='142',
 XY='(625,200)',
 ROT='2',
 VER='1',
 PACK_TYPE='0402LF',
 LOCATION='R1146',
 CDS_LIB='pure_quanta',
 CDS_PART_NAME='Q_RES_0402LF-0,5%,1/16W,EMPTY,CS00002JB13',
 PART_NUMBER='CS00002JB13',
 VALUE='0',
 PRIM_FILE='./archive_libs/logical/q_res/chips/chips.prt';

PART_NAME
 R1147 'Q_RES_0402LF-0,5%,1/16W,EMPTY,CS00002JB13':;

SECTION_NUMBER 1
 '@T6G_MB_LIB.T6G(SCH_1):PAGE257_I39@PURE_QUANTA.Q_RES(CHIPS)':
 C_PATH='@t6g_mb_lib.t6g(sch_1):page257_i39@pure_quanta.q_res(chips)',
 P_PATH='@t6g_mb_lib.t6g(sch_1):page142_i39@pure_quanta.q_res(chips)',
 PATH='I39',
 DRAWING='@T6G_MB_LIB.T6G(SCH_1):PAGE257',
 BOM_COST='MEM',
 WATTAGE='1/16W',
 TOLERANCE='5%',
 MATERIAL='EMPTY',
 PHYS_PAGE='142',
 XY='(625,-1300)',
 ROT='2',
 VER='1',
 PACK_TYPE='0402LF',
 LOCATION='R1147',
 CDS_LIB='pure_quanta',
 CDS_PART_NAME='Q_RES_0402LF-0,5%,1/16W,EMPTY,CS00002JB13',
 PART_NUMBER='CS00002JB13',
 VALUE='0',
 PRIM_FILE='./archive_libs/logical/q_res/chips/chips.prt';

PART_NAME
 R1148 'Q_RES_0402LF-0,5%,1/16W,CHIP,CS00002JB13':;

SECTION_NUMBER 1
 '@T6G_MB_LIB.T6G(SCH_1):PAGE338_I46@PURE_QUANTA.Q_RES(CHIPS)':
 C_PATH='@t6g_mb_lib.t6g(sch_1):page338_i46@pure_quanta.q_res(chips)',
 P_PATH='@t6g_mb_lib.t6g(sch_1):page134_i46@pure_quanta.q_res(chips)',
 PATH='I46',
 DRAWING='@T6G_MB_LIB.T6G(SCH_1):PAGE338',
 WATTAGE='1/16W',
 TOLERANCE='5%',
 MATERIAL='CHIP',
 PHYS_PAGE='134',
 XY='(6850,8900)',
 ROT='0',
 VER='1',
 PACK_TYPE='0402LF',
 LOCATION='R1148',
 CDS_LIB='pure_quanta',
 CDS_PART_NAME='Q_RES_0402LF-0,5%,1/16W,CHIP,CS00002JB13',
 PART_NUMBER='CS00002JB13',
 VALUE='0',
 PRIM_FILE='./archive_libs/logical/q_res/chips/chips.prt';

PART_NAME
 R1149 'Q_RES_0402LF-1K,1%,1/16W,CHIP,CS21002FB06':;

SECTION_NUMBER 1
 '@T6G_MB_LIB.T6G(SCH_1):PAGE257_I25@PURE_QUANTA.Q_RES(CHIPS)':
 C_PATH='@t6g_mb_lib.t6g(sch_1):page257_i25@pure_quanta.q_res(chips)',
 P_PATH='@t6g_mb_lib.t6g(sch_1):page142_i25@pure_quanta.q_res(chips)',
 PATH='I25',
 DRAWING='@T6G_MB_LIB.T6G(SCH_1):PAGE257',
 WATTAGE='1/16W',
 TOLERANCE='1%',
 MATERIAL='CHIP',
 PHYS_PAGE='142',
 XY='(-4075,3625)',
 ROT='2',
 VER='2',
 PACK_TYPE='0402LF',
 LOCATION='R1149',
 CDS_LIB='pure_quanta',
 CDS_PART_NAME='Q_RES_0402LF-1K,1%,1/16W,CHIP,CS21002FB06',
 PART_NUMBER='CS21002FB06',
 VALUE='1K',
 PRIM_FILE='./archive_libs/logical/q_res/chips/chips.prt';

PART_NAME
 R1150 'Q_RES_0402LF-10K,1%,1/16W,CHIP,CS31002FB08':;

SECTION_NUMBER 1
 '@T6G_MB_LIB.T6G(SCH_1):PAGE338_I71@PURE_QUANTA.Q_RES(CHIPS)':
 C_PATH='@t6g_mb_lib.t6g(sch_1):page338_i71@pure_quanta.q_res(chips)',
 P_PATH='@t6g_mb_lib.t6g(sch_1):page134_i71@pure_quanta.q_res(chips)',
 PATH='I71',
 DRAWING='@T6G_MB_LIB.T6G(SCH_1):PAGE338',
 WATTAGE='1/16W',
 TOLERANCE='1%',
 MATERIAL='CHIP',
 PHYS_PAGE='134',
 XY='(8350,9325)',
 ROT='0',
 VER='2',
 PACK_TYPE='0402LF',
 LOCATION='R1150',
 CDS_LIB='pure_quanta',
 CDS_PART_NAME='Q_RES_0402LF-10K,1%,1/16W,CHIP,CS31002FB08',
 PART_NUMBER='CS31002FB08',
 VALUE='10K',
 PRIM_FILE='./archive_libs/logical/q_res/chips/chips.prt';

PART_NAME
 R1151 'Q_RES_0402LF-0,5%,1/16W,EMPTY,CS00002JB13':;

SECTION_NUMBER 1
 '@T6G_MB_LIB.T6G(SCH_1):PAGE137_I93@PURE_QUANTA.Q_RES(CHIPS)':
 C_PATH='@t6g_mb_lib.t6g(sch_1):page137_i93@pure_quanta.q_res(chips)',
 P_PATH='@t6g_mb_lib.t6g(sch_1):page160_i93@pure_quanta.q_res(chips)',
 PATH='I93',
 DRAWING='@T6G_MB_LIB.T6G(SCH_1):PAGE137',
 WATTAGE='1/16W',
 TOLERANCE='5%',
 MATERIAL='EMPTY',
 PHYS_PAGE='160',
 XY='(-4100,2350)',
 ROT='0',
 VER='1',
 PACK_TYPE='0402LF',
 LOCATION='R1151',
 CDS_LIB='pure_quanta',
 CDS_PART_NAME='Q_RES_0402LF-0,5%,1/16W,EMPTY,CS00002JB13',
 PART_NUMBER='CS00002JB13',
 VALUE='0',
 PRIM_FILE='./archive_libs/logical/q_res/chips/chips.prt';

PART_NAME
 R1152 'Q_RES_0402LF-0,5%,1/16W,EMPTY,CS00002JB13':;

SECTION_NUMBER 1
 '@T6G_MB_LIB.T6G(SCH_1):PAGE137_I94@PURE_QUANTA.Q_RES(CHIPS)':
 C_PATH='@t6g_mb_lib.t6g(sch_1):page137_i94@pure_quanta.q_res(chips)',
 P_PATH='@t6g_mb_lib.t6g(sch_1):page160_i94@pure_quanta.q_res(chips)',
 PATH='I94',
 DRAWING='@T6G_MB_LIB.T6G(SCH_1):PAGE137',
 WATTAGE='1/16W',
 TOLERANCE='5%',
 MATERIAL='EMPTY',
 PHYS_PAGE='160',
 XY='(-4100,2250)',
 ROT='0',
 VER='1',
 PACK_TYPE='0402LF',
 LOCATION='R1152',
 CDS_LIB='pure_quanta',
 CDS_PART_NAME='Q_RES_0402LF-0,5%,1/16W,EMPTY,CS00002JB13',
 PART_NUMBER='CS00002JB13',
 VALUE='0',
 PRIM_FILE='./archive_libs/logical/q_res/chips/chips.prt';

PART_NAME
 R1153 'Q_RES_0402LF-0,5%,1/16W,CHIP,CS00002JB13':;

SECTION_NUMBER 1
 '@T6G_MB_LIB.T6G(SCH_1):PAGE137_I16@PURE_QUANTA.Q_RES(CHIPS)':
 C_PATH='@t6g_mb_lib.t6g(sch_1):page137_i16@pure_quanta.q_res(chips)',
 P_PATH='@t6g_mb_lib.t6g(sch_1):page160_i16@pure_quanta.q_res(chips)',
 PATH='I16',
 DRAWING='@T6G_MB_LIB.T6G(SCH_1):PAGE137',
 WATTAGE='1/16W',
 TOLERANCE='5%',
 MATERIAL='CHIP',
 PHYS_PAGE='160',
 XY='(-3900,-1575)',
 ROT='0',
 VER='1',
 PACK_TYPE='0402LF',
 LOCATION='R1153',
 CDS_LIB='pure_quanta',
 CDS_PART_NAME='Q_RES_0402LF-0,5%,1/16W,CHIP,CS00002JB13',
 PART_NUMBER='CS00002JB13',
 VALUE='0',
 PRIM_FILE='./archive_libs/logical/q_res/chips/chips.prt';

PART_NAME
 R1154 'Q_RES_0402LF-0,5%,1/16W,CHIP,CS00002JB13':;

SECTION_NUMBER 1
 '@T6G_MB_LIB.T6G(SCH_1):PAGE137_I15@PURE_QUANTA.Q_RES(CHIPS)':
 C_PATH='@t6g_mb_lib.t6g(sch_1):page137_i15@pure_quanta.q_res(chips)',
 P_PATH='@t6g_mb_lib.t6g(sch_1):page160_i15@pure_quanta.q_res(chips)',
 PATH='I15',
 DRAWING='@T6G_MB_LIB.T6G(SCH_1):PAGE137',
 WATTAGE='1/16W',
 TOLERANCE='5%',
 MATERIAL='CHIP',
 PHYS_PAGE='160',
 XY='(-3900,-1675)',
 ROT='0',
 VER='1',
 PACK_TYPE='0402LF',
 LOCATION='R1154',
 CDS_LIB='pure_quanta',
 CDS_PART_NAME='Q_RES_0402LF-0,5%,1/16W,CHIP,CS00002JB13',
 PART_NUMBER='CS00002JB13',
 VALUE='0',
 PRIM_FILE='./archive_libs/logical/q_res/chips/chips.prt';

PART_NAME
 R1155 'Q_RES_0402LF-33,5%,1/16W,EMPTY,CS03302JB10':;

SECTION_NUMBER 1
 '@T6G_MB_LIB.T6G(SCH_1):PAGE138_I39@PURE_QUANTA.Q_RES(CHIPS)':
 C_PATH='@t6g_mb_lib.t6g(sch_1):page138_i39@pure_quanta.q_res(chips)',
 P_PATH='@t6g_mb_lib.t6g(sch_1):page161_i39@pure_quanta.q_res(chips)',
 PATH='I39',
 DRAWING='@T6G_MB_LIB.T6G(SCH_1):PAGE138',
 WATTAGE='1/16W',
 TOLERANCE='5%',
 MATERIAL='EMPTY',
 PHYS_PAGE='161',
 XY='(3150,4025)',
 ROT='0',
 VER='1',
 PACK_TYPE='0402LF',
 LOCATION='R1155',
 CDS_LIB='pure_quanta',
 CDS_PART_NAME='Q_RES_0402LF-33,5%,1/16W,EMPTY,CS03302JB10',
 PART_NUMBER='CS03302JB10',
 VALUE='33',
 PRIM_FILE='./archive_libs/logical/q_res/chips/chips.prt';

PART_NAME
 R1156 'Q_RES_0402LF-33,5%,1/16W,EMPTY,CS03302JB10':;

SECTION_NUMBER 1
 '@T6G_MB_LIB.T6G(SCH_1):PAGE138_I38@PURE_QUANTA.Q_RES(CHIPS)':
 C_PATH='@t6g_mb_lib.t6g(sch_1):page138_i38@pure_quanta.q_res(chips)',
 P_PATH='@t6g_mb_lib.t6g(sch_1):page161_i38@pure_quanta.q_res(chips)',
 PATH='I38',
 DRAWING='@T6G_MB_LIB.T6G(SCH_1):PAGE138',
 WATTAGE='1/16W',
 TOLERANCE='5%',
 MATERIAL='EMPTY',
 PHYS_PAGE='161',
 XY='(3150,3975)',
 ROT='0',
 VER='1',
 PACK_TYPE='0402LF',
 LOCATION='R1156',
 CDS_LIB='pure_quanta',
 CDS_PART_NAME='Q_RES_0402LF-33,5%,1/16W,EMPTY,CS03302JB10',
 PART_NUMBER='CS03302JB10',
 VALUE='33',
 PRIM_FILE='./archive_libs/logical/q_res/chips/chips.prt';

PART_NAME
 R1157 'Q_RES_0402LF-33,5%,1/16W,EMPTY,CS03302JB10':;

SECTION_NUMBER 1
 '@T6G_MB_LIB.T6G(SCH_1):PAGE138_I74@PURE_QUANTA.Q_RES(CHIPS)':
 C_PATH='@t6g_mb_lib.t6g(sch_1):page138_i74@pure_quanta.q_res(chips)',
 P_PATH='@t6g_mb_lib.t6g(sch_1):page161_i74@pure_quanta.q_res(chips)',
 PATH='I74',
 DRAWING='@T6G_MB_LIB.T6G(SCH_1):PAGE138',
 WATTAGE='1/16W',
 TOLERANCE='5%',
 MATERIAL='EMPTY',
 PHYS_PAGE='161',
 XY='(3150,3875)',
 ROT='0',
 VER='1',
 PACK_TYPE='0402LF',
 LOCATION='R1157',
 CDS_LIB='pure_quanta',
 CDS_PART_NAME='Q_RES_0402LF-33,5%,1/16W,EMPTY,CS03302JB10',
 PART_NUMBER='CS03302JB10',
 VALUE='33',
 PRIM_FILE='./archive_libs/logical/q_res/chips/chips.prt';

PART_NAME
 R1158 'Q_RES_0402LF-33,5%,1/16W,EMPTY,CS03302JB10':;

SECTION_NUMBER 1
 '@T6G_MB_LIB.T6G(SCH_1):PAGE138_I73@PURE_QUANTA.Q_RES(CHIPS)':
 C_PATH='@t6g_mb_lib.t6g(sch_1):page138_i73@pure_quanta.q_res(chips)',
 P_PATH='@t6g_mb_lib.t6g(sch_1):page161_i73@pure_quanta.q_res(chips)',
 PATH='I73',
 DRAWING='@T6G_MB_LIB.T6G(SCH_1):PAGE138',
 WATTAGE='1/16W',
 TOLERANCE='5%',
 MATERIAL='EMPTY',
 PHYS_PAGE='161',
 XY='(3150,3825)',
 ROT='0',
 VER='1',
 PACK_TYPE='0402LF',
 LOCATION='R1158',
 CDS_LIB='pure_quanta',
 CDS_PART_NAME='Q_RES_0402LF-33,5%,1/16W,EMPTY,CS03302JB10',
 PART_NUMBER='CS03302JB10',
 VALUE='33',
 PRIM_FILE='./archive_libs/logical/q_res/chips/chips.prt';

PART_NAME
 R1159 'Q_RES_0402LF-0,5%,1/16W,CHIP,CS00002JB13':;

SECTION_NUMBER 1
 '@T6G_MB_LIB.T6G(SCH_1):PAGE138_I76@PURE_QUANTA.Q_RES(CHIPS)':
 C_PATH='@t6g_mb_lib.t6g(sch_1):page138_i76@pure_quanta.q_res(chips)',
 P_PATH='@t6g_mb_lib.t6g(sch_1):page161_i76@pure_quanta.q_res(chips)',
 PATH='I76',
 DRAWING='@T6G_MB_LIB.T6G(SCH_1):PAGE138',
 WATTAGE='1/16W',
 TOLERANCE='5%',
 MATERIAL='CHIP',
 PHYS_PAGE='161',
 XY='(3175,1925)',
 ROT='0',
 VER='1',
 PACK_TYPE='0402LF',
 LOCATION='R1159',
 CDS_LIB='pure_quanta',
 CDS_PART_NAME='Q_RES_0402LF-0,5%,1/16W,CHIP,CS00002JB13',
 PART_NUMBER='CS00002JB13',
 VALUE='0',
 PRIM_FILE='./archive_libs/logical/q_res/chips/chips.prt';

PART_NAME
 R1160 'Q_RES_0402LF-0,5%,1/16W,CHIP,CS00002JB13':;

SECTION_NUMBER 1
 '@T6G_MB_LIB.T6G(SCH_1):PAGE138_I75@PURE_QUANTA.Q_RES(CHIPS)':
 C_PATH='@t6g_mb_lib.t6g(sch_1):page138_i75@pure_quanta.q_res(chips)',
 P_PATH='@t6g_mb_lib.t6g(sch_1):page161_i75@pure_quanta.q_res(chips)',
 PATH='I75',
 DRAWING='@T6G_MB_LIB.T6G(SCH_1):PAGE138',
 WATTAGE='1/16W',
 TOLERANCE='5%',
 MATERIAL='CHIP',
 PHYS_PAGE='161',
 XY='(3175,1875)',
 ROT='0',
 VER='1',
 PACK_TYPE='0402LF',
 LOCATION='R1160',
 CDS_LIB='pure_quanta',
 CDS_PART_NAME='Q_RES_0402LF-0,5%,1/16W,CHIP,CS00002JB13',
 PART_NUMBER='CS00002JB13',
 VALUE='0',
 PRIM_FILE='./archive_libs/logical/q_res/chips/chips.prt';

PART_NAME
 R1161 'Q_RES_0402LF-0,5%,1/16W,CHIP,CS00002JB13':;

SECTION_NUMBER 1
 '@T6G_MB_LIB.T6G(SCH_1):PAGE138_I23@PURE_QUANTA.Q_RES(CHIPS)':
 C_PATH='@t6g_mb_lib.t6g(sch_1):page138_i23@pure_quanta.q_res(chips)',
 P_PATH='@t6g_mb_lib.t6g(sch_1):page161_i23@pure_quanta.q_res(chips)',
 PATH='I23',
 DRAWING='@T6G_MB_LIB.T6G(SCH_1):PAGE138',
 WATTAGE='1/16W',
 TOLERANCE='5%',
 MATERIAL='CHIP',
 PHYS_PAGE='161',
 XY='(3175,1825)',
 ROT='0',
 VER='1',
 PACK_TYPE='0402LF',
 LOCATION='R1161',
 CDS_LIB='pure_quanta',
 CDS_PART_NAME='Q_RES_0402LF-0,5%,1/16W,CHIP,CS00002JB13',
 PART_NUMBER='CS00002JB13',
 VALUE='0',
 PRIM_FILE='./archive_libs/logical/q_res/chips/chips.prt';

PART_NAME
 R1162 'Q_RES_0402LF-0,5%,1/16W,CHIP,CS00002JB13':;

SECTION_NUMBER 1
 '@T6G_MB_LIB.T6G(SCH_1):PAGE138_I22@PURE_QUANTA.Q_RES(CHIPS)':
 C_PATH='@t6g_mb_lib.t6g(sch_1):page138_i22@pure_quanta.q_res(chips)',
 P_PATH='@t6g_mb_lib.t6g(sch_1):page161_i22@pure_quanta.q_res(chips)',
 PATH='I22',
 DRAWING='@T6G_MB_LIB.T6G(SCH_1):PAGE138',
 WATTAGE='1/16W',
 TOLERANCE='5%',
 MATERIAL='CHIP',
 PHYS_PAGE='161',
 XY='(3175,1775)',
 ROT='0',
 VER='1',
 PACK_TYPE='0402LF',
 LOCATION='R1162',
 CDS_LIB='pure_quanta',
 CDS_PART_NAME='Q_RES_0402LF-0,5%,1/16W,CHIP,CS00002JB13',
 PART_NUMBER='CS00002JB13',
 VALUE='0',
 PRIM_FILE='./archive_libs/logical/q_res/chips/chips.prt';

PART_NAME
 R1163 'Q_RES_0402LF-0,5%,1/16W,CHIP,CS00002JB13':;

SECTION_NUMBER 1
 '@T6G_MB_LIB.T6G(SCH_1):PAGE257_I3@PURE_QUANTA.Q_RES(CHIPS)':
 C_PATH='@t6g_mb_lib.t6g(sch_1):page257_i3@pure_quanta.q_res(chips)',
 P_PATH='@t6g_mb_lib.t6g(sch_1):page142_i3@pure_quanta.q_res(chips)',
 PATH='I3',
 DRAWING='@T6G_MB_LIB.T6G(SCH_1):PAGE257',
 WATTAGE='1/16W',
 TOLERANCE='5%',
 MATERIAL='CHIP',
 PHYS_PAGE='142',
 XY='(-4000,1575)',
 ROT='0',
 VER='1',
 PACK_TYPE='0402LF',
 LOCATION='R1163',
 CDS_LIB='pure_quanta',
 CDS_PART_NAME='Q_RES_0402LF-0,5%,1/16W,CHIP,CS00002JB13',
 PART_NUMBER='CS00002JB13',
 VALUE='0',
 PRIM_FILE='./archive_libs/logical/q_res/chips/chips.prt';

PART_NAME
 R1164 'Q_RES_0402LF-0,5%,1/16W,EMPTY,CS00002JB13':;

SECTION_NUMBER 1
 '@T6G_MB_LIB.T6G(SCH_1):PAGE257_I28@PURE_QUANTA.Q_RES(CHIPS)':
 C_PATH='@t6g_mb_lib.t6g(sch_1):page257_i28@pure_quanta.q_res(chips)',
 P_PATH='@t6g_mb_lib.t6g(sch_1):page142_i28@pure_quanta.q_res(chips)',
 PATH='I28',
 DRAWING='@T6G_MB_LIB.T6G(SCH_1):PAGE257',
 WATTAGE='1/16W',
 TOLERANCE='5%',
 MATERIAL='EMPTY',
 PHYS_PAGE='142',
 XY='(-2325,3425)',
 ROT='0',
 VER='1',
 PACK_TYPE='0402LF',
 LOCATION='R1164',
 CDS_LIB='pure_quanta',
 CDS_PART_NAME='Q_RES_0402LF-0,5%,1/16W,EMPTY,CS00002JB13',
 PART_NUMBER='CS00002JB13',
 VALUE='0',
 PRIM_FILE='./archive_libs/logical/q_res/chips/chips.prt';

PART_NAME
 R1165 'Q_RES_0402LF-1K,1%,1/16W,CHIP,CS21002FB06':;

SECTION_NUMBER 1
 '@T6G_MB_LIB.T6G(SCH_1):PAGE257_I32@PURE_QUANTA.Q_RES(CHIPS)':
 C_PATH='@t6g_mb_lib.t6g(sch_1):page257_i32@pure_quanta.q_res(chips)',
 P_PATH='@t6g_mb_lib.t6g(sch_1):page142_i32@pure_quanta.q_res(chips)',
 PATH='I32',
 DRAWING='@T6G_MB_LIB.T6G(SCH_1):PAGE257',
 WATTAGE='1/16W',
 TOLERANCE='1%',
 MATERIAL='CHIP',
 PHYS_PAGE='142',
 XY='(-1425,3850)',
 ROT='2',
 VER='2',
 PACK_TYPE='0402LF',
 LOCATION='R1165',
 CDS_LIB='pure_quanta',
 CDS_PART_NAME='Q_RES_0402LF-1K,1%,1/16W,CHIP,CS21002FB06',
 PART_NUMBER='CS21002FB06',
 VALUE='1K',
 PRIM_FILE='./archive_libs/logical/q_res/chips/chips.prt';

PART_NAME
 R1166 'Q_RES_0402LF-0,5%,1/16W,CHIP,CS00002JB13':;

SECTION_NUMBER 1
 '@T6G_MB_LIB.T6G(SCH_1):PAGE257_I18@PURE_QUANTA.Q_RES(CHIPS)':
 C_PATH='@t6g_mb_lib.t6g(sch_1):page257_i18@pure_quanta.q_res(chips)',
 P_PATH='@t6g_mb_lib.t6g(sch_1):page142_i18@pure_quanta.q_res(chips)',
 PATH='I18',
 DRAWING='@T6G_MB_LIB.T6G(SCH_1):PAGE257',
 WATTAGE='1/16W',
 TOLERANCE='5%',
 MATERIAL='CHIP',
 PHYS_PAGE='142',
 XY='(-1525,1575)',
 ROT='0',
 VER='1',
 PACK_TYPE='0402LF',
 LOCATION='R1166',
 CDS_LIB='pure_quanta',
 CDS_PART_NAME='Q_RES_0402LF-0,5%,1/16W,CHIP,CS00002JB13',
 PART_NUMBER='CS00002JB13',
 VALUE='0',
 PRIM_FILE='./archive_libs/logical/q_res/chips/chips.prt';

PART_NAME
 R1167 'Q_RES_0402LF-1K,1%,1/16W,CHIP,CS21002FB06':;

SECTION_NUMBER 1
 '@T6G_MB_LIB.T6G(SCH_1):PAGE257_I19@PURE_QUANTA.Q_RES(CHIPS)':
 C_PATH='@t6g_mb_lib.t6g(sch_1):page257_i19@pure_quanta.q_res(chips)',
 P_PATH='@t6g_mb_lib.t6g(sch_1):page142_i19@pure_quanta.q_res(chips)',
 PATH='I19',
 DRAWING='@T6G_MB_LIB.T6G(SCH_1):PAGE257',
 WATTAGE='1/16W',
 TOLERANCE='1%',
 MATERIAL='CHIP',
 PHYS_PAGE='142',
 XY='(-1075,1925)',
 ROT='2',
 VER='2',
 PACK_TYPE='0402LF',
 LOCATION='R1167',
 CDS_LIB='pure_quanta',
 CDS_PART_NAME='Q_RES_0402LF-1K,1%,1/16W,CHIP,CS21002FB06',
 PART_NUMBER='CS21002FB06',
 VALUE='1K',
 PRIM_FILE='./archive_libs/logical/q_res/chips/chips.prt';

PART_NAME
 R1168 'Q_RES_0402LF-0,5%,1/16W,CHIP,CS00002JB13':;

SECTION_NUMBER 1
 '@T6G_MB_LIB.T6G(SCH_1):PAGE257_I57@PURE_QUANTA.Q_RES(CHIPS)':
 C_PATH='@t6g_mb_lib.t6g(sch_1):page257_i57@pure_quanta.q_res(chips)',
 P_PATH='@t6g_mb_lib.t6g(sch_1):page142_i57@pure_quanta.q_res(chips)',
 PATH='I57',
 DRAWING='@T6G_MB_LIB.T6G(SCH_1):PAGE257',
 WATTAGE='1/16W',
 TOLERANCE='5%',
 MATERIAL='CHIP',
 PHYS_PAGE='142',
 XY='(450,3275)',
 ROT='0',
 VER='1',
 PACK_TYPE='0402LF',
 LOCATION='R1168',
 CDS_LIB='pure_quanta',
 CDS_PART_NAME='Q_RES_0402LF-0,5%,1/16W,CHIP,CS00002JB13',
 PART_NUMBER='CS00002JB13',
 VALUE='0',
 PRIM_FILE='./archive_libs/logical/q_res/chips/chips.prt';

PART_NAME
 R1169 'Q_RES_0402LF-0,5%,1/16W,CHIP,CS00002JB13':;

SECTION_NUMBER 1
 '@T6G_MB_LIB.T6G(SCH_1):PAGE257_I34@PURE_QUANTA.Q_RES(CHIPS)':
 C_PATH='@t6g_mb_lib.t6g(sch_1):page257_i34@pure_quanta.q_res(chips)',
 P_PATH='@t6g_mb_lib.t6g(sch_1):page142_i34@pure_quanta.q_res(chips)',
 PATH='I34',
 DRAWING='@T6G_MB_LIB.T6G(SCH_1):PAGE257',
 WATTAGE='1/16W',
 TOLERANCE='5%',
 MATERIAL='CHIP',
 PHYS_PAGE='142',
 XY='(-650,2350)',
 ROT='0',
 VER='1',
 PACK_TYPE='0402LF',
 LOCATION='R1169',
 CDS_LIB='pure_quanta',
 CDS_PART_NAME='Q_RES_0402LF-0,5%,1/16W,CHIP,CS00002JB13',
 PART_NUMBER='CS00002JB13',
 VALUE='0',
 PRIM_FILE='./archive_libs/logical/q_res/chips/chips.prt';

PART_NAME
 R1170 'Q_RES_0402LF-0,5%,1/16W,CHIP,CS00002JB13':;

SECTION_NUMBER 1
 '@T6G_MB_LIB.T6G(SCH_1):PAGE257_I58@PURE_QUANTA.Q_RES(CHIPS)':
 C_PATH='@t6g_mb_lib.t6g(sch_1):page257_i58@pure_quanta.q_res(chips)',
 P_PATH='@t6g_mb_lib.t6g(sch_1):page142_i58@pure_quanta.q_res(chips)',
 PATH='I58',
 DRAWING='@T6G_MB_LIB.T6G(SCH_1):PAGE257',
 WATTAGE='1/16W',
 TOLERANCE='5%',
 MATERIAL='CHIP',
 PHYS_PAGE='142',
 XY='(1775,2350)',
 ROT='0',
 VER='1',
 PACK_TYPE='0402LF',
 LOCATION='R1170',
 CDS_LIB='pure_quanta',
 CDS_PART_NAME='Q_RES_0402LF-0,5%,1/16W,CHIP,CS00002JB13',
 PART_NUMBER='CS00002JB13',
 VALUE='0',
 PRIM_FILE='./archive_libs/logical/q_res/chips/chips.prt';

PART_NAME
 R1171 'Q_RES_0402LF-1K,1%,1/16W,CHIP,CS21002FB06':;

SECTION_NUMBER 1
 '@T6G_MB_LIB.T6G(SCH_1):PAGE257_I60@PURE_QUANTA.Q_RES(CHIPS)':
 C_PATH='@t6g_mb_lib.t6g(sch_1):page257_i60@pure_quanta.q_res(chips)',
 P_PATH='@t6g_mb_lib.t6g(sch_1):page142_i60@pure_quanta.q_res(chips)',
 PATH='I60',
 DRAWING='@T6G_MB_LIB.T6G(SCH_1):PAGE257',
 WATTAGE='1/16W',
 TOLERANCE='1%',
 MATERIAL='CHIP',
 PHYS_PAGE='142',
 XY='(2275,2700)',
 ROT='2',
 VER='2',
 PACK_TYPE='0402LF',
 LOCATION='R1171',
 CDS_LIB='pure_quanta',
 CDS_PART_NAME='Q_RES_0402LF-1K,1%,1/16W,CHIP,CS21002FB06',
 PART_NUMBER='CS21002FB06',
 VALUE='1K',
 PRIM_FILE='./archive_libs/logical/q_res/chips/chips.prt';

PART_NAME
 R1172 'Q_RES_0402LF-10K,5%,1/16W,EMPTY,CS31002JB08':;

SECTION_NUMBER 1
 '@T6G_MB_LIB.T6G(SCH_1):PAGE257_I51@PURE_QUANTA.Q_RES(CHIPS)':
 C_PATH='@t6g_mb_lib.t6g(sch_1):page257_i51@pure_quanta.q_res(chips)',
 P_PATH='@t6g_mb_lib.t6g(sch_1):page142_i51@pure_quanta.q_res(chips)',
 PATH='I51',
 DRAWING='@T6G_MB_LIB.T6G(SCH_1):PAGE257',
 WATTAGE='1/16W',
 TOLERANCE='5%',
 MATERIAL='EMPTY',
 PHYS_PAGE='142',
 XY='(2500,-25)',
 ROT='0',
 VER='2',
 PACK_TYPE='0402LF',
 LOCATION='R1172',
 CDS_LIB='pure_quanta',
 CDS_PART_NAME='Q_RES_0402LF-10K,5%,1/16W,EMPTY,CS31002JB08',
 PART_NUMBER='CS31002JB08',
 VALUE='10K',
 PRIM_FILE='./archive_libs/logical/q_res/chips/chips.prt';

PART_NAME
 R1173 'Q_RES_0402LF-33.2,1%,1/16W,CHIP,CS03322FB03':;

SECTION_NUMBER 1
 '@T6G_MB_LIB.T6G(SCH_1):PAGE257_I16@PURE_QUANTA.Q_RES(CHIPS)':
 C_PATH='@t6g_mb_lib.t6g(sch_1):page257_i16@pure_quanta.q_res(chips)',
 P_PATH='@t6g_mb_lib.t6g(sch_1):page142_i16@pure_quanta.q_res(chips)',
 PATH='I16',
 DRAWING='@T6G_MB_LIB.T6G(SCH_1):PAGE257',
 WATTAGE='1/16W',
 TOLERANCE='1%',
 MATERIAL='CHIP',
 PHYS_PAGE='142',
 XY='(-1200,725)',
 ROT='0',
 VER='1',
 PACK_TYPE='0402LF',
 LOCATION='R1173',
 CDS_LIB='pure_quanta',
 CDS_PART_NAME='Q_RES_0402LF-33.2,1%,1/16W,CHIP,CS03322FB03',
 PART_NUMBER='CS03322FB03',
 VALUE='33.2',
 PRIM_FILE='./archive_libs/logical/q_res/chips/chips.prt';

PART_NAME
 R1174 'Q_RES_0402LF-33.2,1%,1/16W,CHIP,CS03322FB03':;

SECTION_NUMBER 1
 '@T6G_MB_LIB.T6G(SCH_1):PAGE257_I17@PURE_QUANTA.Q_RES(CHIPS)':
 C_PATH='@t6g_mb_lib.t6g(sch_1):page257_i17@pure_quanta.q_res(chips)',
 P_PATH='@t6g_mb_lib.t6g(sch_1):page142_i17@pure_quanta.q_res(chips)',
 PATH='I17',
 DRAWING='@T6G_MB_LIB.T6G(SCH_1):PAGE257',
 WATTAGE='1/16W',
 TOLERANCE='1%',
 MATERIAL='CHIP',
 PHYS_PAGE='142',
 XY='(-1200,825)',
 ROT='0',
 VER='1',
 PACK_TYPE='0402LF',
 LOCATION='R1174',
 CDS_LIB='pure_quanta',
 CDS_PART_NAME='Q_RES_0402LF-33.2,1%,1/16W,CHIP,CS03322FB03',
 PART_NUMBER='CS03322FB03',
 VALUE='33.2',
 PRIM_FILE='./archive_libs/logical/q_res/chips/chips.prt';

PART_NAME
 R1175 'Q_RES_0402LF-33.2,1%,1/16W,CHIP,CS03322FB03':;

SECTION_NUMBER 1
 '@T6G_MB_LIB.T6G(SCH_1):PAGE257_I42@PURE_QUANTA.Q_RES(CHIPS)':
 C_PATH='@t6g_mb_lib.t6g(sch_1):page257_i42@pure_quanta.q_res(chips)',
 P_PATH='@t6g_mb_lib.t6g(sch_1):page142_i42@pure_quanta.q_res(chips)',
 PATH='I42',
 DRAWING='@T6G_MB_LIB.T6G(SCH_1):PAGE257',
 WATTAGE='1/16W',
 TOLERANCE='1%',
 MATERIAL='CHIP',
 PHYS_PAGE='142',
 XY='(1625,-500)',
 ROT='0',
 VER='1',
 PACK_TYPE='0402LF',
 LOCATION='R1175',
 CDS_LIB='pure_quanta',
 CDS_PART_NAME='Q_RES_0402LF-33.2,1%,1/16W,CHIP,CS03322FB03',
 PART_NUMBER='CS03322FB03',
 VALUE='33.2',
 PRIM_FILE='./archive_libs/logical/q_res/chips/chips.prt';

PART_NAME
 R1176 'Q_RES_0402LF-10K,1%,1/16W,CHIP,CS31002FB08':;

SECTION_NUMBER 1
 '@T6G_MB_LIB.T6G(SCH_1):PAGE257_I10@PURE_QUANTA.Q_RES(CHIPS)':
 C_PATH='@t6g_mb_lib.t6g(sch_1):page257_i10@pure_quanta.q_res(chips)',
 P_PATH='@t6g_mb_lib.t6g(sch_1):page142_i10@pure_quanta.q_res(chips)',
 PATH='I10',
 DRAWING='@T6G_MB_LIB.T6G(SCH_1):PAGE257',
 WATTAGE='1/16W',
 TOLERANCE='1%',
 MATERIAL='CHIP',
 PHYS_PAGE='142',
 XY='(-1825,-225)',
 ROT='2',
 VER='2',
 PACK_TYPE='0402LF',
 LOCATION='R1176',
 CDS_LIB='pure_quanta',
 CDS_PART_NAME='Q_RES_0402LF-10K,1%,1/16W,CHIP,CS31002FB08',
 PART_NUMBER='CS31002FB08',
 VALUE='10K',
 PRIM_FILE='./archive_libs/logical/q_res/chips/chips.prt';

PART_NAME
 R1177 'Q_RES_0402LF-33.2,1%,1/16W,CHIP,CS03322FB03':;

SECTION_NUMBER 1
 '@T6G_MB_LIB.T6G(SCH_1):PAGE257_I49@PURE_QUANTA.Q_RES(CHIPS)':
 C_PATH='@t6g_mb_lib.t6g(sch_1):page257_i49@pure_quanta.q_res(chips)',
 P_PATH='@t6g_mb_lib.t6g(sch_1):page142_i49@pure_quanta.q_res(chips)',
 PATH='I49',
 DRAWING='@T6G_MB_LIB.T6G(SCH_1):PAGE257',
 WATTAGE='1/16W',
 TOLERANCE='1%',
 MATERIAL='CHIP',
 PHYS_PAGE='142',
 XY='(1850,675)',
 ROT='0',
 VER='1',
 PACK_TYPE='0402LF',
 LOCATION='R1177',
 CDS_LIB='pure_quanta',
 CDS_PART_NAME='Q_RES_0402LF-33.2,1%,1/16W,CHIP,CS03322FB03',
 PART_NUMBER='CS03322FB03',
 VALUE='33.2',
 PRIM_FILE='./archive_libs/logical/q_res/chips/chips.prt';

PART_NAME
 R1178 'Q_RES_0402LF-33.2,1%,1/16W,CHIP,CS03322FB03':;

SECTION_NUMBER 1
 '@T6G_MB_LIB.T6G(SCH_1):PAGE257_I12@PURE_QUANTA.Q_RES(CHIPS)':
 C_PATH='@t6g_mb_lib.t6g(sch_1):page257_i12@pure_quanta.q_res(chips)',
 P_PATH='@t6g_mb_lib.t6g(sch_1):page142_i12@pure_quanta.q_res(chips)',
 PATH='I12',
 DRAWING='@T6G_MB_LIB.T6G(SCH_1):PAGE257',
 WATTAGE='1/16W',
 TOLERANCE='1%',
 MATERIAL='CHIP',
 PHYS_PAGE='142',
 XY='(-1275,-450)',
 ROT='0',
 VER='1',
 PACK_TYPE='0402LF',
 LOCATION='R1178',
 CDS_LIB='pure_quanta',
 CDS_PART_NAME='Q_RES_0402LF-33.2,1%,1/16W,CHIP,CS03322FB03',
 PART_NUMBER='CS03322FB03',
 VALUE='33.2',
 PRIM_FILE='./archive_libs/logical/q_res/chips/chips.prt';

PART_NAME
 R1179 'Q_RES_0402LF-0,5%,1/16W,CHIP,CS00002JB13':;

SECTION_NUMBER 1
 '@T6G_MB_LIB.T6G(SCH_1):PAGE79_I155@PURE_QUANTA.Q_RES(CHIPS)':
 C_PATH='@t6g_mb_lib.t6g(sch_1):page79_i155@pure_quanta.q_res(chips)',
 P_PATH='@t6g_mb_lib.t6g(sch_1):page80_i155@pure_quanta.q_res(chips)',
 PATH='I155',
 DRAWING='@T6G_MB_LIB.T6G(SCH_1):PAGE79',
 BOM_COST='MEM',
 WATTAGE='1/16W',
 TOLERANCE='5%',
 MATERIAL='CHIP',
 PHYS_PAGE='80',
 XY='(-2675,3400)',
 ROT='2',
 VER='1',
 PACK_TYPE='0402LF',
 LOCATION='R1179',
 CDS_LIB='pure_quanta',
 CDS_PART_NAME='Q_RES_0402LF-0,5%,1/16W,CHIP,CS00002JB13',
 PART_NUMBER='CS00002JB13',
 VALUE='0',
 PRIM_FILE='./archive_libs/logical/q_res/chips/chips.prt';

PART_NAME
 R1180 'Q_RES_0402LF-0,5%,1/16W,EMPTY,CS00002JB13':;

SECTION_NUMBER 1
 '@T6G_MB_LIB.T6G(SCH_1):PAGE248_I45@PURE_QUANTA.Q_RES(CHIPS)':
 C_PATH='@t6g_mb_lib.t6g(sch_1):page248_i45@pure_quanta.q_res(chips)',
 P_PATH='@t6g_mb_lib.t6g(sch_1):page247_i45@pure_quanta.q_res(chips)',
 PATH='I45',
 DRAWING='@T6G_MB_LIB.T6G(SCH_1):PAGE248',
 WATTAGE='1/16W',
 TOLERANCE='5%',
 MATERIAL='EMPTY',
 PHYS_PAGE='247',
 XY='(-3350,2850)',
 ROT='0',
 VER='1',
 PACK_TYPE='0402LF',
 LOCATION='R1180',
 CDS_LIB='pure_quanta',
 CDS_PART_NAME='Q_RES_0402LF-0,5%,1/16W,EMPTY,CS00002JB13',
 PART_NUMBER='CS00002JB13',
 VALUE='0',
 PRIM_FILE='./archive_libs/logical/q_res/chips/chips.prt';

PART_NAME
 R1181 'Q_RES_0402LF-0,5%,1/16W,CHIP,CS00002JB13':
 ROOM='NIC_P12V_MAM_TIC_BOM1';

SECTION_NUMBER 1
 '@T6G_MB_LIB.T6G(SCH_1):PAGE343_I123@PURE_QUANTA.Q_RES(CHIPS)':
 C_PATH='@t6g_mb_lib.t6g(sch_1):page343_i123@pure_quanta.q_res(chips)',
 P_PATH='@t6g_mb_lib.t6g(sch_1):page140_i123@pure_quanta.q_res(chips)',
 PATH='I123',
 DRAWING='@T6G_MB_LIB.T6G(SCH_1):PAGE343',
 WATTAGE='1/16W',
 TOLERANCE='5%',
 MATERIAL='CHIP',
 PHYS_PAGE='140',
 XY='(-3250,6350)',
 ROT='0',
 VER='1',
 PACK_TYPE='0402LF',
 LOCATION='R1181',
 CDS_LIB='pure_quanta',
 CDS_PART_NAME='Q_RES_0402LF-0,5%,1/16W,CHIP,CS00002JB13',
 ROOM='NIC_P12V_MAM_TIC_BOM1',
 PART_NUMBER='CS00002JB13',
 VALUE='0',
 PRIM_FILE='./archive_libs/logical/q_res/chips/chips.prt';

PART_NAME
 R1182 'Q_RES_0402LF-0,5%,1/16W,EMPTY,CS00002JB13':
 ROOM='NIC_P3V3_BOM1';

SECTION_NUMBER 1
 '@T6G_MB_LIB.T6G(SCH_1):PAGE343_I129@PURE_QUANTA.Q_RES(CHIPS)':
 C_PATH='@t6g_mb_lib.t6g(sch_1):page343_i129@pure_quanta.q_res(chips)',
 P_PATH='@t6g_mb_lib.t6g(sch_1):page140_i129@pure_quanta.q_res(chips)',
 PATH='I129',
 DRAWING='@T6G_MB_LIB.T6G(SCH_1):PAGE343',
 WATTAGE='1/16W',
 TOLERANCE='5%',
 MATERIAL='EMPTY',
 PHYS_PAGE='140',
 XY='(-3175,8275)',
 ROT='0',
 VER='1',
 PACK_TYPE='0402LF',
 LOCATION='R1182',
 CDS_LIB='pure_quanta',
 CDS_PART_NAME='Q_RES_0402LF-0,5%,1/16W,EMPTY,CS00002JB13',
 ROOM='NIC_P3V3_BOM1',
 PART_NUMBER='CS00002JB13',
 VALUE='0',
 PRIM_FILE='./archive_libs/logical/q_res/chips/chips.prt';

PART_NAME
 R1183 'Q_RES_0402LF-1K,1%,1/16W,CHIP,CS21002FB06':
 ROOM='';

SECTION_NUMBER 1
 '@T6G_MB_LIB.T6G(SCH_1):PAGE102_I188@PURE_QUANTA.Q_RES(CHIPS)':
 C_PATH='@t6g_mb_lib.t6g(sch_1):page102_i188@pure_quanta.q_res(chips)',
 P_PATH='@t6g_mb_lib.t6g(sch_1):page103_i188@pure_quanta.q_res(chips)',
 PATH='I188',
 DRAWING='@T6G_MB_LIB.T6G(SCH_1):PAGE102',
 BOM_COST='MEM',
 WATTAGE='1/16W',
 TOLERANCE='1%',
 MATERIAL='CHIP',
 PHYS_PAGE='103',
 XY='(-8600,2275)',
 ROT='2',
 VER='1',
 PACK_TYPE='0402LF',
 LOCATION='R1183',
 CDS_LIB='pure_quanta',
 CDS_PART_NAME='Q_RES_0402LF-1K,1%,1/16W,CHIP,CS21002FB06',
 ROOM='',
 PART_NUMBER='CS21002FB06',
 VALUE='1K',
 PRIM_FILE='./archive_libs/logical/q_res/chips/chips.prt';

PART_NAME
 R1184 'Q_RES_0402LF-1K,1%,1/16W,CHIP,CS21002FB06':
 ROOM='';

SECTION_NUMBER 1
 '@T6G_MB_LIB.T6G(SCH_1):PAGE103_I188@PURE_QUANTA.Q_RES(CHIPS)':
 C_PATH='@t6g_mb_lib.t6g(sch_1):page103_i188@pure_quanta.q_res(chips)',
 P_PATH='@t6g_mb_lib.t6g(sch_1):page104_i188@pure_quanta.q_res(chips)',
 PATH='I188',
 DRAWING='@T6G_MB_LIB.T6G(SCH_1):PAGE103',
 BOM_COST='MEM',
 WATTAGE='1/16W',
 TOLERANCE='1%',
 MATERIAL='CHIP',
 PHYS_PAGE='104',
 XY='(-8400,2100)',
 ROT='2',
 VER='1',
 PACK_TYPE='0402LF',
 LOCATION='R1184',
 CDS_LIB='pure_quanta',
 CDS_PART_NAME='Q_RES_0402LF-1K,1%,1/16W,CHIP,CS21002FB06',
 ROOM='',
 PART_NUMBER='CS21002FB06',
 VALUE='1K',
 PRIM_FILE='./archive_libs/logical/q_res/chips/chips.prt';

PART_NAME
 R1185 'Q_RES_0402LF-1K,1%,1/16W,CHIP,CS21002FB06':;

SECTION_NUMBER 1
 '@T6G_MB_LIB.T6G(SCH_1):PAGE82_I62@PURE_QUANTA.Q_RES(CHIPS)':
 C_PATH='@t6g_mb_lib.t6g(sch_1):page82_i62@pure_quanta.q_res(chips)',
 P_PATH='@t6g_mb_lib.t6g(sch_1):page83_i62@pure_quanta.q_res(chips)',
 PATH='I62',
 DRAWING='@T6G_MB_LIB.T6G(SCH_1):PAGE82',
 WATTAGE='1/16W',
 TOLERANCE='1%',
 MATERIAL='CHIP',
 PHYS_PAGE='83',
 XY='(-7050,5575)',
 ROT='0',
 VER='1',
 PACK_TYPE='0402LF',
 LOCATION='R1185',
 CDS_LIB='pure_quanta',
 CDS_PART_NAME='Q_RES_0402LF-1K,1%,1/16W,CHIP,CS21002FB06',
 PART_NUMBER='CS21002FB06',
 VALUE='1K',
 PRIM_FILE='./archive_libs/logical/q_res/chips/chips.prt';

PART_NAME
 R1186 'Q_RES_0402LF-1K,1%,1/16W,CHIP,CS21002FB06':;

SECTION_NUMBER 1
 '@T6G_MB_LIB.T6G(SCH_1):PAGE82_I60@PURE_QUANTA.Q_RES(CHIPS)':
 C_PATH='@t6g_mb_lib.t6g(sch_1):page82_i60@pure_quanta.q_res(chips)',
 P_PATH='@t6g_mb_lib.t6g(sch_1):page83_i60@pure_quanta.q_res(chips)',
 PATH='I60',
 DRAWING='@T6G_MB_LIB.T6G(SCH_1):PAGE82',
 WATTAGE='1/16W',
 TOLERANCE='1%',
 MATERIAL='CHIP',
 PHYS_PAGE='83',
 XY='(-7050,5525)',
 ROT='0',
 VER='1',
 PACK_TYPE='0402LF',
 LOCATION='R1186',
 CDS_LIB='pure_quanta',
 CDS_PART_NAME='Q_RES_0402LF-1K,1%,1/16W,CHIP,CS21002FB06',
 PART_NUMBER='CS21002FB06',
 VALUE='1K',
 PRIM_FILE='./archive_libs/logical/q_res/chips/chips.prt';

PART_NAME
 R1187 'Q_RES_0402LF-1K,1%,1/16W,CHIP,CS21002FB06':;

SECTION_NUMBER 1
 '@T6G_MB_LIB.T6G(SCH_1):PAGE82_I59@PURE_QUANTA.Q_RES(CHIPS)':
 C_PATH='@t6g_mb_lib.t6g(sch_1):page82_i59@pure_quanta.q_res(chips)',
 P_PATH='@t6g_mb_lib.t6g(sch_1):page83_i59@pure_quanta.q_res(chips)',
 PATH='I59',
 DRAWING='@T6G_MB_LIB.T6G(SCH_1):PAGE82',
 WATTAGE='1/16W',
 TOLERANCE='1%',
 MATERIAL='CHIP',
 PHYS_PAGE='83',
 XY='(-7050,5475)',
 ROT='0',
 VER='1',
 PACK_TYPE='0402LF',
 LOCATION='R1187',
 CDS_LIB='pure_quanta',
 CDS_PART_NAME='Q_RES_0402LF-1K,1%,1/16W,CHIP,CS21002FB06',
 PART_NUMBER='CS21002FB06',
 VALUE='1K',
 PRIM_FILE='./archive_libs/logical/q_res/chips/chips.prt';

PART_NAME
 R1188 'Q_RES_0402LF-1K,1%,1/16W,CHIP,CS21002FB06':;

SECTION_NUMBER 1
 '@T6G_MB_LIB.T6G(SCH_1):PAGE82_I61@PURE_QUANTA.Q_RES(CHIPS)':
 C_PATH='@t6g_mb_lib.t6g(sch_1):page82_i61@pure_quanta.q_res(chips)',
 P_PATH='@t6g_mb_lib.t6g(sch_1):page83_i61@pure_quanta.q_res(chips)',
 PATH='I61',
 DRAWING='@T6G_MB_LIB.T6G(SCH_1):PAGE82',
 WATTAGE='1/16W',
 TOLERANCE='1%',
 MATERIAL='CHIP',
 PHYS_PAGE='83',
 XY='(-7050,5425)',
 ROT='0',
 VER='1',
 PACK_TYPE='0402LF',
 LOCATION='R1188',
 CDS_LIB='pure_quanta',
 CDS_PART_NAME='Q_RES_0402LF-1K,1%,1/16W,CHIP,CS21002FB06',
 PART_NUMBER='CS21002FB06',
 VALUE='1K',
 PRIM_FILE='./archive_libs/logical/q_res/chips/chips.prt';

PART_NAME
 R1189 'Q_RES_0402LF-1K,1%,1/16W,CHIP,CS21002FB06':;

SECTION_NUMBER 1
 '@T6G_MB_LIB.T6G(SCH_1):PAGE82_I57@PURE_QUANTA.Q_RES(CHIPS)':
 C_PATH='@t6g_mb_lib.t6g(sch_1):page82_i57@pure_quanta.q_res(chips)',
 P_PATH='@t6g_mb_lib.t6g(sch_1):page83_i57@pure_quanta.q_res(chips)',
 PATH='I57',
 DRAWING='@T6G_MB_LIB.T6G(SCH_1):PAGE82',
 WATTAGE='1/16W',
 TOLERANCE='1%',
 MATERIAL='CHIP',
 PHYS_PAGE='83',
 XY='(-7050,5375)',
 ROT='0',
 VER='1',
 PACK_TYPE='0402LF',
 LOCATION='R1189',
 CDS_LIB='pure_quanta',
 CDS_PART_NAME='Q_RES_0402LF-1K,1%,1/16W,CHIP,CS21002FB06',
 PART_NUMBER='CS21002FB06',
 VALUE='1K',
 PRIM_FILE='./archive_libs/logical/q_res/chips/chips.prt';

PART_NAME
 R1190 'Q_RES_0402LF-1K,1%,1/16W,CHIP,CS21002FB06':;

SECTION_NUMBER 1
 '@T6G_MB_LIB.T6G(SCH_1):PAGE82_I58@PURE_QUANTA.Q_RES(CHIPS)':
 C_PATH='@t6g_mb_lib.t6g(sch_1):page82_i58@pure_quanta.q_res(chips)',
 P_PATH='@t6g_mb_lib.t6g(sch_1):page83_i58@pure_quanta.q_res(chips)',
 PATH='I58',
 DRAWING='@T6G_MB_LIB.T6G(SCH_1):PAGE82',
 WATTAGE='1/16W',
 TOLERANCE='1%',
 MATERIAL='CHIP',
 PHYS_PAGE='83',
 XY='(-7050,5325)',
 ROT='0',
 VER='1',
 PACK_TYPE='0402LF',
 LOCATION='R1190',
 CDS_LIB='pure_quanta',
 CDS_PART_NAME='Q_RES_0402LF-1K,1%,1/16W,CHIP,CS21002FB06',
 PART_NUMBER='CS21002FB06',
 VALUE='1K',
 PRIM_FILE='./archive_libs/logical/q_res/chips/chips.prt';

PART_NAME
 R1191 'Q_RES_0402LF-0,5%,1/16W,CHIP,CS00002JB13':;

SECTION_NUMBER 1
 '@T6G_MB_LIB.T6G(SCH_1):PAGE343_I116@PURE_QUANTA.Q_RES(CHIPS)':
 C_PATH='@t6g_mb_lib.t6g(sch_1):page343_i116@pure_quanta.q_res(chips)',
 P_PATH='@t6g_mb_lib.t6g(sch_1):page140_i116@pure_quanta.q_res(chips)',
 PATH='I116',
 DRAWING='@T6G_MB_LIB.T6G(SCH_1):PAGE343',
 WATTAGE='1/16W',
 TOLERANCE='5%',
 MATERIAL='CHIP',
 PHYS_PAGE='140',
 XY='(425,4275)',
 ROT='0',
 VER='1',
 PACK_TYPE='0402LF',
 LOCATION='R1191',
 CDS_LIB='pure_quanta',
 CDS_PART_NAME='Q_RES_0402LF-0,5%,1/16W,CHIP,CS00002JB13',
 PART_NUMBER='CS00002JB13',
 VALUE='0',
 PRIM_FILE='./archive_libs/logical/q_res/chips/chips.prt';

PART_NAME
 R1192 'Q_RES_0402LF-1K,1%,1/16W,CHIP,CS21002FB06':;

SECTION_NUMBER 1
 '@T6G_MB_LIB.T6G(SCH_1):PAGE343_I118@PURE_QUANTA.Q_RES(CHIPS)':
 C_PATH='@t6g_mb_lib.t6g(sch_1):page343_i118@pure_quanta.q_res(chips)',
 P_PATH='@t6g_mb_lib.t6g(sch_1):page140_i118@pure_quanta.q_res(chips)',
 PATH='I118',
 DRAWING='@T6G_MB_LIB.T6G(SCH_1):PAGE343',
 WATTAGE='1/16W',
 TOLERANCE='1%',
 MATERIAL='CHIP',
 PHYS_PAGE='140',
 XY='(1750,4950)',
 ROT='2',
 VER='2',
 PACK_TYPE='0402LF',
 LOCATION='R1192',
 CDS_LIB='pure_quanta',
 CDS_PART_NAME='Q_RES_0402LF-1K,1%,1/16W,CHIP,CS21002FB06',
 PART_NUMBER='CS21002FB06',
 VALUE='1K',
 PRIM_FILE='./archive_libs/logical/q_res/chips/chips.prt';

PART_NAME
 R1193 'Q_RES_0402LF-0,5%,1/16W,CHIP,CS00002JB13':
 ROOM='NIC_P12V_MPS_MAM_BOM2';

SECTION_NUMBER 1
 '@T6G_MB_LIB.T6G(SCH_1):PAGE344_I76@PURE_QUANTA.Q_RES(CHIPS)':
 C_PATH='@t6g_mb_lib.t6g(sch_1):page344_i76@pure_quanta.q_res(chips)',
 P_PATH='@t6g_mb_lib.t6g(sch_1):page141_i76@pure_quanta.q_res(chips)',
 PATH='I76',
 DRAWING='@T6G_MB_LIB.T6G(SCH_1):PAGE344',
 WATTAGE='1/16W',
 TOLERANCE='5%',
 MATERIAL='CHIP',
 PHYS_PAGE='141',
 XY='(-3450,3500)',
 ROT='0',
 VER='1',
 PACK_TYPE='0402LF',
 LOCATION='R1193',
 CDS_LIB='pure_quanta',
 CDS_PART_NAME='Q_RES_0402LF-0,5%,1/16W,CHIP,CS00002JB13',
 ROOM='NIC_P12V_MPS_MAM_BOM2',
 PART_NUMBER='CS00002JB13',
 VALUE='0',
 PRIM_FILE='./archive_libs/logical/q_res/chips/chips.prt';

PART_NAME
 R1194 'Q_RES_0402LF-200,1%,1/16W,CHIP,CS12002FB06':;

SECTION_NUMBER 1
 '@T6G_MB_LIB.T6G(SCH_1):PAGE84_I46@PURE_QUANTA.Q_RES(CHIPS)':
 C_PATH='@t6g_mb_lib.t6g(sch_1):page84_i46@pure_quanta.q_res(chips)',
 P_PATH='@t6g_mb_lib.t6g(sch_1):page85_i46@pure_quanta.q_res(chips)',
 PATH='I46',
 DRAWING='@T6G_MB_LIB.T6G(SCH_1):PAGE84',
 WATTAGE='1/16W',
 TOLERANCE='1%',
 MATERIAL='CHIP',
 PHYS_PAGE='85',
 XY='(-3700,6050)',
 ROT='0',
 VER='1',
 PACK_TYPE='0402LF',
 LOCATION='R1194',
 CDS_LIB='pure_quanta',
 CDS_PART_NAME='Q_RES_0402LF-200,1%,1/16W,CHIP,CS12002FB06',
 PART_NUMBER='CS12002FB06',
 VALUE='200',
 PRIM_FILE='./archive_libs/logical/q_res/chips/chips.prt';

PART_NAME
 R1195 'Q_RES_0402LF-4.7K,5%,1/16W,EMPTY,CS24702JB10':;

SECTION_NUMBER 1
 '@T6G_MB_LIB.T6G(SCH_1):PAGE82_I36@PURE_QUANTA.Q_RES(CHIPS)':
 C_PATH='@t6g_mb_lib.t6g(sch_1):page82_i36@pure_quanta.q_res(chips)',
 P_PATH='@t6g_mb_lib.t6g(sch_1):page83_i36@pure_quanta.q_res(chips)',
 PATH='I36',
 DRAWING='@T6G_MB_LIB.T6G(SCH_1):PAGE82',
 WATTAGE='1/16W',
 TOLERANCE='5%',
 MATERIAL='EMPTY',
 PHYS_PAGE='83',
 XY='(-7050,3600)',
 ROT='0',
 VER='1',
 PACK_TYPE='0402LF',
 LOCATION='R1195',
 CDS_LIB='pure_quanta',
 CDS_PART_NAME='Q_RES_0402LF-4.7K,5%,1/16W,EMPTY,CS24702JB10',
 PART_NUMBER='CS24702JB10',
 VALUE='4.7K',
 PRIM_FILE='./archive_libs/logical/q_res/chips/chips.prt';

PART_NAME
 R1196 'Q_RES_0402LF-0,5%,1/16W,EMPTY,CS00002JB13':
 ROOM='NIC_P3V3_BOM2';

SECTION_NUMBER 1
 '@T6G_MB_LIB.T6G(SCH_1):PAGE344_I79@PURE_QUANTA.Q_RES(CHIPS)':
 C_PATH='@t6g_mb_lib.t6g(sch_1):page344_i79@pure_quanta.q_res(chips)',
 P_PATH='@t6g_mb_lib.t6g(sch_1):page141_i79@pure_quanta.q_res(chips)',
 PATH='I79',
 DRAWING='@T6G_MB_LIB.T6G(SCH_1):PAGE344',
 WATTAGE='1/16W',
 TOLERANCE='5%',
 MATERIAL='EMPTY',
 PHYS_PAGE='141',
 XY='(225,6850)',
 ROT='0',
 VER='1',
 PACK_TYPE='0402LF',
 LOCATION='R1196',
 CDS_LIB='pure_quanta',
 CDS_PART_NAME='Q_RES_0402LF-0,5%,1/16W,EMPTY,CS00002JB13',
 ROOM='NIC_P3V3_BOM2',
 PART_NUMBER='CS00002JB13',
 VALUE='0',
 PRIM_FILE='./archive_libs/logical/q_res/chips/chips.prt';

PART_NAME
 R1197 'Q_RES_0402LF-0,5%,1/16W,EMPTY,CS00002JB13':;

SECTION_NUMBER 1
 '@T6G_MB_LIB.T6G(SCH_1):PAGE130_I24@PURE_QUANTA.Q_RES(CHIPS)':
 C_PATH='@t6g_mb_lib.t6g(sch_1):page130_i24@pure_quanta.q_res(chips)',
 P_PATH='@t6g_mb_lib.t6g(sch_1):page153_i24@pure_quanta.q_res(chips)',
 PATH='I24',
 DRAWING='@T6G_MB_LIB.T6G(SCH_1):PAGE130',
 WATTAGE='1/16W',
 TOLERANCE='5%',
 MATERIAL='EMPTY',
 PHYS_PAGE='153',
 XY='(-4950,4650)',
 ROT='0',
 VER='1',
 PACK_TYPE='0402LF',
 LOCATION='R1197',
 CDS_LIB='pure_quanta',
 CDS_PART_NAME='Q_RES_0402LF-0,5%,1/16W,EMPTY,CS00002JB13',
 PART_NUMBER='CS00002JB13',
 VALUE='0',
 PRIM_FILE='./archive_libs/logical/q_res/chips/chips.prt';

PART_NAME
 R1198 'Q_RES_0201LF-0,5%,1/20W,CHIP,CS00001JE10':;

SECTION_NUMBER 1
 '@T6G_MB_LIB.T6G(SCH_1):PAGE376_I53@PURE_QUANTA.Q_RES(CHIPS)':
 C_PATH='@t6g_mb_lib.t6g(sch_1):page376_i53@pure_quanta.q_res(chips)',
 P_PATH='@t6g_mb_lib.t6g(sch_1):page186_i53@pure_quanta.q_res(chips)',
 PATH='I53',
 DRAWING='@T6G_MB_LIB.T6G(SCH_1):PAGE376',
 WATTAGE='1/20W',
 TOLERANCE='5%',
 MATERIAL='CHIP',
 PHYS_PAGE='186',
 XY='(-7525,2825)',
 ROT='0',
 VER='1',
 PACK_TYPE='0201LF',
 LOCATION='R1198',
 CDS_LIB='pure_quanta',
 CDS_PART_NAME='Q_RES_0201LF-0,5%,1/20W,CHIP,CS00001JE10',
 PART_NUMBER='CS00001JE10',
 VALUE='0',
 PRIM_FILE='./archive_libs/logical/q_res/chips/chips.prt';

PART_NAME
 R1199 'Q_RES_0201LF-0,5%,1/20W,CHIP,CS00001JE10':;

SECTION_NUMBER 1
 '@T6G_MB_LIB.T6G(SCH_1):PAGE376_I40@PURE_QUANTA.Q_RES(CHIPS)':
 C_PATH='@t6g_mb_lib.t6g(sch_1):page376_i40@pure_quanta.q_res(chips)',
 P_PATH='@t6g_mb_lib.t6g(sch_1):page186_i40@pure_quanta.q_res(chips)',
 PATH='I40',
 DRAWING='@T6G_MB_LIB.T6G(SCH_1):PAGE376',
 WATTAGE='1/20W',
 TOLERANCE='5%',
 MATERIAL='CHIP',
 PHYS_PAGE='186',
 XY='(-7475,4300)',
 ROT='0',
 VER='1',
 PACK_TYPE='0201LF',
 LOCATION='R1199',
 CDS_LIB='pure_quanta',
 CDS_PART_NAME='Q_RES_0201LF-0,5%,1/20W,CHIP,CS00001JE10',
 PART_NUMBER='CS00001JE10',
 VALUE='0',
 PRIM_FILE='./archive_libs/logical/q_res/chips/chips.prt';

PART_NAME
 R1200 'Q_RES_0201LF-0,5%,1/20W,CHIP,CS00001JE10':;

SECTION_NUMBER 1
 '@T6G_MB_LIB.T6G(SCH_1):PAGE376_I68@PURE_QUANTA.Q_RES(CHIPS)':
 C_PATH='@t6g_mb_lib.t6g(sch_1):page376_i68@pure_quanta.q_res(chips)',
 P_PATH='@t6g_mb_lib.t6g(sch_1):page186_i68@pure_quanta.q_res(chips)',
 PATH='I68',
 DRAWING='@T6G_MB_LIB.T6G(SCH_1):PAGE376',
 WATTAGE='1/20W',
 TOLERANCE='5%',
 MATERIAL='CHIP',
 PHYS_PAGE='186',
 XY='(-7475,1225)',
 ROT='0',
 VER='1',
 PACK_TYPE='0201LF',
 LOCATION='R1200',
 CDS_LIB='pure_quanta',
 CDS_PART_NAME='Q_RES_0201LF-0,5%,1/20W,CHIP,CS00001JE10',
 PART_NUMBER='CS00001JE10',
 VALUE='0',
 PRIM_FILE='./archive_libs/logical/q_res/chips/chips.prt';

PART_NAME
 R1201 'Q_RES_0201LF-0,5%,1/20W,CHIP,CS00001JE10':;

SECTION_NUMBER 1
 '@T6G_MB_LIB.T6G(SCH_1):PAGE376_I30@PURE_QUANTA.Q_RES(CHIPS)':
 C_PATH='@t6g_mb_lib.t6g(sch_1):page376_i30@pure_quanta.q_res(chips)',
 P_PATH='@t6g_mb_lib.t6g(sch_1):page186_i30@pure_quanta.q_res(chips)',
 PATH='I30',
 DRAWING='@T6G_MB_LIB.T6G(SCH_1):PAGE376',
 WATTAGE='1/20W',
 TOLERANCE='5%',
 MATERIAL='CHIP',
 PHYS_PAGE='186',
 XY='(-7400,5725)',
 ROT='0',
 VER='1',
 PACK_TYPE='0201LF',
 LOCATION='R1201',
 CDS_LIB='pure_quanta',
 CDS_PART_NAME='Q_RES_0201LF-0,5%,1/20W,CHIP,CS00001JE10',
 PART_NUMBER='CS00001JE10',
 VALUE='0',
 PRIM_FILE='./archive_libs/logical/q_res/chips/chips.prt';

PART_NAME
 R1202 'Q_RES_0402LF-0,5%,1/16W,CHIP,CS00002JB13':;

SECTION_NUMBER 1
 '@T6G_MB_LIB.T6G(SCH_1):PAGE80_I127@PURE_QUANTA.Q_RES(CHIPS)':
 C_PATH='@t6g_mb_lib.t6g(sch_1):page80_i127@pure_quanta.q_res(chips)',
 P_PATH='@t6g_mb_lib.t6g(sch_1):page81_i127@pure_quanta.q_res(chips)',
 PATH='I127',
 DRAWING='@T6G_MB_LIB.T6G(SCH_1):PAGE80',
 BOM_COST='MEM',
 WATTAGE='1/16W',
 TOLERANCE='5%',
 MATERIAL='CHIP',
 PHYS_PAGE='81',
 XY='(-3225,3875)',
 ROT='0',
 VER='1',
 PACK_TYPE='0402LF',
 LOCATION='R1202',
 CDS_LIB='pure_quanta',
 CDS_PART_NAME='Q_RES_0402LF-0,5%,1/16W,CHIP,CS00002JB13',
 PART_NUMBER='CS00002JB13',
 VALUE='0',
 PRIM_FILE='./archive_libs/logical/q_res/chips/chips.prt';

PART_NAME
 R1203 'Q_RES_0402LF-33,5%,1/16W,CHIP,CS03302JB10':;

SECTION_NUMBER 1
 '@T6G_MB_LIB.T6G(SCH_1):PAGE80_I178@PURE_QUANTA.Q_RES(CHIPS)':
 C_PATH='@t6g_mb_lib.t6g(sch_1):page80_i178@pure_quanta.q_res(chips)',
 P_PATH='@t6g_mb_lib.t6g(sch_1):page81_i178@pure_quanta.q_res(chips)',
 PATH='I178',
 DRAWING='@T6G_MB_LIB.T6G(SCH_1):PAGE80',
 BOM_COST='MEM',
 WATTAGE='1/16W',
 TOLERANCE='5%',
 MATERIAL='CHIP',
 PHYS_PAGE='81',
 XY='(-3225,5775)',
 ROT='0',
 VER='1',
 PACK_TYPE='0402LF',
 LOCATION='R1203',
 CDS_LIB='pure_quanta',
 CDS_PART_NAME='Q_RES_0402LF-33,5%,1/16W,CHIP,CS03302JB10',
 PART_NUMBER='CS03302JB10',
 VALUE='33',
 PRIM_FILE='./archive_libs/logical/q_res/chips/chips.prt';

PART_NAME
 R1204 'Q_RES_0402LF-0,5%,1/16W,CHIP,CS00002JB13':;

SECTION_NUMBER 1
 '@T6G_MB_LIB.T6G(SCH_1):PAGE27_I353@PURE_QUANTA.Q_RES(CHIPS)':
 C_PATH='@t6g_mb_lib.t6g(sch_1):page27_i353@pure_quanta.q_res(chips)',
 P_PATH='@t6g_mb_lib.t6g(sch_1):page27_i353@pure_quanta.q_res(chips)',
 PATH='I353',
 DRAWING='@T6G_MB_LIB.T6G(SCH_1):PAGE27',
 WATTAGE='1/16W',
 TOLERANCE='5%',
 MATERIAL='CHIP',
 PHYS_PAGE='27',
 XY='(-2500,1625)',
 ROT='0',
 VER='1',
 PACK_TYPE='0402LF',
 LOCATION='R1204',
 CDS_LIB='pure_quanta',
 CDS_PART_NAME='Q_RES_0402LF-0,5%,1/16W,CHIP,CS00002JB13',
 PART_NUMBER='CS00002JB13',
 VALUE='0',
 PRIM_FILE='./archive_libs/logical/q_res/chips/chips.prt';

PART_NAME
 R1205 'Q_RES_0402LF-0,5%,1/16W,CHIP,CS00002JB13':;

SECTION_NUMBER 1
 '@T6G_MB_LIB.T6G(SCH_1):PAGE28_I100@PURE_QUANTA.Q_RES(CHIPS)':
 C_PATH='@t6g_mb_lib.t6g(sch_1):page28_i100@pure_quanta.q_res(chips)',
 P_PATH='@t6g_mb_lib.t6g(sch_1):page28_i100@pure_quanta.q_res(chips)',
 PATH='I100',
 DRAWING='@T6G_MB_LIB.T6G(SCH_1):PAGE28',
 WATTAGE='1/16W',
 TOLERANCE='5%',
 MATERIAL='CHIP',
 PHYS_PAGE='28',
 XY='(-6375,10325)',
 ROT='2',
 VER='1',
 PACK_TYPE='0402LF',
 LOCATION='R1205',
 CDS_LIB='pure_quanta',
 CDS_PART_NAME='Q_RES_0402LF-0,5%,1/16W,CHIP,CS00002JB13',
 PART_NUMBER='CS00002JB13',
 VALUE='0',
 PRIM_FILE='./archive_libs/logical/q_res/chips/chips.prt';

PART_NAME
 R1206 'Q_RES_0201LF-0,5%,1/20W,CHIP,CS00001JE10':;

SECTION_NUMBER 1
 '@T6G_MB_LIB.T6G(SCH_1):PAGE376_I115@PURE_QUANTA.Q_RES(CHIPS)':
 C_PATH='@t6g_mb_lib.t6g(sch_1):page376_i115@pure_quanta.q_res(chips)',
 P_PATH='@t6g_mb_lib.t6g(sch_1):page186_i115@pure_quanta.q_res(chips)',
 PATH='I115',
 DRAWING='@T6G_MB_LIB.T6G(SCH_1):PAGE376',
 WATTAGE='1/20W',
 TOLERANCE='5%',
 MATERIAL='CHIP',
 PHYS_PAGE='186',
 XY='(-3150,2200)',
 ROT='0',
 VER='1',
 PACK_TYPE='0201LF',
 LOCATION='R1206',
 CDS_LIB='pure_quanta',
 CDS_PART_NAME='Q_RES_0201LF-0,5%,1/20W,CHIP,CS00001JE10',
 PART_NUMBER='CS00001JE10',
 VALUE='0',
 PRIM_FILE='./archive_libs/logical/q_res/chips/chips.prt';

PART_NAME
 R1207 'Q_RES_0402LF-470,1%,1/16W,CHIP,CS14702FB04':;

SECTION_NUMBER 1
 '@T6G_MB_LIB.T6G(SCH_1):PAGE143_I41@PURE_QUANTA.Q_RES(CHIPS)':
 C_PATH='@t6g_mb_lib.t6g(sch_1):page143_i41@pure_quanta.q_res(chips)',
 P_PATH='@t6g_mb_lib.t6g(sch_1):page166_i41@pure_quanta.q_res(chips)',
 PATH='I41',
 DRAWING='@T6G_MB_LIB.T6G(SCH_1):PAGE143',
 WATTAGE='1/16W',
 TOLERANCE='1%',
 MATERIAL='CHIP',
 PHYS_PAGE='166',
 XY='(-3275,550)',
 ROT='0',
 VER='1',
 PACK_TYPE='0402LF',
 LOCATION='R1207',
 CDS_LIB='pure_quanta',
 CDS_PART_NAME='Q_RES_0402LF-470,1%,1/16W,CHIP,CS14702FB04',
 PART_NUMBER='CS14702FB04',
 VALUE='470',
 PRIM_FILE='./archive_libs/logical/q_res/chips/chips.prt';

PART_NAME
 R1208 'Q_RES_0402LF-470,1%,1/16W,CHIP,CS14702FB04':;

SECTION_NUMBER 1
 '@T6G_MB_LIB.T6G(SCH_1):PAGE143_I42@PURE_QUANTA.Q_RES(CHIPS)':
 C_PATH='@t6g_mb_lib.t6g(sch_1):page143_i42@pure_quanta.q_res(chips)',
 P_PATH='@t6g_mb_lib.t6g(sch_1):page166_i42@pure_quanta.q_res(chips)',
 PATH='I42',
 DRAWING='@T6G_MB_LIB.T6G(SCH_1):PAGE143',
 WATTAGE='1/16W',
 TOLERANCE='1%',
 MATERIAL='CHIP',
 PHYS_PAGE='166',
 XY='(-3125,1975)',
 ROT='0',
 VER='1',
 PACK_TYPE='0402LF',
 LOCATION='R1208',
 CDS_LIB='pure_quanta',
 CDS_PART_NAME='Q_RES_0402LF-470,1%,1/16W,CHIP,CS14702FB04',
 PART_NUMBER='CS14702FB04',
 VALUE='470',
 PRIM_FILE='./archive_libs/logical/q_res/chips/chips.prt';

PART_NAME
 R1209 'Q_RES_0201LF-0,5%,1/20W,CHIP,CS00001JE10':;

SECTION_NUMBER 1
 '@T6G_MB_LIB.T6G(SCH_1):PAGE376_I123@PURE_QUANTA.Q_RES(CHIPS)':
 C_PATH='@t6g_mb_lib.t6g(sch_1):page376_i123@pure_quanta.q_res(chips)',
 P_PATH='@t6g_mb_lib.t6g(sch_1):page186_i123@pure_quanta.q_res(chips)',
 PATH='I123',
 DRAWING='@T6G_MB_LIB.T6G(SCH_1):PAGE376',
 WATTAGE='1/20W',
 TOLERANCE='5%',
 MATERIAL='CHIP',
 PHYS_PAGE='186',
 XY='(-3125,775)',
 ROT='0',
 VER='1',
 PACK_TYPE='0201LF',
 LOCATION='R1209',
 CDS_LIB='pure_quanta',
 CDS_PART_NAME='Q_RES_0201LF-0,5%,1/20W,CHIP,CS00001JE10',
 PART_NUMBER='CS00001JE10',
 VALUE='0',
 PRIM_FILE='./archive_libs/logical/q_res/chips/chips.prt';

PART_NAME
 R1210 'Q_RES_0201LF-0,5%,1/20W,CHIP,CS00001JE10':;

SECTION_NUMBER 1
 '@T6G_MB_LIB.T6G(SCH_1):PAGE376_I109@PURE_QUANTA.Q_RES(CHIPS)':
 C_PATH='@t6g_mb_lib.t6g(sch_1):page376_i109@pure_quanta.q_res(chips)',
 P_PATH='@t6g_mb_lib.t6g(sch_1):page186_i109@pure_quanta.q_res(chips)',
 PATH='I109',
 DRAWING='@T6G_MB_LIB.T6G(SCH_1):PAGE376',
 WATTAGE='1/20W',
 TOLERANCE='5%',
 MATERIAL='CHIP',
 PHYS_PAGE='186',
 XY='(-3100,3675)',
 ROT='0',
 VER='1',
 PACK_TYPE='0201LF',
 LOCATION='R1210',
 CDS_LIB='pure_quanta',
 CDS_PART_NAME='Q_RES_0201LF-0,5%,1/20W,CHIP,CS00001JE10',
 PART_NUMBER='CS00001JE10',
 VALUE='0',
 PRIM_FILE='./archive_libs/logical/q_res/chips/chips.prt';

PART_NAME
 R1211 'Q_RES_0201LF-0,5%,1/20W,CHIP,CS00001JE10':;

SECTION_NUMBER 1
 '@T6G_MB_LIB.T6G(SCH_1):PAGE376_I86@PURE_QUANTA.Q_RES(CHIPS)':
 C_PATH='@t6g_mb_lib.t6g(sch_1):page376_i86@pure_quanta.q_res(chips)',
 P_PATH='@t6g_mb_lib.t6g(sch_1):page186_i86@pure_quanta.q_res(chips)',
 PATH='I86',
 DRAWING='@T6G_MB_LIB.T6G(SCH_1):PAGE376',
 WATTAGE='1/20W',
 TOLERANCE='5%',
 MATERIAL='CHIP',
 PHYS_PAGE='186',
 XY='(-3025,5200)',
 ROT='0',
 VER='1',
 PACK_TYPE='0201LF',
 LOCATION='R1211',
 CDS_LIB='pure_quanta',
 CDS_PART_NAME='Q_RES_0201LF-0,5%,1/20W,CHIP,CS00001JE10',
 PART_NUMBER='CS00001JE10',
 VALUE='0',
 PRIM_FILE='./archive_libs/logical/q_res/chips/chips.prt';

PART_NAME
 R1212 'Q_RES_0201LF-1K,1%,1/20W,CHIP,CS21001FE07':;

SECTION_NUMBER 1
 '@T6G_MB_LIB.T6G(SCH_1):PAGE376_I54@PURE_QUANTA.Q_RES(CHIPS)':
 C_PATH='@t6g_mb_lib.t6g(sch_1):page376_i54@pure_quanta.q_res(chips)',
 P_PATH='@t6g_mb_lib.t6g(sch_1):page186_i54@pure_quanta.q_res(chips)',
 PATH='I54',
 DRAWING='@T6G_MB_LIB.T6G(SCH_1):PAGE376',
 WATTAGE='1/20W',
 TOLERANCE='1%',
 MATERIAL='CHIP',
 PHYS_PAGE='186',
 XY='(-7525,2875)',
 ROT='0',
 VER='1',
 PACK_TYPE='0201LF',
 LOCATION='R1212',
 CDS_LIB='pure_quanta',
 CDS_PART_NAME='Q_RES_0201LF-1K,1%,1/20W,CHIP,CS21001FE07',
 PART_NUMBER='CS21001FE07',
 VALUE='1K',
 PRIM_FILE='./archive_libs/logical/q_res/chips/chips.prt';

PART_NAME
 R1213 'Q_RES_0201LF-1K,1%,1/20W,CHIP,CS21001FE07':;

SECTION_NUMBER 1
 '@T6G_MB_LIB.T6G(SCH_1):PAGE376_I41@PURE_QUANTA.Q_RES(CHIPS)':
 C_PATH='@t6g_mb_lib.t6g(sch_1):page376_i41@pure_quanta.q_res(chips)',
 P_PATH='@t6g_mb_lib.t6g(sch_1):page186_i41@pure_quanta.q_res(chips)',
 PATH='I41',
 DRAWING='@T6G_MB_LIB.T6G(SCH_1):PAGE376',
 WATTAGE='1/20W',
 TOLERANCE='1%',
 MATERIAL='CHIP',
 PHYS_PAGE='186',
 XY='(-7475,4350)',
 ROT='0',
 VER='1',
 PACK_TYPE='0201LF',
 LOCATION='R1213',
 CDS_LIB='pure_quanta',
 CDS_PART_NAME='Q_RES_0201LF-1K,1%,1/20W,CHIP,CS21001FE07',
 PART_NUMBER='CS21001FE07',
 VALUE='1K',
 PRIM_FILE='./archive_libs/logical/q_res/chips/chips.prt';

PART_NAME
 R1214 'Q_RES_0201LF-1K,1%,1/20W,CHIP,CS21001FE07':;

SECTION_NUMBER 1
 '@T6G_MB_LIB.T6G(SCH_1):PAGE376_I69@PURE_QUANTA.Q_RES(CHIPS)':
 C_PATH='@t6g_mb_lib.t6g(sch_1):page376_i69@pure_quanta.q_res(chips)',
 P_PATH='@t6g_mb_lib.t6g(sch_1):page186_i69@pure_quanta.q_res(chips)',
 PATH='I69',
 DRAWING='@T6G_MB_LIB.T6G(SCH_1):PAGE376',
 WATTAGE='1/20W',
 TOLERANCE='1%',
 MATERIAL='CHIP',
 PHYS_PAGE='186',
 XY='(-7475,1275)',
 ROT='0',
 VER='1',
 PACK_TYPE='0201LF',
 LOCATION='R1214',
 CDS_LIB='pure_quanta',
 CDS_PART_NAME='Q_RES_0201LF-1K,1%,1/20W,CHIP,CS21001FE07',
 PART_NUMBER='CS21001FE07',
 VALUE='1K',
 PRIM_FILE='./archive_libs/logical/q_res/chips/chips.prt';

PART_NAME
 R1215 'Q_RES_0201LF-1K,1%,1/20W,CHIP,CS21001FE07':;

SECTION_NUMBER 1
 '@T6G_MB_LIB.T6G(SCH_1):PAGE376_I28@PURE_QUANTA.Q_RES(CHIPS)':
 C_PATH='@t6g_mb_lib.t6g(sch_1):page376_i28@pure_quanta.q_res(chips)',
 P_PATH='@t6g_mb_lib.t6g(sch_1):page186_i28@pure_quanta.q_res(chips)',
 PATH='I28',
 DRAWING='@T6G_MB_LIB.T6G(SCH_1):PAGE376',
 WATTAGE='1/20W',
 TOLERANCE='1%',
 MATERIAL='CHIP',
 PHYS_PAGE='186',
 XY='(-7400,5775)',
 ROT='0',
 VER='1',
 PACK_TYPE='0201LF',
 LOCATION='R1215',
 CDS_LIB='pure_quanta',
 CDS_PART_NAME='Q_RES_0201LF-1K,1%,1/20W,CHIP,CS21001FE07',
 PART_NUMBER='CS21001FE07',
 VALUE='1K',
 PRIM_FILE='./archive_libs/logical/q_res/chips/chips.prt';

PART_NAME
 R1216 'Q_RES_0201LF-1K,1%,1/20W,CHIP,CS21001FE07':;

SECTION_NUMBER 1
 '@T6G_MB_LIB.T6G(SCH_1):PAGE376_I116@PURE_QUANTA.Q_RES(CHIPS)':
 C_PATH='@t6g_mb_lib.t6g(sch_1):page376_i116@pure_quanta.q_res(chips)',
 P_PATH='@t6g_mb_lib.t6g(sch_1):page186_i116@pure_quanta.q_res(chips)',
 PATH='I116',
 DRAWING='@T6G_MB_LIB.T6G(SCH_1):PAGE376',
 WATTAGE='1/20W',
 TOLERANCE='1%',
 MATERIAL='CHIP',
 PHYS_PAGE='186',
 XY='(-3150,2250)',
 ROT='0',
 VER='1',
 PACK_TYPE='0201LF',
 LOCATION='R1216',
 CDS_LIB='pure_quanta',
 CDS_PART_NAME='Q_RES_0201LF-1K,1%,1/20W,CHIP,CS21001FE07',
 PART_NUMBER='CS21001FE07',
 VALUE='1K',
 PRIM_FILE='./archive_libs/logical/q_res/chips/chips.prt';

PART_NAME
 R1217 'Q_RES_0201LF-1K,1%,1/20W,CHIP,CS21001FE07':;

SECTION_NUMBER 1
 '@T6G_MB_LIB.T6G(SCH_1):PAGE376_I122@PURE_QUANTA.Q_RES(CHIPS)':
 C_PATH='@t6g_mb_lib.t6g(sch_1):page376_i122@pure_quanta.q_res(chips)',
 P_PATH='@t6g_mb_lib.t6g(sch_1):page186_i122@pure_quanta.q_res(chips)',
 PATH='I122',
 DRAWING='@T6G_MB_LIB.T6G(SCH_1):PAGE376',
 WATTAGE='1/20W',
 TOLERANCE='1%',
 MATERIAL='CHIP',
 PHYS_PAGE='186',
 XY='(-3125,825)',
 ROT='0',
 VER='1',
 PACK_TYPE='0201LF',
 LOCATION='R1217',
 CDS_LIB='pure_quanta',
 CDS_PART_NAME='Q_RES_0201LF-1K,1%,1/20W,CHIP,CS21001FE07',
 PART_NUMBER='CS21001FE07',
 VALUE='1K',
 PRIM_FILE='./archive_libs/logical/q_res/chips/chips.prt';

PART_NAME
 R1218 'Q_RES_0201LF-1K,1%,1/20W,CHIP,CS21001FE07':;

SECTION_NUMBER 1
 '@T6G_MB_LIB.T6G(SCH_1):PAGE376_I110@PURE_QUANTA.Q_RES(CHIPS)':
 C_PATH='@t6g_mb_lib.t6g(sch_1):page376_i110@pure_quanta.q_res(chips)',
 P_PATH='@t6g_mb_lib.t6g(sch_1):page186_i110@pure_quanta.q_res(chips)',
 PATH='I110',
 DRAWING='@T6G_MB_LIB.T6G(SCH_1):PAGE376',
 WATTAGE='1/20W',
 TOLERANCE='1%',
 MATERIAL='CHIP',
 PHYS_PAGE='186',
 XY='(-3100,3725)',
 ROT='0',
 VER='1',
 PACK_TYPE='0201LF',
 LOCATION='R1218',
 CDS_LIB='pure_quanta',
 CDS_PART_NAME='Q_RES_0201LF-1K,1%,1/20W,CHIP,CS21001FE07',
 PART_NUMBER='CS21001FE07',
 VALUE='1K',
 PRIM_FILE='./archive_libs/logical/q_res/chips/chips.prt';

PART_NAME
 R1219 'Q_RES_0201LF-1K,1%,1/20W,CHIP,CS21001FE07':;

SECTION_NUMBER 1
 '@T6G_MB_LIB.T6G(SCH_1):PAGE376_I87@PURE_QUANTA.Q_RES(CHIPS)':
 C_PATH='@t6g_mb_lib.t6g(sch_1):page376_i87@pure_quanta.q_res(chips)',
 P_PATH='@t6g_mb_lib.t6g(sch_1):page186_i87@pure_quanta.q_res(chips)',
 PATH='I87',
 DRAWING='@T6G_MB_LIB.T6G(SCH_1):PAGE376',
 WATTAGE='1/20W',
 TOLERANCE='1%',
 MATERIAL='CHIP',
 PHYS_PAGE='186',
 XY='(-3025,5250)',
 ROT='0',
 VER='1',
 PACK_TYPE='0201LF',
 LOCATION='R1219',
 CDS_LIB='pure_quanta',
 CDS_PART_NAME='Q_RES_0201LF-1K,1%,1/20W,CHIP,CS21001FE07',
 PART_NUMBER='CS21001FE07',
 VALUE='1K',
 PRIM_FILE='./archive_libs/logical/q_res/chips/chips.prt';

PART_NAME
 R1220 'Q_RES_0402LF-18K,1%,1/16W,CHIP,CS31802FB04':;

SECTION_NUMBER 1
 '@T6G_MB_LIB.T6G(SCH_1):PAGE263_I244@PURE_QUANTA.Q_RES(CHIPS)':
 C_PATH='@t6g_mb_lib.t6g(sch_1):page263_i244@pure_quanta.q_res(chips)',
 P_PATH='@t6g_mb_lib.t6g(sch_1):page258_i244@pure_quanta.q_res(chips)',
 PATH='I244',
 DRAWING='@T6G_MB_LIB.T6G(SCH_1):PAGE263',
 WATTAGE='1/16W',
 TOLERANCE='1%',
 MATERIAL='CHIP',
 PHYS_PAGE='258',
 XY='(-9025,1100)',
 ROT='0',
 VER='2',
 PACK_TYPE='0402LF',
 LOCATION='R1220',
 CDS_LIB='pure_quanta',
 CDS_PART_NAME='Q_RES_0402LF-18K,1%,1/16W,CHIP,CS31802FB04',
 PART_NUMBER='CS31802FB04',
 VALUE='18K',
 PRIM_FILE='./archive_libs/logical/q_res/chips/chips.prt';

PART_NAME
 R1221 'Q_RES_0402LF-18K,1%,1/16W,CHIP,CS31802FB04':;

SECTION_NUMBER 1
 '@T6G_MB_LIB.T6G(SCH_1):PAGE263_I243@PURE_QUANTA.Q_RES(CHIPS)':
 C_PATH='@t6g_mb_lib.t6g(sch_1):page263_i243@pure_quanta.q_res(chips)',
 P_PATH='@t6g_mb_lib.t6g(sch_1):page258_i243@pure_quanta.q_res(chips)',
 PATH='I243',
 DRAWING='@T6G_MB_LIB.T6G(SCH_1):PAGE263',
 WATTAGE='1/16W',
 TOLERANCE='1%',
 MATERIAL='CHIP',
 PHYS_PAGE='258',
 XY='(-8950,2700)',
 ROT='0',
 VER='2',
 PACK_TYPE='0402LF',
 LOCATION='R1221',
 CDS_LIB='pure_quanta',
 CDS_PART_NAME='Q_RES_0402LF-18K,1%,1/16W,CHIP,CS31802FB04',
 PART_NUMBER='CS31802FB04',
 VALUE='18K',
 PRIM_FILE='./archive_libs/logical/q_res/chips/chips.prt';

PART_NAME
 R1222 'Q_RES_0402LF-18K,1%,1/16W,CHIP,CS31802FB04':;

SECTION_NUMBER 1
 '@T6G_MB_LIB.T6G(SCH_1):PAGE263_I246@PURE_QUANTA.Q_RES(CHIPS)':
 C_PATH='@t6g_mb_lib.t6g(sch_1):page263_i246@pure_quanta.q_res(chips)',
 P_PATH='@t6g_mb_lib.t6g(sch_1):page258_i246@pure_quanta.q_res(chips)',
 PATH='I246',
 DRAWING='@T6G_MB_LIB.T6G(SCH_1):PAGE263',
 WATTAGE='1/16W',
 TOLERANCE='1%',
 MATERIAL='CHIP',
 PHYS_PAGE='258',
 XY='(-6850,2525)',
 ROT='0',
 VER='2',
 PACK_TYPE='0402LF',
 LOCATION='R1222',
 CDS_LIB='pure_quanta',
 CDS_PART_NAME='Q_RES_0402LF-18K,1%,1/16W,CHIP,CS31802FB04',
 PART_NUMBER='CS31802FB04',
 VALUE='18K',
 PRIM_FILE='./archive_libs/logical/q_res/chips/chips.prt';

PART_NAME
 R1223 'Q_RES_0402LF-18K,1%,1/16W,CHIP,CS31802FB04':;

SECTION_NUMBER 1
 '@T6G_MB_LIB.T6G(SCH_1):PAGE263_I245@PURE_QUANTA.Q_RES(CHIPS)':
 C_PATH='@t6g_mb_lib.t6g(sch_1):page263_i245@pure_quanta.q_res(chips)',
 P_PATH='@t6g_mb_lib.t6g(sch_1):page258_i245@pure_quanta.q_res(chips)',
 PATH='I245',
 DRAWING='@T6G_MB_LIB.T6G(SCH_1):PAGE263',
 WATTAGE='1/16W',
 TOLERANCE='1%',
 MATERIAL='CHIP',
 PHYS_PAGE='258',
 XY='(-6800,5500)',
 ROT='0',
 VER='2',
 PACK_TYPE='0402LF',
 LOCATION='R1223',
 CDS_LIB='pure_quanta',
 CDS_PART_NAME='Q_RES_0402LF-18K,1%,1/16W,CHIP,CS31802FB04',
 PART_NUMBER='CS31802FB04',
 VALUE='18K',
 PRIM_FILE='./archive_libs/logical/q_res/chips/chips.prt';

PART_NAME
 R1224 'Q_RES_0402LF-4.7K,1%,1/16W,CHIP,CS24702FB06':;

SECTION_NUMBER 1
 '@T6G_MB_LIB.T6G(SCH_1):PAGE263_I216@PURE_QUANTA.Q_RES(CHIPS)':
 C_PATH='@t6g_mb_lib.t6g(sch_1):page263_i216@pure_quanta.q_res(chips)',
 P_PATH='@t6g_mb_lib.t6g(sch_1):page258_i216@pure_quanta.q_res(chips)',
 PATH='I216',
 DRAWING='@T6G_MB_LIB.T6G(SCH_1):PAGE263',
 WATTAGE='1/16W',
 TOLERANCE='1%',
 MATERIAL='CHIP',
 PHYS_PAGE='258',
 XY='(-6750,3950)',
 ROT='0',
 VER='2',
 PACK_TYPE='0402LF',
 LOCATION='R1224',
 CDS_LIB='pure_quanta',
 CDS_PART_NAME='Q_RES_0402LF-4.7K,1%,1/16W,CHIP,CS24702FB06',
 PART_NUMBER='CS24702FB06',
 VALUE='4.7K',
 PRIM_FILE='./archive_libs/logical/q_res/chips/chips.prt';

PART_NAME
 R1225 'Q_RES_0402LF-18K,1%,1/16W,CHIP,CS31802FB04':;

SECTION_NUMBER 1
 '@T6G_MB_LIB.T6G(SCH_1):PAGE263_I247@PURE_QUANTA.Q_RES(CHIPS)':
 C_PATH='@t6g_mb_lib.t6g(sch_1):page263_i247@pure_quanta.q_res(chips)',
 P_PATH='@t6g_mb_lib.t6g(sch_1):page258_i247@pure_quanta.q_res(chips)',
 PATH='I247',
 DRAWING='@T6G_MB_LIB.T6G(SCH_1):PAGE263',
 WATTAGE='1/16W',
 TOLERANCE='1%',
 MATERIAL='CHIP',
 PHYS_PAGE='258',
 XY='(-6675,1000)',
 ROT='0',
 VER='2',
 PACK_TYPE='0402LF',
 LOCATION='R1225',
 CDS_LIB='pure_quanta',
 CDS_PART_NAME='Q_RES_0402LF-18K,1%,1/16W,CHIP,CS31802FB04',
 PART_NUMBER='CS31802FB04',
 VALUE='18K',
 PRIM_FILE='./archive_libs/logical/q_res/chips/chips.prt';

PART_NAME
 R1226 'Q_RES_0402LF-9.09K,1%,1/16W,CHIP,CS29092FB05':;

SECTION_NUMBER 1
 '@T6G_MB_LIB.T6G(SCH_1):PAGE263_I12@PURE_QUANTA.Q_RES(CHIPS)':
 C_PATH='@t6g_mb_lib.t6g(sch_1):page263_i12@pure_quanta.q_res(chips)',
 P_PATH='@t6g_mb_lib.t6g(sch_1):page258_i12@pure_quanta.q_res(chips)',
 PATH='I12',
 DRAWING='@T6G_MB_LIB.T6G(SCH_1):PAGE263',
 WATTAGE='1/16W',
 TOLERANCE='1%',
 MATERIAL='CHIP',
 PHYS_PAGE='258',
 XY='(-9025,5475)',
 ROT='0',
 VER='2',
 PACK_TYPE='0402LF',
 LOCATION='R1226',
 CDS_LIB='pure_quanta',
 CDS_PART_NAME='Q_RES_0402LF-9.09K,1%,1/16W,CHIP,CS29092FB05',
 PART_NUMBER='CS29092FB05',
 VALUE='9.09K',
 PRIM_FILE='./archive_libs/logical/q_res/chips/chips.prt';

PART_NAME
 R1227 'Q_RES_0402LF-0,5%,1/16W,EMPTY,CS00002JB13':
 ROOM='ADC_MAM_BOM2';

SECTION_NUMBER 1
 '@T6G_MB_LIB.T6G(SCH_1):PAGE263_I138@PURE_QUANTA.Q_RES(CHIPS)':
 C_PATH='@t6g_mb_lib.t6g(sch_1):page263_i138@pure_quanta.q_res(chips)',
 P_PATH='@t6g_mb_lib.t6g(sch_1):page258_i138@pure_quanta.q_res(chips)',
 PATH='I138',
 DRAWING='@T6G_MB_LIB.T6G(SCH_1):PAGE263',
 WATTAGE='1/16W',
 TOLERANCE='5%',
 MATERIAL='EMPTY',
 PHYS_PAGE='258',
 XY='(-2350,3550)',
 ROT='0',
 VER='1',
 PACK_TYPE='0402LF',
 LOCATION='R1227',
 CDS_LIB='pure_quanta',
 CDS_PART_NAME='Q_RES_0402LF-0,5%,1/16W,EMPTY,CS00002JB13',
 ROOM='ADC_MAM_BOM2',
 PART_NUMBER='CS00002JB13',
 VALUE='0',
 PRIM_FILE='./archive_libs/logical/q_res/chips/chips.prt';

PART_NAME
 R1228 'Q_RES_0402LF-0,5%,1/16W,EMPTY,CS00002JB13':
 ROOM='ADC_MAM_BOM2';

SECTION_NUMBER 1
 '@T6G_MB_LIB.T6G(SCH_1):PAGE263_I139@PURE_QUANTA.Q_RES(CHIPS)':
 C_PATH='@t6g_mb_lib.t6g(sch_1):page263_i139@pure_quanta.q_res(chips)',
 P_PATH='@t6g_mb_lib.t6g(sch_1):page258_i139@pure_quanta.q_res(chips)',
 PATH='I139',
 DRAWING='@T6G_MB_LIB.T6G(SCH_1):PAGE263',
 WATTAGE='1/16W',
 TOLERANCE='5%',
 MATERIAL='EMPTY',
 PHYS_PAGE='258',
 XY='(-2350,3500)',
 ROT='0',
 VER='1',
 PACK_TYPE='0402LF',
 LOCATION='R1228',
 CDS_LIB='pure_quanta',
 CDS_PART_NAME='Q_RES_0402LF-0,5%,1/16W,EMPTY,CS00002JB13',
 ROOM='ADC_MAM_BOM2',
 PART_NUMBER='CS00002JB13',
 VALUE='0',
 PRIM_FILE='./archive_libs/logical/q_res/chips/chips.prt';

PART_NAME
 R1229 'Q_RES_0402LF-18K,1%,1/16W,CHIP,CS31802FB04':;

SECTION_NUMBER 1
 '@T6G_MB_LIB.T6G(SCH_1):PAGE263_I242@PURE_QUANTA.Q_RES(CHIPS)':
 C_PATH='@t6g_mb_lib.t6g(sch_1):page263_i242@pure_quanta.q_res(chips)',
 P_PATH='@t6g_mb_lib.t6g(sch_1):page258_i242@pure_quanta.q_res(chips)',
 PATH='I242',
 DRAWING='@T6G_MB_LIB.T6G(SCH_1):PAGE263',
 WATTAGE='1/16W',
 TOLERANCE='1%',
 MATERIAL='CHIP',
 PHYS_PAGE='258',
 XY='(-8975,4225)',
 ROT='0',
 VER='2',
 PACK_TYPE='0402LF',
 LOCATION='R1229',
 CDS_LIB='pure_quanta',
 CDS_PART_NAME='Q_RES_0402LF-18K,1%,1/16W,CHIP,CS31802FB04',
 PART_NUMBER='CS31802FB04',
 VALUE='18K',
 PRIM_FILE='./archive_libs/logical/q_res/chips/chips.prt';

PART_NAME
 R1230 'Q_RES_0402LF-2K,1%,1/16W,CHIP,CS22002FB07':;

SECTION_NUMBER 1
 '@T6G_MB_LIB.T6G(SCH_1):PAGE263_I154@PURE_QUANTA.Q_RES(CHIPS)':
 C_PATH='@t6g_mb_lib.t6g(sch_1):page263_i154@pure_quanta.q_res(chips)',
 P_PATH='@t6g_mb_lib.t6g(sch_1):page258_i154@pure_quanta.q_res(chips)',
 PATH='I154',
 DRAWING='@T6G_MB_LIB.T6G(SCH_1):PAGE263',
 WATTAGE='1/16W',
 TOLERANCE='1%',
 MATERIAL='CHIP',
 PHYS_PAGE='258',
 XY='(-3425,5375)',
 ROT='0',
 VER='1',
 PACK_TYPE='0402LF',
 LOCATION='R1230',
 CDS_LIB='pure_quanta',
 CDS_PART_NAME='Q_RES_0402LF-2K,1%,1/16W,CHIP,CS22002FB07',
 PART_NUMBER='CS22002FB07',
 VALUE='2K',
 PRIM_FILE='./archive_libs/logical/q_res/chips/chips.prt';

PART_NAME
 R1231 'Q_RES_0402LF-5.11K,1%,1/16W,CHIP,CS25112FB04':;

SECTION_NUMBER 1
 '@T6G_MB_LIB.T6G(SCH_1):PAGE263_I191@PURE_QUANTA.Q_RES(CHIPS)':
 C_PATH='@t6g_mb_lib.t6g(sch_1):page263_i191@pure_quanta.q_res(chips)',
 P_PATH='@t6g_mb_lib.t6g(sch_1):page258_i191@pure_quanta.q_res(chips)',
 PATH='I191',
 DRAWING='@T6G_MB_LIB.T6G(SCH_1):PAGE263',
 WATTAGE='1/16W',
 TOLERANCE='1%',
 MATERIAL='CHIP',
 PHYS_PAGE='258',
 XY='(-9025,1625)',
 ROT='0',
 VER='2',
 PACK_TYPE='0402LF',
 LOCATION='R1231',
 CDS_LIB='pure_quanta',
 CDS_PART_NAME='Q_RES_0402LF-5.11K,1%,1/16W,CHIP,CS25112FB04',
 PART_NUMBER='CS25112FB04',
 VALUE='5.11K',
 PRIM_FILE='./archive_libs/logical/q_res/chips/chips.prt';

PART_NAME
 R1232 'Q_RES_0402LF-5.11K,1%,1/16W,CHIP,CS25112FB04':;

SECTION_NUMBER 1
 '@T6G_MB_LIB.T6G(SCH_1):PAGE263_I179@PURE_QUANTA.Q_RES(CHIPS)':
 C_PATH='@t6g_mb_lib.t6g(sch_1):page263_i179@pure_quanta.q_res(chips)',
 P_PATH='@t6g_mb_lib.t6g(sch_1):page258_i179@pure_quanta.q_res(chips)',
 PATH='I179',
 DRAWING='@T6G_MB_LIB.T6G(SCH_1):PAGE263',
 WATTAGE='1/16W',
 TOLERANCE='1%',
 MATERIAL='CHIP',
 PHYS_PAGE='258',
 XY='(-8950,3225)',
 ROT='0',
 VER='2',
 PACK_TYPE='0402LF',
 LOCATION='R1232',
 CDS_LIB='pure_quanta',
 CDS_PART_NAME='Q_RES_0402LF-5.11K,1%,1/16W,CHIP,CS25112FB04',
 PART_NUMBER='CS25112FB04',
 VALUE='5.11K',
 PRIM_FILE='./archive_libs/logical/q_res/chips/chips.prt';

PART_NAME
 R1233 'Q_RES_0402LF-5.11K,1%,1/16W,CHIP,CS25112FB04':;

SECTION_NUMBER 1
 '@T6G_MB_LIB.T6G(SCH_1):PAGE263_I227@PURE_QUANTA.Q_RES(CHIPS)':
 C_PATH='@t6g_mb_lib.t6g(sch_1):page263_i227@pure_quanta.q_res(chips)',
 P_PATH='@t6g_mb_lib.t6g(sch_1):page258_i227@pure_quanta.q_res(chips)',
 PATH='I227',
 DRAWING='@T6G_MB_LIB.T6G(SCH_1):PAGE263',
 WATTAGE='1/16W',
 TOLERANCE='1%',
 MATERIAL='CHIP',
 PHYS_PAGE='258',
 XY='(-6850,3050)',
 ROT='0',
 VER='2',
 PACK_TYPE='0402LF',
 LOCATION='R1233',
 CDS_LIB='pure_quanta',
 CDS_PART_NAME='Q_RES_0402LF-5.11K,1%,1/16W,CHIP,CS25112FB04',
 PART_NUMBER='CS25112FB04',
 VALUE='5.11K',
 PRIM_FILE='./archive_libs/logical/q_res/chips/chips.prt';

PART_NAME
 R1234 'Q_RES_0402LF-5.11K,1%,1/16W,CHIP,CS25112FB04':;

SECTION_NUMBER 1
 '@T6G_MB_LIB.T6G(SCH_1):PAGE263_I194@PURE_QUANTA.Q_RES(CHIPS)':
 C_PATH='@t6g_mb_lib.t6g(sch_1):page263_i194@pure_quanta.q_res(chips)',
 P_PATH='@t6g_mb_lib.t6g(sch_1):page258_i194@pure_quanta.q_res(chips)',
 PATH='I194',
 DRAWING='@T6G_MB_LIB.T6G(SCH_1):PAGE263',
 WATTAGE='1/16W',
 TOLERANCE='1%',
 MATERIAL='CHIP',
 PHYS_PAGE='258',
 XY='(-6800,6000)',
 ROT='0',
 VER='2',
 PACK_TYPE='0402LF',
 LOCATION='R1234',
 CDS_LIB='pure_quanta',
 CDS_PART_NAME='Q_RES_0402LF-5.11K,1%,1/16W,CHIP,CS25112FB04',
 PART_NUMBER='CS25112FB04',
 VALUE='5.11K',
 PRIM_FILE='./archive_libs/logical/q_res/chips/chips.prt';

PART_NAME
 R1235 'Q_RES_0402LF-5.11K,1%,1/16W,CHIP,CS25112FB04':;

SECTION_NUMBER 1
 '@T6G_MB_LIB.T6G(SCH_1):PAGE263_I215@PURE_QUANTA.Q_RES(CHIPS)':
 C_PATH='@t6g_mb_lib.t6g(sch_1):page263_i215@pure_quanta.q_res(chips)',
 P_PATH='@t6g_mb_lib.t6g(sch_1):page258_i215@pure_quanta.q_res(chips)',
 PATH='I215',
 DRAWING='@T6G_MB_LIB.T6G(SCH_1):PAGE263',
 WATTAGE='1/16W',
 TOLERANCE='1%',
 MATERIAL='CHIP',
 PHYS_PAGE='258',
 XY='(-6750,4475)',
 ROT='0',
 VER='2',
 PACK_TYPE='0402LF',
 LOCATION='R1235',
 CDS_LIB='pure_quanta',
 CDS_PART_NAME='Q_RES_0402LF-5.11K,1%,1/16W,CHIP,CS25112FB04',
 PART_NUMBER='CS25112FB04',
 VALUE='5.11K',
 PRIM_FILE='./archive_libs/logical/q_res/chips/chips.prt';

PART_NAME
 R1236 'Q_RES_0402LF-5.11K,1%,1/16W,CHIP,CS25112FB04':;

SECTION_NUMBER 1
 '@T6G_MB_LIB.T6G(SCH_1):PAGE263_I230@PURE_QUANTA.Q_RES(CHIPS)':
 C_PATH='@t6g_mb_lib.t6g(sch_1):page263_i230@pure_quanta.q_res(chips)',
 P_PATH='@t6g_mb_lib.t6g(sch_1):page258_i230@pure_quanta.q_res(chips)',
 PATH='I230',
 DRAWING='@T6G_MB_LIB.T6G(SCH_1):PAGE263',
 WATTAGE='1/16W',
 TOLERANCE='1%',
 MATERIAL='CHIP',
 PHYS_PAGE='258',
 XY='(-6675,1525)',
 ROT='0',
 VER='2',
 PACK_TYPE='0402LF',
 LOCATION='R1236',
 CDS_LIB='pure_quanta',
 CDS_PART_NAME='Q_RES_0402LF-5.11K,1%,1/16W,CHIP,CS25112FB04',
 PART_NUMBER='CS25112FB04',
 VALUE='5.11K',
 PRIM_FILE='./archive_libs/logical/q_res/chips/chips.prt';

PART_NAME
 R1237 'Q_RES_0402LF-5.11K,1%,1/16W,CHIP,CS25112FB04':;

SECTION_NUMBER 1
 '@T6G_MB_LIB.T6G(SCH_1):PAGE263_I19@PURE_QUANTA.Q_RES(CHIPS)':
 C_PATH='@t6g_mb_lib.t6g(sch_1):page263_i19@pure_quanta.q_res(chips)',
 P_PATH='@t6g_mb_lib.t6g(sch_1):page258_i19@pure_quanta.q_res(chips)',
 PATH='I19',
 DRAWING='@T6G_MB_LIB.T6G(SCH_1):PAGE263',
 WATTAGE='1/16W',
 TOLERANCE='1%',
 MATERIAL='CHIP',
 PHYS_PAGE='258',
 XY='(-8975,4700)',
 ROT='0',
 VER='2',
 PACK_TYPE='0402LF',
 LOCATION='R1237',
 CDS_LIB='pure_quanta',
 CDS_PART_NAME='Q_RES_0402LF-5.11K,1%,1/16W,CHIP,CS25112FB04',
 PART_NUMBER='CS25112FB04',
 VALUE='5.11K',
 PRIM_FILE='./archive_libs/logical/q_res/chips/chips.prt';

PART_NAME
 R1238 'Q_RES_0402LF-18K,1%,1/16W,CHIP,CS31802FB04':;

SECTION_NUMBER 1
 '@T6G_MB_LIB.T6G(SCH_1):PAGE263_I13@PURE_QUANTA.Q_RES(CHIPS)':
 C_PATH='@t6g_mb_lib.t6g(sch_1):page263_i13@pure_quanta.q_res(chips)',
 P_PATH='@t6g_mb_lib.t6g(sch_1):page258_i13@pure_quanta.q_res(chips)',
 PATH='I13',
 DRAWING='@T6G_MB_LIB.T6G(SCH_1):PAGE263',
 WATTAGE='1/16W',
 TOLERANCE='1%',
 MATERIAL='CHIP',
 PHYS_PAGE='258',
 XY='(-9025,6025)',
 ROT='0',
 VER='2',
 PACK_TYPE='0402LF',
 LOCATION='R1238',
 CDS_LIB='pure_quanta',
 CDS_PART_NAME='Q_RES_0402LF-18K,1%,1/16W,CHIP,CS31802FB04',
 PART_NUMBER='CS31802FB04',
 VALUE='18K',
 PRIM_FILE='./archive_libs/logical/q_res/chips/chips.prt';

PART_NAME
 R1239 'Q_RES_0402LF-1K,1%,1/16W,EMPTY,CS21002FB06':
 ROOM='ADC_TI_BOM1';

SECTION_NUMBER 1
 '@T6G_MB_LIB.T6G(SCH_1):PAGE263_I59@PURE_QUANTA.Q_RES(CHIPS)':
 C_PATH='@t6g_mb_lib.t6g(sch_1):page263_i59@pure_quanta.q_res(chips)',
 P_PATH='@t6g_mb_lib.t6g(sch_1):page258_i59@pure_quanta.q_res(chips)',
 PATH='I59',
 DRAWING='@T6G_MB_LIB.T6G(SCH_1):PAGE263',
 WATTAGE='1/16W',
 TOLERANCE='1%',
 MATERIAL='EMPTY',
 PHYS_PAGE='258',
 XY='(-4500,1175)',
 ROT='0',
 VER='2',
 PACK_TYPE='0402LF',
 LOCATION='R1239',
 CDS_LIB='pure_quanta',
 CDS_PART_NAME='Q_RES_0402LF-1K,1%,1/16W,EMPTY,CS21002FB06',
 ROOM='ADC_TI_BOM1',
 PART_NUMBER='CS21002FB06',
 VALUE='1K',
 PRIM_FILE='./archive_libs/logical/q_res/chips/chips.prt';

PART_NAME
 R1240 'Q_RES_0402LF-1K,1%,1/16W,CHIP,CS21002FB06':
 ROOM='ADC_TI_BOM1';

SECTION_NUMBER 1
 '@T6G_MB_LIB.T6G(SCH_1):PAGE263_I57@PURE_QUANTA.Q_RES(CHIPS)':
 C_PATH='@t6g_mb_lib.t6g(sch_1):page263_i57@pure_quanta.q_res(chips)',
 P_PATH='@t6g_mb_lib.t6g(sch_1):page258_i57@pure_quanta.q_res(chips)',
 PATH='I57',
 DRAWING='@T6G_MB_LIB.T6G(SCH_1):PAGE263',
 WATTAGE='1/16W',
 TOLERANCE='1%',
 MATERIAL='CHIP',
 PHYS_PAGE='258',
 XY='(-4500,575)',
 ROT='0',
 VER='2',
 PACK_TYPE='0402LF',
 LOCATION='R1240',
 CDS_LIB='pure_quanta',
 CDS_PART_NAME='Q_RES_0402LF-1K,1%,1/16W,CHIP,CS21002FB06',
 ROOM='ADC_TI_BOM1',
 PART_NUMBER='CS21002FB06',
 VALUE='1K',
 PRIM_FILE='./archive_libs/logical/q_res/chips/chips.prt';

PART_NAME
 R1241 'Q_RES_0402LF-1K,1%,1/16W,EMPTY,CS21002FB06':
 ROOM='ADC_TI_BOM1';

SECTION_NUMBER 1
 '@T6G_MB_LIB.T6G(SCH_1):PAGE263_I60@PURE_QUANTA.Q_RES(CHIPS)':
 C_PATH='@t6g_mb_lib.t6g(sch_1):page263_i60@pure_quanta.q_res(chips)',
 P_PATH='@t6g_mb_lib.t6g(sch_1):page258_i60@pure_quanta.q_res(chips)',
 PATH='I60',
 DRAWING='@T6G_MB_LIB.T6G(SCH_1):PAGE263',
 WATTAGE='1/16W',
 TOLERANCE='1%',
 MATERIAL='EMPTY',
 PHYS_PAGE='258',
 XY='(-4250,1175)',
 ROT='0',
 VER='2',
 PACK_TYPE='0402LF',
 LOCATION='R1241',
 CDS_LIB='pure_quanta',
 CDS_PART_NAME='Q_RES_0402LF-1K,1%,1/16W,EMPTY,CS21002FB06',
 ROOM='ADC_TI_BOM1',
 PART_NUMBER='CS21002FB06',
 VALUE='1K',
 PRIM_FILE='./archive_libs/logical/q_res/chips/chips.prt';

PART_NAME
 R1242 'Q_RES_0402LF-1K,1%,1/16W,CHIP,CS21002FB06':
 ROOM='ADC_TI_BOM1';

SECTION_NUMBER 1
 '@T6G_MB_LIB.T6G(SCH_1):PAGE263_I58@PURE_QUANTA.Q_RES(CHIPS)':
 C_PATH='@t6g_mb_lib.t6g(sch_1):page263_i58@pure_quanta.q_res(chips)',
 P_PATH='@t6g_mb_lib.t6g(sch_1):page258_i58@pure_quanta.q_res(chips)',
 PATH='I58',
 DRAWING='@T6G_MB_LIB.T6G(SCH_1):PAGE263',
 WATTAGE='1/16W',
 TOLERANCE='1%',
 MATERIAL='CHIP',
 PHYS_PAGE='258',
 XY='(-4250,575)',
 ROT='0',
 VER='2',
 PACK_TYPE='0402LF',
 LOCATION='R1242',
 CDS_LIB='pure_quanta',
 CDS_PART_NAME='Q_RES_0402LF-1K,1%,1/16W,CHIP,CS21002FB06',
 ROOM='ADC_TI_BOM1',
 PART_NUMBER='CS21002FB06',
 VALUE='1K',
 PRIM_FILE='./archive_libs/logical/q_res/chips/chips.prt';

PART_NAME
 R1243 'Q_RES_0402LF-0,5%,1/16W,CHIP,CS00002JB13':
 ROOM='ADC_TI_BOM1';

SECTION_NUMBER 1
 '@T6G_MB_LIB.T6G(SCH_1):PAGE263_I141@PURE_QUANTA.Q_RES(CHIPS)':
 C_PATH='@t6g_mb_lib.t6g(sch_1):page263_i141@pure_quanta.q_res(chips)',
 P_PATH='@t6g_mb_lib.t6g(sch_1):page258_i141@pure_quanta.q_res(chips)',
 PATH='I141',
 DRAWING='@T6G_MB_LIB.T6G(SCH_1):PAGE263',
 WATTAGE='1/16W',
 TOLERANCE='5%',
 MATERIAL='CHIP',
 PHYS_PAGE='258',
 XY='(-1500,900)',
 ROT='0',
 VER='1',
 PACK_TYPE='0402LF',
 LOCATION='R1243',
 CDS_LIB='pure_quanta',
 CDS_PART_NAME='Q_RES_0402LF-0,5%,1/16W,CHIP,CS00002JB13',
 ROOM='ADC_TI_BOM1',
 PART_NUMBER='CS00002JB13',
 VALUE='0',
 PRIM_FILE='./archive_libs/logical/q_res/chips/chips.prt';

PART_NAME
 R1244 'Q_RES_0402LF-0,5%,1/16W,CHIP,CS00002JB13':
 ROOM='ADC_TI_BOM1';

SECTION_NUMBER 1
 '@T6G_MB_LIB.T6G(SCH_1):PAGE263_I140@PURE_QUANTA.Q_RES(CHIPS)':
 C_PATH='@t6g_mb_lib.t6g(sch_1):page263_i140@pure_quanta.q_res(chips)',
 P_PATH='@t6g_mb_lib.t6g(sch_1):page258_i140@pure_quanta.q_res(chips)',
 PATH='I140',
 DRAWING='@T6G_MB_LIB.T6G(SCH_1):PAGE263',
 WATTAGE='1/16W',
 TOLERANCE='5%',
 MATERIAL='CHIP',
 PHYS_PAGE='258',
 XY='(-1500,850)',
 ROT='0',
 VER='1',
 PACK_TYPE='0402LF',
 LOCATION='R1244',
 CDS_LIB='pure_quanta',
 CDS_PART_NAME='Q_RES_0402LF-0,5%,1/16W,CHIP,CS00002JB13',
 ROOM='ADC_TI_BOM1',
 PART_NUMBER='CS00002JB13',
 VALUE='0',
 PRIM_FILE='./archive_libs/logical/q_res/chips/chips.prt';

PART_NAME
 R1245 'Q_RES_0402LF-0,5%,1/16W,EMPTY,CS00002JB13':
 ROOM='ADC_MAM_BOM2';

SECTION_NUMBER 1
 '@T6G_MB_LIB.T6G(SCH_1):PAGE263_I177@PURE_QUANTA.Q_RES(CHIPS)':
 C_PATH='@t6g_mb_lib.t6g(sch_1):page263_i177@pure_quanta.q_res(chips)',
 P_PATH='@t6g_mb_lib.t6g(sch_1):page258_i177@pure_quanta.q_res(chips)',
 PATH='I177',
 DRAWING='@T6G_MB_LIB.T6G(SCH_1):PAGE263',
 WATTAGE='1/16W',
 TOLERANCE='5%',
 MATERIAL='EMPTY',
 PHYS_PAGE='258',
 XY='(-8250,2975)',
 ROT='0',
 VER='1',
 PACK_TYPE='0402LF',
 LOCATION='R1245',
 CDS_LIB='pure_quanta',
 CDS_PART_NAME='Q_RES_0402LF-0,5%,1/16W,EMPTY,CS00002JB13',
 ROOM='ADC_MAM_BOM2',
 PART_NUMBER='CS00002JB13',
 VALUE='0',
 PRIM_FILE='./archive_libs/logical/q_res/chips/chips.prt';

PART_NAME
 R1246 'Q_RES_0402LF-0,5%,1/16W,EMPTY,CS00002JB13':
 ROOM='ADC_MAM_BOM2';

SECTION_NUMBER 1
 '@T6G_MB_LIB.T6G(SCH_1):PAGE263_I189@PURE_QUANTA.Q_RES(CHIPS)':
 C_PATH='@t6g_mb_lib.t6g(sch_1):page263_i189@pure_quanta.q_res(chips)',
 P_PATH='@t6g_mb_lib.t6g(sch_1):page258_i189@pure_quanta.q_res(chips)',
 PATH='I189',
 DRAWING='@T6G_MB_LIB.T6G(SCH_1):PAGE263',
 WATTAGE='1/16W',
 TOLERANCE='5%',
 MATERIAL='EMPTY',
 PHYS_PAGE='258',
 XY='(-8200,1375)',
 ROT='0',
 VER='1',
 PACK_TYPE='0402LF',
 LOCATION='R1246',
 CDS_LIB='pure_quanta',
 CDS_PART_NAME='Q_RES_0402LF-0,5%,1/16W,EMPTY,CS00002JB13',
 ROOM='ADC_MAM_BOM2',
 PART_NUMBER='CS00002JB13',
 VALUE='0',
 PRIM_FILE='./archive_libs/logical/q_res/chips/chips.prt';

PART_NAME
 R1247 'Q_RES_0402LF-0,5%,1/16W,EMPTY,CS00002JB13':
 ROOM='ADC_MAM_BOM2';

SECTION_NUMBER 1
 '@T6G_MB_LIB.T6G(SCH_1):PAGE263_I225@PURE_QUANTA.Q_RES(CHIPS)':
 C_PATH='@t6g_mb_lib.t6g(sch_1):page263_i225@pure_quanta.q_res(chips)',
 P_PATH='@t6g_mb_lib.t6g(sch_1):page258_i225@pure_quanta.q_res(chips)',
 PATH='I225',
 DRAWING='@T6G_MB_LIB.T6G(SCH_1):PAGE263',
 WATTAGE='1/16W',
 TOLERANCE='5%',
 MATERIAL='EMPTY',
 PHYS_PAGE='258',
 XY='(-6150,2800)',
 ROT='0',
 VER='1',
 PACK_TYPE='0402LF',
 LOCATION='R1247',
 CDS_LIB='pure_quanta',
 CDS_PART_NAME='Q_RES_0402LF-0,5%,1/16W,EMPTY,CS00002JB13',
 ROOM='ADC_MAM_BOM2',
 PART_NUMBER='CS00002JB13',
 VALUE='0',
 PRIM_FILE='./archive_libs/logical/q_res/chips/chips.prt';

PART_NAME
 R1248 'Q_RES_0402LF-0,5%,1/16W,EMPTY,CS00002JB13':
 ROOM='ADC_MAM_BOM2';

SECTION_NUMBER 1
 '@T6G_MB_LIB.T6G(SCH_1):PAGE263_I213@PURE_QUANTA.Q_RES(CHIPS)':
 C_PATH='@t6g_mb_lib.t6g(sch_1):page263_i213@pure_quanta.q_res(chips)',
 P_PATH='@t6g_mb_lib.t6g(sch_1):page258_i213@pure_quanta.q_res(chips)',
 PATH='I213',
 DRAWING='@T6G_MB_LIB.T6G(SCH_1):PAGE263',
 WATTAGE='1/16W',
 TOLERANCE='5%',
 MATERIAL='EMPTY',
 PHYS_PAGE='258',
 XY='(-6050,4225)',
 ROT='0',
 VER='1',
 PACK_TYPE='0402LF',
 LOCATION='R1248',
 CDS_LIB='pure_quanta',
 CDS_PART_NAME='Q_RES_0402LF-0,5%,1/16W,EMPTY,CS00002JB13',
 ROOM='ADC_MAM_BOM2',
 PART_NUMBER='CS00002JB13',
 VALUE='0',
 PRIM_FILE='./archive_libs/logical/q_res/chips/chips.prt';

PART_NAME
 R1249 'Q_RES_0402LF-0,5%,1/16W,EMPTY,CS00002JB13':
 ROOM='ADC_MAM_BOM2';

SECTION_NUMBER 1
 '@T6G_MB_LIB.T6G(SCH_1):PAGE263_I231@PURE_QUANTA.Q_RES(CHIPS)':
 C_PATH='@t6g_mb_lib.t6g(sch_1):page263_i231@pure_quanta.q_res(chips)',
 P_PATH='@t6g_mb_lib.t6g(sch_1):page258_i231@pure_quanta.q_res(chips)',
 PATH='I231',
 DRAWING='@T6G_MB_LIB.T6G(SCH_1):PAGE263',
 WATTAGE='1/16W',
 TOLERANCE='5%',
 MATERIAL='EMPTY',
 PHYS_PAGE='258',
 XY='(-5975,1275)',
 ROT='0',
 VER='1',
 PACK_TYPE='0402LF',
 LOCATION='R1249',
 CDS_LIB='pure_quanta',
 CDS_PART_NAME='Q_RES_0402LF-0,5%,1/16W,EMPTY,CS00002JB13',
 ROOM='ADC_MAM_BOM2',
 PART_NUMBER='CS00002JB13',
 VALUE='0',
 PRIM_FILE='./archive_libs/logical/q_res/chips/chips.prt';

PART_NAME
 R1250 'Q_RES_0402LF-0,5%,1/16W,EMPTY,CS00002JB13':
 ROOM='ADC_MAM_BOM2';

SECTION_NUMBER 1
 '@T6G_MB_LIB.T6G(SCH_1):PAGE263_I202@PURE_QUANTA.Q_RES(CHIPS)':
 C_PATH='@t6g_mb_lib.t6g(sch_1):page263_i202@pure_quanta.q_res(chips)',
 P_PATH='@t6g_mb_lib.t6g(sch_1):page258_i202@pure_quanta.q_res(chips)',
 PATH='I202',
 DRAWING='@T6G_MB_LIB.T6G(SCH_1):PAGE263',
 WATTAGE='1/16W',
 TOLERANCE='5%',
 MATERIAL='EMPTY',
 PHYS_PAGE='258',
 XY='(-5925,5750)',
 ROT='0',
 VER='1',
 PACK_TYPE='0402LF',
 LOCATION='R1250',
 CDS_LIB='pure_quanta',
 CDS_PART_NAME='Q_RES_0402LF-0,5%,1/16W,EMPTY,CS00002JB13',
 ROOM='ADC_MAM_BOM2',
 PART_NUMBER='CS00002JB13',
 VALUE='0',
 PRIM_FILE='./archive_libs/logical/q_res/chips/chips.prt';

PART_NAME
 R1251 'Q_RES_0402LF-0,5%,1/16W,CHIP,CS00002JB13':
 ROOM='ADC_TI_BOM1';

SECTION_NUMBER 1
 '@T6G_MB_LIB.T6G(SCH_1):PAGE263_I178@PURE_QUANTA.Q_RES(CHIPS)':
 C_PATH='@t6g_mb_lib.t6g(sch_1):page263_i178@pure_quanta.q_res(chips)',
 P_PATH='@t6g_mb_lib.t6g(sch_1):page258_i178@pure_quanta.q_res(chips)',
 PATH='I178',
 DRAWING='@T6G_MB_LIB.T6G(SCH_1):PAGE263',
 WATTAGE='1/16W',
 TOLERANCE='5%',
 MATERIAL='CHIP',
 PHYS_PAGE='258',
 XY='(-8250,2825)',
 ROT='0',
 VER='1',
 PACK_TYPE='0402LF',
 LOCATION='R1251',
 CDS_LIB='pure_quanta',
 CDS_PART_NAME='Q_RES_0402LF-0,5%,1/16W,CHIP,CS00002JB13',
 ROOM='ADC_TI_BOM1',
 PART_NUMBER='CS00002JB13',
 VALUE='0',
 PRIM_FILE='./archive_libs/logical/q_res/chips/chips.prt';

PART_NAME
 R1252 'Q_RES_0402LF-0,5%,1/16W,CHIP,CS00002JB13':
 ROOM='ADC_TI_BOM1';

SECTION_NUMBER 1
 '@T6G_MB_LIB.T6G(SCH_1):PAGE263_I190@PURE_QUANTA.Q_RES(CHIPS)':
 C_PATH='@t6g_mb_lib.t6g(sch_1):page263_i190@pure_quanta.q_res(chips)',
 P_PATH='@t6g_mb_lib.t6g(sch_1):page258_i190@pure_quanta.q_res(chips)',
 PATH='I190',
 DRAWING='@T6G_MB_LIB.T6G(SCH_1):PAGE263',
 WATTAGE='1/16W',
 TOLERANCE='5%',
 MATERIAL='CHIP',
 PHYS_PAGE='258',
 XY='(-8200,1225)',
 ROT='0',
 VER='1',
 PACK_TYPE='0402LF',
 LOCATION='R1252',
 CDS_LIB='pure_quanta',
 CDS_PART_NAME='Q_RES_0402LF-0,5%,1/16W,CHIP,CS00002JB13',
 ROOM='ADC_TI_BOM1',
 PART_NUMBER='CS00002JB13',
 VALUE='0',
 PRIM_FILE='./archive_libs/logical/q_res/chips/chips.prt';

PART_NAME
 R1253 'Q_RES_0402LF-33,5%,1/16W,CHIP,CS03302JB10':;

SECTION_NUMBER 1
 '@T6G_MB_LIB.T6G(SCH_1):PAGE141_I211@PURE_QUANTA.Q_RES(CHIPS)':
 C_PATH='@t6g_mb_lib.t6g(sch_1):page141_i211@pure_quanta.q_res(chips)',
 P_PATH='@t6g_mb_lib.t6g(sch_1):page164_i211@pure_quanta.q_res(chips)',
 PATH='I211',
 DRAWING='@T6G_MB_LIB.T6G(SCH_1):PAGE141',
 BOM_COST='MEM',
 WATTAGE='1/16W',
 TOLERANCE='5%',
 MATERIAL='CHIP',
 PHYS_PAGE='164',
 XY='(-6250,2325)',
 ROT='2',
 VER='1',
 PACK_TYPE='0402LF',
 LOCATION='R1253',
 CDS_LIB='pure_quanta',
 CDS_PART_NAME='Q_RES_0402LF-33,5%,1/16W,CHIP,CS03302JB10',
 PART_NUMBER='CS03302JB10',
 VALUE='33',
 PRIM_FILE='./archive_libs/logical/q_res/chips/chips.prt';

PART_NAME
 R1254 'Q_RES_0402LF-0,5%,1/16W,CHIP,CS00002JB13':
 ROOM='ADC_TI_BOM1';

SECTION_NUMBER 1
 '@T6G_MB_LIB.T6G(SCH_1):PAGE263_I226@PURE_QUANTA.Q_RES(CHIPS)':
 C_PATH='@t6g_mb_lib.t6g(sch_1):page263_i226@pure_quanta.q_res(chips)',
 P_PATH='@t6g_mb_lib.t6g(sch_1):page258_i226@pure_quanta.q_res(chips)',
 PATH='I226',
 DRAWING='@T6G_MB_LIB.T6G(SCH_1):PAGE263',
 WATTAGE='1/16W',
 TOLERANCE='5%',
 MATERIAL='CHIP',
 PHYS_PAGE='258',
 XY='(-6150,2650)',
 ROT='0',
 VER='1',
 PACK_TYPE='0402LF',
 LOCATION='R1254',
 CDS_LIB='pure_quanta',
 CDS_PART_NAME='Q_RES_0402LF-0,5%,1/16W,CHIP,CS00002JB13',
 ROOM='ADC_TI_BOM1',
 PART_NUMBER='CS00002JB13',
 VALUE='0',
 PRIM_FILE='./archive_libs/logical/q_res/chips/chips.prt';

PART_NAME
 R1255 'Q_RES_0402LF-0,5%,1/16W,CHIP,CS00002JB13':
 ROOM='ADC_TI_BOM1';

SECTION_NUMBER 1
 '@T6G_MB_LIB.T6G(SCH_1):PAGE263_I214@PURE_QUANTA.Q_RES(CHIPS)':
 C_PATH='@t6g_mb_lib.t6g(sch_1):page263_i214@pure_quanta.q_res(chips)',
 P_PATH='@t6g_mb_lib.t6g(sch_1):page258_i214@pure_quanta.q_res(chips)',
 PATH='I214',
 DRAWING='@T6G_MB_LIB.T6G(SCH_1):PAGE263',
 WATTAGE='1/16W',
 TOLERANCE='5%',
 MATERIAL='CHIP',
 PHYS_PAGE='258',
 XY='(-6050,4075)',
 ROT='0',
 VER='1',
 PACK_TYPE='0402LF',
 LOCATION='R1255',
 CDS_LIB='pure_quanta',
 CDS_PART_NAME='Q_RES_0402LF-0,5%,1/16W,CHIP,CS00002JB13',
 ROOM='ADC_TI_BOM1',
 PART_NUMBER='CS00002JB13',
 VALUE='0',
 PRIM_FILE='./archive_libs/logical/q_res/chips/chips.prt';

PART_NAME
 R1256 'Q_RES_0402LF-0,5%,1/16W,CHIP,CS00002JB13':
 ROOM='ADC_TI_BOM1';

SECTION_NUMBER 1
 '@T6G_MB_LIB.T6G(SCH_1):PAGE263_I239@PURE_QUANTA.Q_RES(CHIPS)':
 C_PATH='@t6g_mb_lib.t6g(sch_1):page263_i239@pure_quanta.q_res(chips)',
 P_PATH='@t6g_mb_lib.t6g(sch_1):page258_i239@pure_quanta.q_res(chips)',
 PATH='I239',
 DRAWING='@T6G_MB_LIB.T6G(SCH_1):PAGE263',
 WATTAGE='1/16W',
 TOLERANCE='5%',
 MATERIAL='CHIP',
 PHYS_PAGE='258',
 XY='(-5975,1125)',
 ROT='0',
 VER='1',
 PACK_TYPE='0402LF',
 LOCATION='R1256',
 CDS_LIB='pure_quanta',
 CDS_PART_NAME='Q_RES_0402LF-0,5%,1/16W,CHIP,CS00002JB13',
 ROOM='ADC_TI_BOM1',
 PART_NUMBER='CS00002JB13',
 VALUE='0',
 PRIM_FILE='./archive_libs/logical/q_res/chips/chips.prt';

PART_NAME
 R1257 'Q_RES_0402LF-0,5%,1/16W,CHIP,CS00002JB13':
 ROOM='ADC_TI_BOM1';

SECTION_NUMBER 1
 '@T6G_MB_LIB.T6G(SCH_1):PAGE263_I203@PURE_QUANTA.Q_RES(CHIPS)':
 C_PATH='@t6g_mb_lib.t6g(sch_1):page263_i203@pure_quanta.q_res(chips)',
 P_PATH='@t6g_mb_lib.t6g(sch_1):page258_i203@pure_quanta.q_res(chips)',
 PATH='I203',
 DRAWING='@T6G_MB_LIB.T6G(SCH_1):PAGE263',
 WATTAGE='1/16W',
 TOLERANCE='5%',
 MATERIAL='CHIP',
 PHYS_PAGE='258',
 XY='(-5925,5600)',
 ROT='0',
 VER='1',
 PACK_TYPE='0402LF',
 LOCATION='R1257',
 CDS_LIB='pure_quanta',
 CDS_PART_NAME='Q_RES_0402LF-0,5%,1/16W,CHIP,CS00002JB13',
 ROOM='ADC_TI_BOM1',
 PART_NUMBER='CS00002JB13',
 VALUE='0',
 PRIM_FILE='./archive_libs/logical/q_res/chips/chips.prt';

PART_NAME
 R1258 'Q_RES_0402LF-0,5%,1/16W,EMPTY,CS00002JB13':
 ROOM='ADC_MAM_BOM2';

SECTION_NUMBER 1
 '@T6G_MB_LIB.T6G(SCH_1):PAGE263_I22@PURE_QUANTA.Q_RES(CHIPS)':
 C_PATH='@t6g_mb_lib.t6g(sch_1):page263_i22@pure_quanta.q_res(chips)',
 P_PATH='@t6g_mb_lib.t6g(sch_1):page258_i22@pure_quanta.q_res(chips)',
 PATH='I22',
 DRAWING='@T6G_MB_LIB.T6G(SCH_1):PAGE263',
 WATTAGE='1/16W',
 TOLERANCE='5%',
 MATERIAL='EMPTY',
 PHYS_PAGE='258',
 XY='(-8350,4450)',
 ROT='0',
 VER='1',
 PACK_TYPE='0402LF',
 LOCATION='R1258',
 CDS_LIB='pure_quanta',
 CDS_PART_NAME='Q_RES_0402LF-0,5%,1/16W,EMPTY,CS00002JB13',
 ROOM='ADC_MAM_BOM2',
 PART_NUMBER='CS00002JB13',
 VALUE='0',
 PRIM_FILE='./archive_libs/logical/q_res/chips/chips.prt';

PART_NAME
 R1259 'Q_RES_0402LF-0,5%,1/16W,CHIP,CS00002JB13':
 ROOM='ADC_TI_BOM1';

SECTION_NUMBER 1
 '@T6G_MB_LIB.T6G(SCH_1):PAGE263_I21@PURE_QUANTA.Q_RES(CHIPS)':
 C_PATH='@t6g_mb_lib.t6g(sch_1):page263_i21@pure_quanta.q_res(chips)',
 P_PATH='@t6g_mb_lib.t6g(sch_1):page258_i21@pure_quanta.q_res(chips)',
 PATH='I21',
 DRAWING='@T6G_MB_LIB.T6G(SCH_1):PAGE263',
 WATTAGE='1/16W',
 TOLERANCE='5%',
 MATERIAL='CHIP',
 PHYS_PAGE='258',
 XY='(-8350,4300)',
 ROT='0',
 VER='1',
 PACK_TYPE='0402LF',
 LOCATION='R1259',
 CDS_LIB='pure_quanta',
 CDS_PART_NAME='Q_RES_0402LF-0,5%,1/16W,CHIP,CS00002JB13',
 ROOM='ADC_TI_BOM1',
 PART_NUMBER='CS00002JB13',
 VALUE='0',
 PRIM_FILE='./archive_libs/logical/q_res/chips/chips.prt';

PART_NAME
 R1260 'Q_RES_0402LF-0,5%,1/16W,EMPTY,CS00002JB13':
 ROOM='ADC_MAM_BOM2';

SECTION_NUMBER 1
 '@T6G_MB_LIB.T6G(SCH_1):PAGE263_I16@PURE_QUANTA.Q_RES(CHIPS)':
 C_PATH='@t6g_mb_lib.t6g(sch_1):page263_i16@pure_quanta.q_res(chips)',
 P_PATH='@t6g_mb_lib.t6g(sch_1):page258_i16@pure_quanta.q_res(chips)',
 PATH='I16',
 DRAWING='@T6G_MB_LIB.T6G(SCH_1):PAGE263',
 WATTAGE='1/16W',
 TOLERANCE='5%',
 MATERIAL='EMPTY',
 PHYS_PAGE='258',
 XY='(-8400,5775)',
 ROT='0',
 VER='1',
 PACK_TYPE='0402LF',
 LOCATION='R1260',
 CDS_LIB='pure_quanta',
 CDS_PART_NAME='Q_RES_0402LF-0,5%,1/16W,EMPTY,CS00002JB13',
 ROOM='ADC_MAM_BOM2',
 PART_NUMBER='CS00002JB13',
 VALUE='0',
 PRIM_FILE='./archive_libs/logical/q_res/chips/chips.prt';

PART_NAME
 R1261 'Q_RES_0402LF-10K,5%,1/16W,CHIP,CS31002JB08':;

SECTION_NUMBER 1
 '@T6G_MB_LIB.T6G(SCH_1):PAGE144_I15@PURE_QUANTA.Q_RES(CHIPS)':
 C_PATH='@t6g_mb_lib.t6g(sch_1):page144_i15@pure_quanta.q_res(chips)',
 P_PATH='@t6g_mb_lib.t6g(sch_1):page167_i15@pure_quanta.q_res(chips)',
 PATH='I15',
 DRAWING='@T6G_MB_LIB.T6G(SCH_1):PAGE144',
 WATTAGE='1/16W',
 TOLERANCE='5%',
 MATERIAL='CHIP',
 PHYS_PAGE='167',
 XY='(-8200,5800)',
 ROT='2',
 VER='2',
 PACK_TYPE='0402LF',
 LOCATION='R1261',
 CDS_LIB='pure_quanta',
 CDS_PART_NAME='Q_RES_0402LF-10K,5%,1/16W,CHIP,CS31002JB08',
 PART_NUMBER='CS31002JB08',
 VALUE='10K',
 PRIM_FILE='./archive_libs/logical/q_res/chips/chips.prt';

PART_NAME
 R1262 'Q_RES_0402LF-10K,5%,1/16W,CHIP,CS31002JB08':;

SECTION_NUMBER 1
 '@T6G_MB_LIB.T6G(SCH_1):PAGE144_I30@PURE_QUANTA.Q_RES(CHIPS)':
 C_PATH='@t6g_mb_lib.t6g(sch_1):page144_i30@pure_quanta.q_res(chips)',
 P_PATH='@t6g_mb_lib.t6g(sch_1):page167_i30@pure_quanta.q_res(chips)',
 PATH='I30',
 DRAWING='@T6G_MB_LIB.T6G(SCH_1):PAGE144',
 WATTAGE='1/16W',
 TOLERANCE='5%',
 MATERIAL='CHIP',
 PHYS_PAGE='167',
 XY='(-8075,2550)',
 ROT='2',
 VER='2',
 PACK_TYPE='0402LF',
 LOCATION='R1262',
 CDS_LIB='pure_quanta',
 CDS_PART_NAME='Q_RES_0402LF-10K,5%,1/16W,CHIP,CS31002JB08',
 PART_NUMBER='CS31002JB08',
 VALUE='10K',
 PRIM_FILE='./archive_libs/logical/q_res/chips/chips.prt';

PART_NAME
 R1263 'Q_RES_0402LF-0,5%,1/16W,CHIP,CS00002JB13':
 ROOM='ADC_TI_BOM1';

SECTION_NUMBER 1
 '@T6G_MB_LIB.T6G(SCH_1):PAGE263_I15@PURE_QUANTA.Q_RES(CHIPS)':
 C_PATH='@t6g_mb_lib.t6g(sch_1):page263_i15@pure_quanta.q_res(chips)',
 P_PATH='@t6g_mb_lib.t6g(sch_1):page258_i15@pure_quanta.q_res(chips)',
 PATH='I15',
 DRAWING='@T6G_MB_LIB.T6G(SCH_1):PAGE263',
 WATTAGE='1/16W',
 TOLERANCE='5%',
 MATERIAL='CHIP',
 PHYS_PAGE='258',
 XY='(-8400,5625)',
 ROT='0',
 VER='1',
 PACK_TYPE='0402LF',
 LOCATION='R1263',
 CDS_LIB='pure_quanta',
 CDS_PART_NAME='Q_RES_0402LF-0,5%,1/16W,CHIP,CS00002JB13',
 ROOM='ADC_TI_BOM1',
 PART_NUMBER='CS00002JB13',
 VALUE='0',
 PRIM_FILE='./archive_libs/logical/q_res/chips/chips.prt';

PART_NAME
 R1264 'Q_RES_0402LF-1K,1%,1/16W,EMPTY,CS21002FB06':;

SECTION_NUMBER 1
 '@T6G_MB_LIB.T6G(SCH_1):PAGE144_I44@PURE_QUANTA.Q_RES(CHIPS)':
 C_PATH='@t6g_mb_lib.t6g(sch_1):page144_i44@pure_quanta.q_res(chips)',
 P_PATH='@t6g_mb_lib.t6g(sch_1):page167_i44@pure_quanta.q_res(chips)',
 PATH='I44',
 DRAWING='@T6G_MB_LIB.T6G(SCH_1):PAGE144',
 WATTAGE='1/16W',
 TOLERANCE='1%',
 MATERIAL='EMPTY',
 PHYS_PAGE='167',
 XY='(-5025,2450)',
 ROT='2',
 VER='2',
 PACK_TYPE='0402LF',
 LOCATION='R1264',
 CDS_LIB='pure_quanta',
 CDS_PART_NAME='Q_RES_0402LF-1K,1%,1/16W,EMPTY,CS21002FB06',
 PART_NUMBER='CS21002FB06',
 VALUE='1K',
 PRIM_FILE='./archive_libs/logical/q_res/chips/chips.prt';

PART_NAME
 R1265 'Q_RES_0402LF-10K,5%,1/16W,CHIP,CS31002JB08':;

SECTION_NUMBER 1
 '@T6G_MB_LIB.T6G(SCH_1):PAGE144_I52@PURE_QUANTA.Q_RES(CHIPS)':
 C_PATH='@t6g_mb_lib.t6g(sch_1):page144_i52@pure_quanta.q_res(chips)',
 P_PATH='@t6g_mb_lib.t6g(sch_1):page167_i52@pure_quanta.q_res(chips)',
 PATH='I52',
 DRAWING='@T6G_MB_LIB.T6G(SCH_1):PAGE144',
 WATTAGE='1/16W',
 TOLERANCE='5%',
 MATERIAL='CHIP',
 PHYS_PAGE='167',
 XY='(-4075,5150)',
 ROT='2',
 VER='2',
 PACK_TYPE='0402LF',
 LOCATION='R1265',
 CDS_LIB='pure_quanta',
 CDS_PART_NAME='Q_RES_0402LF-10K,5%,1/16W,CHIP,CS31002JB08',
 PART_NUMBER='CS31002JB08',
 VALUE='10K',
 PRIM_FILE='./archive_libs/logical/q_res/chips/chips.prt';

PART_NAME
 R1266 'Q_RES_0402LF-200,1%,1/16W,CHIP,CS12002FB06':;

SECTION_NUMBER 1
 '@T6G_MB_LIB.T6G(SCH_1):PAGE84_I45@PURE_QUANTA.Q_RES(CHIPS)':
 C_PATH='@t6g_mb_lib.t6g(sch_1):page84_i45@pure_quanta.q_res(chips)',
 P_PATH='@t6g_mb_lib.t6g(sch_1):page85_i45@pure_quanta.q_res(chips)',
 PATH='I45',
 DRAWING='@T6G_MB_LIB.T6G(SCH_1):PAGE84',
 WATTAGE='1/16W',
 TOLERANCE='1%',
 MATERIAL='CHIP',
 PHYS_PAGE='85',
 XY='(-3700,5700)',
 ROT='0',
 VER='1',
 PACK_TYPE='0402LF',
 LOCATION='R1266',
 CDS_LIB='pure_quanta',
 CDS_PART_NAME='Q_RES_0402LF-200,1%,1/16W,CHIP,CS12002FB06',
 PART_NUMBER='CS12002FB06',
 VALUE='200',
 PRIM_FILE='./archive_libs/logical/q_res/chips/chips.prt';

PART_NAME
 R1267 'Q_RES_0402LF-4.7K,1%,1/16W,EMPTY,CS24702FB06':
 ROOM='ADC_TI_BOM1';

SECTION_NUMBER 1
 '@T6G_MB_LIB.T6G(SCH_1):PAGE263_I131@PURE_QUANTA.Q_RES(CHIPS)':
 C_PATH='@t6g_mb_lib.t6g(sch_1):page263_i131@pure_quanta.q_res(chips)',
 P_PATH='@t6g_mb_lib.t6g(sch_1):page258_i131@pure_quanta.q_res(chips)',
 PATH='I131',
 DRAWING='@T6G_MB_LIB.T6G(SCH_1):PAGE263',
 WATTAGE='1/16W',
 TOLERANCE='1%',
 MATERIAL='EMPTY',
 PHYS_PAGE='258',
 XY='(-3425,2350)',
 ROT='0',
 VER='2',
 PACK_TYPE='0402LF',
 LOCATION='R1267',
 CDS_LIB='pure_quanta',
 CDS_PART_NAME='Q_RES_0402LF-4.7K,1%,1/16W,EMPTY,CS24702FB06',
 ROOM='ADC_TI_BOM1',
 PART_NUMBER='CS24702FB06',
 VALUE='4.7K',
 PRIM_FILE='./archive_libs/logical/q_res/chips/chips.prt';

PART_NAME
 R1268 'Q_RES_0402LF-4.7K,1%,1/16W,EMPTY,CS24702FB06':
 ROOM='ADC_TI_BOM1';

SECTION_NUMBER 1
 '@T6G_MB_LIB.T6G(SCH_1):PAGE263_I119@PURE_QUANTA.Q_RES(CHIPS)':
 C_PATH='@t6g_mb_lib.t6g(sch_1):page263_i119@pure_quanta.q_res(chips)',
 P_PATH='@t6g_mb_lib.t6g(sch_1):page258_i119@pure_quanta.q_res(chips)',
 PATH='I119',
 DRAWING='@T6G_MB_LIB.T6G(SCH_1):PAGE263',
 WATTAGE='1/16W',
 TOLERANCE='1%',
 MATERIAL='EMPTY',
 PHYS_PAGE='258',
 XY='(-3425,1850)',
 ROT='0',
 VER='2',
 PACK_TYPE='0402LF',
 LOCATION='R1268',
 CDS_LIB='pure_quanta',
 CDS_PART_NAME='Q_RES_0402LF-4.7K,1%,1/16W,EMPTY,CS24702FB06',
 ROOM='ADC_TI_BOM1',
 PART_NUMBER='CS24702FB06',
 VALUE='4.7K',
 PRIM_FILE='./archive_libs/logical/q_res/chips/chips.prt';

PART_NAME
 R1269 'Q_RES_0402LF-0,5%,1/16W,CHIP,CS00002JB13':;

SECTION_NUMBER 1
 '@T6G_MB_LIB.T6G(SCH_1):PAGE466_I62@PURE_QUANTA.Q_RES(CHIPS)':
 C_PATH='@t6g_mb_lib.t6g(sch_1):page466_i62@pure_quanta.q_res(chips)',
 P_PATH='@t6g_mb_lib.t6g(sch_1):page357_i62@pure_quanta.q_res(chips)',
 PATH='I62',
 DRAWING='@T6G_MB_LIB.T6G(SCH_1):PAGE466',
 WATTAGE='1/16W',
 TOLERANCE='5%',
 MATERIAL='CHIP',
 PHYS_PAGE='357',
 XY='(-3075,1400)',
 ROT='0',
 VER='1',
 PACK_TYPE='0402LF',
 LOCATION='R1269',
 CDS_LIB='pure_quanta',
 CDS_PART_NAME='Q_RES_0402LF-0,5%,1/16W,CHIP,CS00002JB13',
 PART_NUMBER='CS00002JB13',
 VALUE='0',
 PRIM_FILE='./archive_libs/logical/q_res/chips/chips.prt';

PART_NAME
 R1270 'Q_RES_0402LF-0,5%,1/16W,CHIP,CS00002JB13':;

SECTION_NUMBER 1
 '@T6G_MB_LIB.T6G(SCH_1):PAGE466_I23@PURE_QUANTA.Q_RES(CHIPS)':
 C_PATH='@t6g_mb_lib.t6g(sch_1):page466_i23@pure_quanta.q_res(chips)',
 P_PATH='@t6g_mb_lib.t6g(sch_1):page357_i23@pure_quanta.q_res(chips)',
 PATH='I23',
 DRAWING='@T6G_MB_LIB.T6G(SCH_1):PAGE466',
 WATTAGE='1/16W',
 TOLERANCE='5%',
 MATERIAL='CHIP',
 PHYS_PAGE='357',
 XY='(-2525,5725)',
 ROT='0',
 VER='1',
 PACK_TYPE='0402LF',
 LOCATION='R1270',
 CDS_LIB='pure_quanta',
 CDS_PART_NAME='Q_RES_0402LF-0,5%,1/16W,CHIP,CS00002JB13',
 PART_NUMBER='CS00002JB13',
 VALUE='0',
 PRIM_FILE='./archive_libs/logical/q_res/chips/chips.prt';

PART_NAME
 R1271 'Q_RES_0402LF-0,5%,1/16W,CHIP,CS00002JB13':;

SECTION_NUMBER 1
 '@T6G_MB_LIB.T6G(SCH_1):PAGE466_I33@PURE_QUANTA.Q_RES(CHIPS)':
 C_PATH='@t6g_mb_lib.t6g(sch_1):page466_i33@pure_quanta.q_res(chips)',
 P_PATH='@t6g_mb_lib.t6g(sch_1):page357_i33@pure_quanta.q_res(chips)',
 PATH='I33',
 DRAWING='@T6G_MB_LIB.T6G(SCH_1):PAGE466',
 WATTAGE='1/16W',
 TOLERANCE='5%',
 MATERIAL='CHIP',
 PHYS_PAGE='357',
 XY='(-1875,3675)',
 ROT='0',
 VER='1',
 PACK_TYPE='0402LF',
 LOCATION='R1271',
 CDS_LIB='pure_quanta',
 CDS_PART_NAME='Q_RES_0402LF-0,5%,1/16W,CHIP,CS00002JB13',
 PART_NUMBER='CS00002JB13',
 VALUE='0',
 PRIM_FILE='./archive_libs/logical/q_res/chips/chips.prt';

PART_NAME
 R1272 'Q_RES_0402LF-0,5%,1/16W,CHIP,CS00002JB13':;

SECTION_NUMBER 1
 '@T6G_MB_LIB.T6G(SCH_1):PAGE466_I71@PURE_QUANTA.Q_RES(CHIPS)':
 C_PATH='@t6g_mb_lib.t6g(sch_1):page466_i71@pure_quanta.q_res(chips)',
 P_PATH='@t6g_mb_lib.t6g(sch_1):page357_i71@pure_quanta.q_res(chips)',
 PATH='I71',
 DRAWING='@T6G_MB_LIB.T6G(SCH_1):PAGE466',
 WATTAGE='1/16W',
 TOLERANCE='5%',
 MATERIAL='CHIP',
 PHYS_PAGE='357',
 XY='(-6400,1150)',
 ROT='0',
 VER='1',
 PACK_TYPE='0402LF',
 LOCATION='R1272',
 CDS_LIB='pure_quanta',
 CDS_PART_NAME='Q_RES_0402LF-0,5%,1/16W,CHIP,CS00002JB13',
 PART_NUMBER='CS00002JB13',
 VALUE='0',
 PRIM_FILE='./archive_libs/logical/q_res/chips/chips.prt';

PART_NAME
 R1273 'Q_RES_0402LF-0,5%,1/16W,CHIP,CS00002JB13':;

SECTION_NUMBER 1
 '@T6G_MB_LIB.T6G(SCH_1):PAGE466_I27@PURE_QUANTA.Q_RES(CHIPS)':
 C_PATH='@t6g_mb_lib.t6g(sch_1):page466_i27@pure_quanta.q_res(chips)',
 P_PATH='@t6g_mb_lib.t6g(sch_1):page357_i27@pure_quanta.q_res(chips)',
 PATH='I27',
 DRAWING='@T6G_MB_LIB.T6G(SCH_1):PAGE466',
 WATTAGE='1/16W',
 TOLERANCE='5%',
 MATERIAL='CHIP',
 PHYS_PAGE='357',
 XY='(-5850,5475)',
 ROT='0',
 VER='1',
 PACK_TYPE='0402LF',
 LOCATION='R1273',
 CDS_LIB='pure_quanta',
 CDS_PART_NAME='Q_RES_0402LF-0,5%,1/16W,CHIP,CS00002JB13',
 PART_NUMBER='CS00002JB13',
 VALUE='0',
 PRIM_FILE='./archive_libs/logical/q_res/chips/chips.prt';

PART_NAME
 R1274 'Q_RES_0402LF-0,5%,1/16W,CHIP,CS00002JB13':;

SECTION_NUMBER 1
 '@T6G_MB_LIB.T6G(SCH_1):PAGE466_I42@PURE_QUANTA.Q_RES(CHIPS)':
 C_PATH='@t6g_mb_lib.t6g(sch_1):page466_i42@pure_quanta.q_res(chips)',
 P_PATH='@t6g_mb_lib.t6g(sch_1):page357_i42@pure_quanta.q_res(chips)',
 PATH='I42',
 DRAWING='@T6G_MB_LIB.T6G(SCH_1):PAGE466',
 WATTAGE='1/16W',
 TOLERANCE='5%',
 MATERIAL='CHIP',
 PHYS_PAGE='357',
 XY='(-5200,3425)',
 ROT='0',
 VER='1',
 PACK_TYPE='0402LF',
 LOCATION='R1274',
 CDS_LIB='pure_quanta',
 CDS_PART_NAME='Q_RES_0402LF-0,5%,1/16W,CHIP,CS00002JB13',
 PART_NUMBER='CS00002JB13',
 VALUE='0',
 PRIM_FILE='./archive_libs/logical/q_res/chips/chips.prt';

PART_NAME
 R1275 'Q_RES_0402LF-0,5%,1/16W,CHIP,CS00002JB13':;

SECTION_NUMBER 1
 '@T6G_MB_LIB.T6G(SCH_1):PAGE466_I70@PURE_QUANTA.Q_RES(CHIPS)':
 C_PATH='@t6g_mb_lib.t6g(sch_1):page466_i70@pure_quanta.q_res(chips)',
 P_PATH='@t6g_mb_lib.t6g(sch_1):page357_i70@pure_quanta.q_res(chips)',
 PATH='I70',
 DRAWING='@T6G_MB_LIB.T6G(SCH_1):PAGE466',
 WATTAGE='1/16W',
 TOLERANCE='5%',
 MATERIAL='CHIP',
 PHYS_PAGE='357',
 XY='(-6400,1100)',
 ROT='0',
 VER='1',
 PACK_TYPE='0402LF',
 LOCATION='R1275',
 CDS_LIB='pure_quanta',
 CDS_PART_NAME='Q_RES_0402LF-0,5%,1/16W,CHIP,CS00002JB13',
 PART_NUMBER='CS00002JB13',
 VALUE='0',
 PRIM_FILE='./archive_libs/logical/q_res/chips/chips.prt';

PART_NAME
 R1276 'Q_RES_0402LF-0,5%,1/16W,CHIP,CS00002JB13':;

SECTION_NUMBER 1
 '@T6G_MB_LIB.T6G(SCH_1):PAGE466_I14@PURE_QUANTA.Q_RES(CHIPS)':
 C_PATH='@t6g_mb_lib.t6g(sch_1):page466_i14@pure_quanta.q_res(chips)',
 P_PATH='@t6g_mb_lib.t6g(sch_1):page357_i14@pure_quanta.q_res(chips)',
 PATH='I14',
 DRAWING='@T6G_MB_LIB.T6G(SCH_1):PAGE466',
 WATTAGE='1/16W',
 TOLERANCE='5%',
 MATERIAL='CHIP',
 PHYS_PAGE='357',
 XY='(-5850,5425)',
 ROT='0',
 VER='1',
 PACK_TYPE='0402LF',
 LOCATION='R1276',
 CDS_LIB='pure_quanta',
 CDS_PART_NAME='Q_RES_0402LF-0,5%,1/16W,CHIP,CS00002JB13',
 PART_NUMBER='CS00002JB13',
 VALUE='0',
 PRIM_FILE='./archive_libs/logical/q_res/chips/chips.prt';

PART_NAME
 R1277 'Q_RES_0402LF-0,5%,1/16W,CHIP,CS00002JB13':;

SECTION_NUMBER 1
 '@T6G_MB_LIB.T6G(SCH_1):PAGE466_I41@PURE_QUANTA.Q_RES(CHIPS)':
 C_PATH='@t6g_mb_lib.t6g(sch_1):page466_i41@pure_quanta.q_res(chips)',
 P_PATH='@t6g_mb_lib.t6g(sch_1):page357_i41@pure_quanta.q_res(chips)',
 PATH='I41',
 DRAWING='@T6G_MB_LIB.T6G(SCH_1):PAGE466',
 WATTAGE='1/16W',
 TOLERANCE='5%',
 MATERIAL='CHIP',
 PHYS_PAGE='357',
 XY='(-5200,3375)',
 ROT='0',
 VER='1',
 PACK_TYPE='0402LF',
 LOCATION='R1277',
 CDS_LIB='pure_quanta',
 CDS_PART_NAME='Q_RES_0402LF-0,5%,1/16W,CHIP,CS00002JB13',
 PART_NUMBER='CS00002JB13',
 VALUE='0',
 PRIM_FILE='./archive_libs/logical/q_res/chips/chips.prt';

PART_NAME
 R1278 'Q_RES_0402LF-33,5%,1/16W,CHIP,CS03302JB10':;

SECTION_NUMBER 1
 '@T6G_MB_LIB.T6G(SCH_1):PAGE80_I105@PURE_QUANTA.Q_RES(CHIPS)':
 C_PATH='@t6g_mb_lib.t6g(sch_1):page80_i105@pure_quanta.q_res(chips)',
 P_PATH='@t6g_mb_lib.t6g(sch_1):page81_i105@pure_quanta.q_res(chips)',
 PATH='I105',
 DRAWING='@T6G_MB_LIB.T6G(SCH_1):PAGE80',
 BOM_COST='MEM',
 WATTAGE='1/16W',
 TOLERANCE='5%',
 MATERIAL='CHIP',
 PHYS_PAGE='81',
 XY='(-6425,4625)',
 ROT='0',
 VER='1',
 PACK_TYPE='0402LF',
 LOCATION='R1278',
 CDS_LIB='pure_quanta',
 CDS_PART_NAME='Q_RES_0402LF-33,5%,1/16W,CHIP,CS03302JB10',
 PART_NUMBER='CS03302JB10',
 VALUE='33',
 PRIM_FILE='./archive_libs/logical/q_res/chips/chips.prt';

PART_NAME
 R1279 'Q_RES_0402LF-33,5%,1/16W,CHIP,CS03302JB10':;

SECTION_NUMBER 1
 '@T6G_MB_LIB.T6G(SCH_1):PAGE80_I103@PURE_QUANTA.Q_RES(CHIPS)':
 C_PATH='@t6g_mb_lib.t6g(sch_1):page80_i103@pure_quanta.q_res(chips)',
 P_PATH='@t6g_mb_lib.t6g(sch_1):page81_i103@pure_quanta.q_res(chips)',
 PATH='I103',
 DRAWING='@T6G_MB_LIB.T6G(SCH_1):PAGE80',
 BOM_COST='MEM',
 WATTAGE='1/16W',
 TOLERANCE='5%',
 MATERIAL='CHIP',
 PHYS_PAGE='81',
 XY='(-6425,4475)',
 ROT='0',
 VER='1',
 PACK_TYPE='0402LF',
 LOCATION='R1279',
 CDS_LIB='pure_quanta',
 CDS_PART_NAME='Q_RES_0402LF-33,5%,1/16W,CHIP,CS03302JB10',
 PART_NUMBER='CS03302JB10',
 VALUE='33',
 PRIM_FILE='./archive_libs/logical/q_res/chips/chips.prt';

PART_NAME
 R1280 'Q_RES_0402LF-33,5%,1/16W,CHIP,CS03302JB10':;

SECTION_NUMBER 1
 '@T6G_MB_LIB.T6G(SCH_1):PAGE80_I102@PURE_QUANTA.Q_RES(CHIPS)':
 C_PATH='@t6g_mb_lib.t6g(sch_1):page80_i102@pure_quanta.q_res(chips)',
 P_PATH='@t6g_mb_lib.t6g(sch_1):page81_i102@pure_quanta.q_res(chips)',
 PATH='I102',
 DRAWING='@T6G_MB_LIB.T6G(SCH_1):PAGE80',
 BOM_COST='MEM',
 WATTAGE='1/16W',
 TOLERANCE='5%',
 MATERIAL='CHIP',
 PHYS_PAGE='81',
 XY='(-6425,4275)',
 ROT='0',
 VER='1',
 PACK_TYPE='0402LF',
 LOCATION='R1280',
 CDS_LIB='pure_quanta',
 CDS_PART_NAME='Q_RES_0402LF-33,5%,1/16W,CHIP,CS03302JB10',
 PART_NUMBER='CS03302JB10',
 VALUE='33',
 PRIM_FILE='./archive_libs/logical/q_res/chips/chips.prt';

PART_NAME
 R1281 'Q_RES_0402LF-33,5%,1/16W,CHIP,CS03302JB10':;

SECTION_NUMBER 1
 '@T6G_MB_LIB.T6G(SCH_1):PAGE80_I101@PURE_QUANTA.Q_RES(CHIPS)':
 C_PATH='@t6g_mb_lib.t6g(sch_1):page80_i101@pure_quanta.q_res(chips)',
 P_PATH='@t6g_mb_lib.t6g(sch_1):page81_i101@pure_quanta.q_res(chips)',
 PATH='I101',
 DRAWING='@T6G_MB_LIB.T6G(SCH_1):PAGE80',
 BOM_COST='MEM',
 WATTAGE='1/16W',
 TOLERANCE='5%',
 MATERIAL='CHIP',
 PHYS_PAGE='81',
 XY='(-6425,4325)',
 ROT='0',
 VER='1',
 PACK_TYPE='0402LF',
 LOCATION='R1281',
 CDS_LIB='pure_quanta',
 CDS_PART_NAME='Q_RES_0402LF-33,5%,1/16W,CHIP,CS03302JB10',
 PART_NUMBER='CS03302JB10',
 VALUE='33',
 PRIM_FILE='./archive_libs/logical/q_res/chips/chips.prt';

PART_NAME
 R1282 'Q_RES_0402LF-33,5%,1/16W,CHIP,CS03302JB10':;

SECTION_NUMBER 1
 '@T6G_MB_LIB.T6G(SCH_1):PAGE80_I29@PURE_QUANTA.Q_RES(CHIPS)':
 C_PATH='@t6g_mb_lib.t6g(sch_1):page80_i29@pure_quanta.q_res(chips)',
 P_PATH='@t6g_mb_lib.t6g(sch_1):page81_i29@pure_quanta.q_res(chips)',
 PATH='I29',
 DRAWING='@T6G_MB_LIB.T6G(SCH_1):PAGE80',
 BOM_COST='MEM',
 WATTAGE='1/16W',
 TOLERANCE='5%',
 MATERIAL='CHIP',
 PHYS_PAGE='81',
 XY='(-6725,1325)',
 ROT='0',
 VER='1',
 PACK_TYPE='0402LF',
 LOCATION='R1282',
 CDS_LIB='pure_quanta',
 CDS_PART_NAME='Q_RES_0402LF-33,5%,1/16W,CHIP,CS03302JB10',
 PART_NUMBER='CS03302JB10',
 VALUE='33',
 PRIM_FILE='./archive_libs/logical/q_res/chips/chips.prt';

PART_NAME
 R1283 'Q_RES_0402LF-10,1%,1/16W,CHIP,CS01002FB07':;

SECTION_NUMBER 1
 '@T6G_MB_LIB.T6G(SCH_1):PAGE466_I74@PURE_QUANTA.Q_RES(CHIPS)':
 C_PATH='@t6g_mb_lib.t6g(sch_1):page466_i74@pure_quanta.q_res(chips)',
 P_PATH='@t6g_mb_lib.t6g(sch_1):page357_i74@pure_quanta.q_res(chips)',
 PATH='I74',
 DRAWING='@T6G_MB_LIB.T6G(SCH_1):PAGE466',
 WATTAGE='1/16W',
 TOLERANCE='1%',
 MATERIAL='CHIP',
 PHYS_PAGE='357',
 XY='(-6375,550)',
 ROT='0',
 VER='1',
 PACK_TYPE='0402LF',
 LOCATION='R1283',
 CDS_LIB='pure_quanta',
 CDS_PART_NAME='Q_RES_0402LF-10,1%,1/16W,CHIP,CS01002FB07',
 PART_NUMBER='CS01002FB07',
 VALUE='10',
 PRIM_FILE='./archive_libs/logical/q_res/chips/chips.prt';

PART_NAME
 R1284 'Q_RES_0402LF-10,1%,1/16W,CHIP,CS01002FB07':;

SECTION_NUMBER 1
 '@T6G_MB_LIB.T6G(SCH_1):PAGE466_I10@PURE_QUANTA.Q_RES(CHIPS)':
 C_PATH='@t6g_mb_lib.t6g(sch_1):page466_i10@pure_quanta.q_res(chips)',
 P_PATH='@t6g_mb_lib.t6g(sch_1):page357_i10@pure_quanta.q_res(chips)',
 PATH='I10',
 DRAWING='@T6G_MB_LIB.T6G(SCH_1):PAGE466',
 WATTAGE='1/16W',
 TOLERANCE='1%',
 MATERIAL='CHIP',
 PHYS_PAGE='357',
 XY='(-5825,4875)',
 ROT='0',
 VER='1',
 PACK_TYPE='0402LF',
 LOCATION='R1284',
 CDS_LIB='pure_quanta',
 CDS_PART_NAME='Q_RES_0402LF-10,1%,1/16W,CHIP,CS01002FB07',
 PART_NUMBER='CS01002FB07',
 VALUE='10',
 PRIM_FILE='./archive_libs/logical/q_res/chips/chips.prt';

PART_NAME
 R1285 'Q_RES_0402LF-4.7K,5%,1/16W,CHIP,CS24702JB10':;

SECTION_NUMBER 1
 '@T6G_MB_LIB.T6G(SCH_1):PAGE82_I77@PURE_QUANTA.Q_RES(CHIPS)':
 C_PATH='@t6g_mb_lib.t6g(sch_1):page82_i77@pure_quanta.q_res(chips)',
 P_PATH='@t6g_mb_lib.t6g(sch_1):page83_i77@pure_quanta.q_res(chips)',
 PATH='I77',
 DRAWING='@T6G_MB_LIB.T6G(SCH_1):PAGE82',
 WATTAGE='1/16W',
 TOLERANCE='5%',
 MATERIAL='CHIP',
 PHYS_PAGE='83',
 XY='(-4925,5900)',
 ROT='0',
 VER='1',
 PACK_TYPE='0402LF',
 LOCATION='R1285',
 CDS_LIB='pure_quanta',
 CDS_PART_NAME='Q_RES_0402LF-4.7K,5%,1/16W,CHIP,CS24702JB10',
 PART_NUMBER='CS24702JB10',
 VALUE='4.7K',
 PRIM_FILE='./archive_libs/logical/q_res/chips/chips.prt';

PART_NAME
 R1286 'Q_RES_0402LF-4.7K,5%,1/16W,CHIP,CS24702JB10':;

SECTION_NUMBER 1
 '@T6G_MB_LIB.T6G(SCH_1):PAGE82_I76@PURE_QUANTA.Q_RES(CHIPS)':
 C_PATH='@t6g_mb_lib.t6g(sch_1):page82_i76@pure_quanta.q_res(chips)',
 P_PATH='@t6g_mb_lib.t6g(sch_1):page83_i76@pure_quanta.q_res(chips)',
 PATH='I76',
 DRAWING='@T6G_MB_LIB.T6G(SCH_1):PAGE82',
 WATTAGE='1/16W',
 TOLERANCE='5%',
 MATERIAL='CHIP',
 PHYS_PAGE='83',
 XY='(-4925,5850)',
 ROT='0',
 VER='1',
 PACK_TYPE='0402LF',
 LOCATION='R1286',
 CDS_LIB='pure_quanta',
 CDS_PART_NAME='Q_RES_0402LF-4.7K,5%,1/16W,CHIP,CS24702JB10',
 PART_NUMBER='CS24702JB10',
 VALUE='4.7K',
 PRIM_FILE='./archive_libs/logical/q_res/chips/chips.prt';

PART_NAME
 R1287 'Q_RES_0402LF-4.7K,5%,1/16W,CHIP,CS24702JB10':;

SECTION_NUMBER 1
 '@T6G_MB_LIB.T6G(SCH_1):PAGE82_I74@PURE_QUANTA.Q_RES(CHIPS)':
 C_PATH='@t6g_mb_lib.t6g(sch_1):page82_i74@pure_quanta.q_res(chips)',
 P_PATH='@t6g_mb_lib.t6g(sch_1):page83_i74@pure_quanta.q_res(chips)',
 PATH='I74',
 DRAWING='@T6G_MB_LIB.T6G(SCH_1):PAGE82',
 WATTAGE='1/16W',
 TOLERANCE='5%',
 MATERIAL='CHIP',
 PHYS_PAGE='83',
 XY='(-4925,5400)',
 ROT='0',
 VER='1',
 PACK_TYPE='0402LF',
 LOCATION='R1287',
 CDS_LIB='pure_quanta',
 CDS_PART_NAME='Q_RES_0402LF-4.7K,5%,1/16W,CHIP,CS24702JB10',
 PART_NUMBER='CS24702JB10',
 VALUE='4.7K',
 PRIM_FILE='./archive_libs/logical/q_res/chips/chips.prt';

PART_NAME
 R1288 'Q_RES_0402LF-4.7K,5%,1/16W,CHIP,CS24702JB10':;

SECTION_NUMBER 1
 '@T6G_MB_LIB.T6G(SCH_1):PAGE82_I73@PURE_QUANTA.Q_RES(CHIPS)':
 C_PATH='@t6g_mb_lib.t6g(sch_1):page82_i73@pure_quanta.q_res(chips)',
 P_PATH='@t6g_mb_lib.t6g(sch_1):page83_i73@pure_quanta.q_res(chips)',
 PATH='I73',
 DRAWING='@T6G_MB_LIB.T6G(SCH_1):PAGE82',
 WATTAGE='1/16W',
 TOLERANCE='5%',
 MATERIAL='CHIP',
 PHYS_PAGE='83',
 XY='(-4925,5350)',
 ROT='0',
 VER='1',
 PACK_TYPE='0402LF',
 LOCATION='R1288',
 CDS_LIB='pure_quanta',
 CDS_PART_NAME='Q_RES_0402LF-4.7K,5%,1/16W,CHIP,CS24702JB10',
 PART_NUMBER='CS24702JB10',
 VALUE='4.7K',
 PRIM_FILE='./archive_libs/logical/q_res/chips/chips.prt';

PART_NAME
 R1289 'Q_RES_0402LF-100K,1%,1/16W,CHIP,CS41002FB09':;

SECTION_NUMBER 1
 '@T6G_MB_LIB.T6G(SCH_1):PAGE336_I56@PURE_QUANTA.Q_RES(CHIPS)':
 C_PATH='@t6g_mb_lib.t6g(sch_1):page336_i56@pure_quanta.q_res(chips)',
 P_PATH='@t6g_mb_lib.t6g(sch_1):page132_i56@pure_quanta.q_res(chips)',
 PATH='I56',
 DRAWING='@T6G_MB_LIB.T6G(SCH_1):PAGE336',
 WATTAGE='1/16W',
 TOLERANCE='1%',
 MATERIAL='CHIP',
 PHYS_PAGE='132',
 XY='(-175,3800)',
 ROT='0',
 VER='2',
 PACK_TYPE='0402LF',
 LOCATION='R1289',
 CDS_LIB='pure_quanta',
 CDS_PART_NAME='Q_RES_0402LF-100K,1%,1/16W,CHIP,CS41002FB09',
 PART_NUMBER='CS41002FB09',
 VALUE='100K',
 PRIM_FILE='./archive_libs/logical/q_res/chips/chips.prt';

PART_NAME
 R1290 'Q_RES_0402LF-22,1%,1/16W,EMPTY,CS02202FB02':;

SECTION_NUMBER 1
 '@T6G_MB_LIB.T6G(SCH_1):PAGE336_I98@PURE_QUANTA.Q_RES(CHIPS)':
 C_PATH='@t6g_mb_lib.t6g(sch_1):page336_i98@pure_quanta.q_res(chips)',
 P_PATH='@t6g_mb_lib.t6g(sch_1):page132_i98@pure_quanta.q_res(chips)',
 PATH='I98',
 DRAWING='@T6G_MB_LIB.T6G(SCH_1):PAGE336',
 WATTAGE='1/16W',
 TOLERANCE='1%',
 MATERIAL='EMPTY',
 PHYS_PAGE='132',
 XY='(3050,6900)',
 ROT='0',
 VER='1',
 PACK_TYPE='0402LF',
 LOCATION='R1290',
 CDS_LIB='pure_quanta',
 CDS_PART_NAME='Q_RES_0402LF-22,1%,1/16W,EMPTY,CS02202FB02',
 PART_NUMBER='CS02202FB02',
 VALUE='22',
 PRIM_FILE='./archive_libs/logical/q_res/chips/chips.prt';

PART_NAME
 R1291 'Q_RES_0402LF-10,1%,1/16W,CHIP,CS01002FB07':;

SECTION_NUMBER 1
 '@T6G_MB_LIB.T6G(SCH_1):PAGE466_I43@PURE_QUANTA.Q_RES(CHIPS)':
 C_PATH='@t6g_mb_lib.t6g(sch_1):page466_i43@pure_quanta.q_res(chips)',
 P_PATH='@t6g_mb_lib.t6g(sch_1):page357_i43@pure_quanta.q_res(chips)',
 PATH='I43',
 DRAWING='@T6G_MB_LIB.T6G(SCH_1):PAGE466',
 WATTAGE='1/16W',
 TOLERANCE='1%',
 MATERIAL='CHIP',
 PHYS_PAGE='357',
 XY='(-5175,2825)',
 ROT='0',
 VER='1',
 PACK_TYPE='0402LF',
 LOCATION='R1291',
 CDS_LIB='pure_quanta',
 CDS_PART_NAME='Q_RES_0402LF-10,1%,1/16W,CHIP,CS01002FB07',
 PART_NUMBER='CS01002FB07',
 VALUE='10',
 PRIM_FILE='./archive_libs/logical/q_res/chips/chips.prt';

PART_NAME
 R1292 'Q_RES_0402LF-10,1%,1/16W,CHIP,CS01002FB07':;

SECTION_NUMBER 1
 '@T6G_MB_LIB.T6G(SCH_1):PAGE466_I75@PURE_QUANTA.Q_RES(CHIPS)':
 C_PATH='@t6g_mb_lib.t6g(sch_1):page466_i75@pure_quanta.q_res(chips)',
 P_PATH='@t6g_mb_lib.t6g(sch_1):page357_i75@pure_quanta.q_res(chips)',
 PATH='I75',
 DRAWING='@T6G_MB_LIB.T6G(SCH_1):PAGE466',
 WATTAGE='1/16W',
 TOLERANCE='1%',
 MATERIAL='CHIP',
 PHYS_PAGE='357',
 XY='(-6375,275)',
 ROT='0',
 VER='1',
 PACK_TYPE='0402LF',
 LOCATION='R1292',
 CDS_LIB='pure_quanta',
 CDS_PART_NAME='Q_RES_0402LF-10,1%,1/16W,CHIP,CS01002FB07',
 PART_NUMBER='CS01002FB07',
 VALUE='10',
 PRIM_FILE='./archive_libs/logical/q_res/chips/chips.prt';

PART_NAME
 R1293 'Q_RES_0402LF-0,5%,1/16W,CHIP,CS00002JB13':;

SECTION_NUMBER 1
 '@T6G_MB_LIB.T6G(SCH_1):PAGE136_I35@PURE_QUANTA.Q_RES(CHIPS)':
 C_PATH='@t6g_mb_lib.t6g(sch_1):page136_i35@pure_quanta.q_res(chips)',
 P_PATH='@t6g_mb_lib.t6g(sch_1):page159_i35@pure_quanta.q_res(chips)',
 PATH='I35',
 DRAWING='@T6G_MB_LIB.T6G(SCH_1):PAGE136',
 WATTAGE='1/16W',
 TOLERANCE='5%',
 MATERIAL='CHIP',
 PHYS_PAGE='159',
 XY='(-3200,2950)',
 ROT='2',
 VER='1',
 PACK_TYPE='0402LF',
 LOCATION='R1293',
 CDS_LIB='pure_quanta',
 CDS_PART_NAME='Q_RES_0402LF-0,5%,1/16W,CHIP,CS00002JB13',
 PART_NUMBER='CS00002JB13',
 VALUE='0',
 PRIM_FILE='./archive_libs/logical/q_res/chips/chips.prt';

PART_NAME
 R1294 'Q_RES_0402LF-0,5%,1/16W,CHIP,CS00002JB13':;

SECTION_NUMBER 1
 '@T6G_MB_LIB.T6G(SCH_1):PAGE136_I36@PURE_QUANTA.Q_RES(CHIPS)':
 C_PATH='@t6g_mb_lib.t6g(sch_1):page136_i36@pure_quanta.q_res(chips)',
 P_PATH='@t6g_mb_lib.t6g(sch_1):page159_i36@pure_quanta.q_res(chips)',
 PATH='I36',
 DRAWING='@T6G_MB_LIB.T6G(SCH_1):PAGE136',
 WATTAGE='1/16W',
 TOLERANCE='5%',
 MATERIAL='CHIP',
 PHYS_PAGE='159',
 XY='(-3200,2900)',
 ROT='2',
 VER='1',
 PACK_TYPE='0402LF',
 LOCATION='R1294',
 CDS_LIB='pure_quanta',
 CDS_PART_NAME='Q_RES_0402LF-0,5%,1/16W,CHIP,CS00002JB13',
 PART_NUMBER='CS00002JB13',
 VALUE='0',
 PRIM_FILE='./archive_libs/logical/q_res/chips/chips.prt';

PART_NAME
 R1295 'Q_RES_0402LF-0,5%,1/16W,CHIP,CS00002JB13':;

SECTION_NUMBER 1
 '@T6G_MB_LIB.T6G(SCH_1):PAGE136_I37@PURE_QUANTA.Q_RES(CHIPS)':
 C_PATH='@t6g_mb_lib.t6g(sch_1):page136_i37@pure_quanta.q_res(chips)',
 P_PATH='@t6g_mb_lib.t6g(sch_1):page159_i37@pure_quanta.q_res(chips)',
 PATH='I37',
 DRAWING='@T6G_MB_LIB.T6G(SCH_1):PAGE136',
 WATTAGE='1/16W',
 TOLERANCE='5%',
 MATERIAL='CHIP',
 PHYS_PAGE='159',
 XY='(-3175,1500)',
 ROT='2',
 VER='1',
 PACK_TYPE='0402LF',
 LOCATION='R1295',
 CDS_LIB='pure_quanta',
 CDS_PART_NAME='Q_RES_0402LF-0,5%,1/16W,CHIP,CS00002JB13',
 PART_NUMBER='CS00002JB13',
 VALUE='0',
 PRIM_FILE='./archive_libs/logical/q_res/chips/chips.prt';

PART_NAME
 R1296 'Q_RES_0402LF-0,5%,1/16W,CHIP,CS00002JB13':;

SECTION_NUMBER 1
 '@T6G_MB_LIB.T6G(SCH_1):PAGE136_I38@PURE_QUANTA.Q_RES(CHIPS)':
 C_PATH='@t6g_mb_lib.t6g(sch_1):page136_i38@pure_quanta.q_res(chips)',
 P_PATH='@t6g_mb_lib.t6g(sch_1):page159_i38@pure_quanta.q_res(chips)',
 PATH='I38',
 DRAWING='@T6G_MB_LIB.T6G(SCH_1):PAGE136',
 WATTAGE='1/16W',
 TOLERANCE='5%',
 MATERIAL='CHIP',
 PHYS_PAGE='159',
 XY='(-3175,1450)',
 ROT='2',
 VER='1',
 PACK_TYPE='0402LF',
 LOCATION='R1296',
 CDS_LIB='pure_quanta',
 CDS_PART_NAME='Q_RES_0402LF-0,5%,1/16W,CHIP,CS00002JB13',
 PART_NUMBER='CS00002JB13',
 VALUE='0',
 PRIM_FILE='./archive_libs/logical/q_res/chips/chips.prt';

PART_NAME
 R1297 'Q_RES_0402LF-0,5%,1/16W,CHIP,CS00002JB13':;

SECTION_NUMBER 1
 '@T6G_MB_LIB.T6G(SCH_1):PAGE136_I31@PURE_QUANTA.Q_RES(CHIPS)':
 C_PATH='@t6g_mb_lib.t6g(sch_1):page136_i31@pure_quanta.q_res(chips)',
 P_PATH='@t6g_mb_lib.t6g(sch_1):page159_i31@pure_quanta.q_res(chips)',
 PATH='I31',
 DRAWING='@T6G_MB_LIB.T6G(SCH_1):PAGE136',
 WATTAGE='1/16W',
 TOLERANCE='5%',
 MATERIAL='CHIP',
 PHYS_PAGE='159',
 XY='(-3150,5875)',
 ROT='2',
 VER='1',
 PACK_TYPE='0402LF',
 LOCATION='R1297',
 CDS_LIB='pure_quanta',
 CDS_PART_NAME='Q_RES_0402LF-0,5%,1/16W,CHIP,CS00002JB13',
 PART_NUMBER='CS00002JB13',
 VALUE='0',
 PRIM_FILE='./archive_libs/logical/q_res/chips/chips.prt';

PART_NAME
 R1298 'Q_RES_0402LF-0,5%,1/16W,CHIP,CS00002JB13':;

SECTION_NUMBER 1
 '@T6G_MB_LIB.T6G(SCH_1):PAGE136_I32@PURE_QUANTA.Q_RES(CHIPS)':
 C_PATH='@t6g_mb_lib.t6g(sch_1):page136_i32@pure_quanta.q_res(chips)',
 P_PATH='@t6g_mb_lib.t6g(sch_1):page159_i32@pure_quanta.q_res(chips)',
 PATH='I32',
 DRAWING='@T6G_MB_LIB.T6G(SCH_1):PAGE136',
 WATTAGE='1/16W',
 TOLERANCE='5%',
 MATERIAL='CHIP',
 PHYS_PAGE='159',
 XY='(-3150,5825)',
 ROT='2',
 VER='1',
 PACK_TYPE='0402LF',
 LOCATION='R1298',
 CDS_LIB='pure_quanta',
 CDS_PART_NAME='Q_RES_0402LF-0,5%,1/16W,CHIP,CS00002JB13',
 PART_NUMBER='CS00002JB13',
 VALUE='0',
 PRIM_FILE='./archive_libs/logical/q_res/chips/chips.prt';

PART_NAME
 R1299 'Q_RES_0402LF-0,5%,1/16W,CHIP,CS00002JB13':;

SECTION_NUMBER 1
 '@T6G_MB_LIB.T6G(SCH_1):PAGE136_I33@PURE_QUANTA.Q_RES(CHIPS)':
 C_PATH='@t6g_mb_lib.t6g(sch_1):page136_i33@pure_quanta.q_res(chips)',
 P_PATH='@t6g_mb_lib.t6g(sch_1):page159_i33@pure_quanta.q_res(chips)',
 PATH='I33',
 DRAWING='@T6G_MB_LIB.T6G(SCH_1):PAGE136',
 WATTAGE='1/16W',
 TOLERANCE='5%',
 MATERIAL='CHIP',
 PHYS_PAGE='159',
 XY='(-3150,4475)',
 ROT='2',
 VER='1',
 PACK_TYPE='0402LF',
 LOCATION='R1299',
 CDS_LIB='pure_quanta',
 CDS_PART_NAME='Q_RES_0402LF-0,5%,1/16W,CHIP,CS00002JB13',
 PART_NUMBER='CS00002JB13',
 VALUE='0',
 PRIM_FILE='./archive_libs/logical/q_res/chips/chips.prt';

PART_NAME
 R1300 'Q_RES_0402LF-0,5%,1/16W,CHIP,CS00002JB13':;

SECTION_NUMBER 1
 '@T6G_MB_LIB.T6G(SCH_1):PAGE136_I34@PURE_QUANTA.Q_RES(CHIPS)':
 C_PATH='@t6g_mb_lib.t6g(sch_1):page136_i34@pure_quanta.q_res(chips)',
 P_PATH='@t6g_mb_lib.t6g(sch_1):page159_i34@pure_quanta.q_res(chips)',
 PATH='I34',
 DRAWING='@T6G_MB_LIB.T6G(SCH_1):PAGE136',
 WATTAGE='1/16W',
 TOLERANCE='5%',
 MATERIAL='CHIP',
 PHYS_PAGE='159',
 XY='(-3150,4425)',
 ROT='2',
 VER='1',
 PACK_TYPE='0402LF',
 LOCATION='R1300',
 CDS_LIB='pure_quanta',
 CDS_PART_NAME='Q_RES_0402LF-0,5%,1/16W,CHIP,CS00002JB13',
 PART_NUMBER='CS00002JB13',
 VALUE='0',
 PRIM_FILE='./archive_libs/logical/q_res/chips/chips.prt';

PART_NAME
 R1301 'Q_RES_0402LF-10,1%,1/16W,CHIP,CS01002FB07':;

SECTION_NUMBER 1
 '@T6G_MB_LIB.T6G(SCH_1):PAGE466_I11@PURE_QUANTA.Q_RES(CHIPS)':
 C_PATH='@t6g_mb_lib.t6g(sch_1):page466_i11@pure_quanta.q_res(chips)',
 P_PATH='@t6g_mb_lib.t6g(sch_1):page357_i11@pure_quanta.q_res(chips)',
 PATH='I11',
 DRAWING='@T6G_MB_LIB.T6G(SCH_1):PAGE466',
 WATTAGE='1/16W',
 TOLERANCE='1%',
 MATERIAL='CHIP',
 PHYS_PAGE='357',
 XY='(-5825,4600)',
 ROT='0',
 VER='1',
 PACK_TYPE='0402LF',
 LOCATION='R1301',
 CDS_LIB='pure_quanta',
 CDS_PART_NAME='Q_RES_0402LF-10,1%,1/16W,CHIP,CS01002FB07',
 PART_NUMBER='CS01002FB07',
 VALUE='10',
 PRIM_FILE='./archive_libs/logical/q_res/chips/chips.prt';

PART_NAME
 R1302 'Q_RES_0402LF-10,1%,1/16W,CHIP,CS01002FB07':;

SECTION_NUMBER 1
 '@T6G_MB_LIB.T6G(SCH_1):PAGE466_I55@PURE_QUANTA.Q_RES(CHIPS)':
 C_PATH='@t6g_mb_lib.t6g(sch_1):page466_i55@pure_quanta.q_res(chips)',
 P_PATH='@t6g_mb_lib.t6g(sch_1):page357_i55@pure_quanta.q_res(chips)',
 PATH='I55',
 DRAWING='@T6G_MB_LIB.T6G(SCH_1):PAGE466',
 WATTAGE='1/16W',
 TOLERANCE='1%',
 MATERIAL='CHIP',
 PHYS_PAGE='357',
 XY='(-5175,2550)',
 ROT='0',
 VER='1',
 PACK_TYPE='0402LF',
 LOCATION='R1302',
 CDS_LIB='pure_quanta',
 CDS_PART_NAME='Q_RES_0402LF-10,1%,1/16W,CHIP,CS01002FB07',
 PART_NUMBER='CS01002FB07',
 VALUE='10',
 PRIM_FILE='./archive_libs/logical/q_res/chips/chips.prt';

PART_NAME
 R1303 'Q_RES_0402LF-1K,1%,1/16W,CHIP,CS21002FB06':;

SECTION_NUMBER 1
 '@T6G_MB_LIB.T6G(SCH_1):PAGE84_I5@PURE_QUANTA.Q_RES(CHIPS)':
 C_PATH='@t6g_mb_lib.t6g(sch_1):page84_i5@pure_quanta.q_res(chips)',
 P_PATH='@t6g_mb_lib.t6g(sch_1):page85_i5@pure_quanta.q_res(chips)',
 PATH='I5',
 DRAWING='@T6G_MB_LIB.T6G(SCH_1):PAGE84',
 WATTAGE='1/16W',
 TOLERANCE='1%',
 MATERIAL='CHIP',
 PHYS_PAGE='85',
 XY='(-7625,1700)',
 ROT='0',
 VER='1',
 PACK_TYPE='0402LF',
 LOCATION='R1303',
 CDS_LIB='pure_quanta',
 CDS_PART_NAME='Q_RES_0402LF-1K,1%,1/16W,CHIP,CS21002FB06',
 PART_NUMBER='CS21002FB06',
 VALUE='1K',
 PRIM_FILE='./archive_libs/logical/q_res/chips/chips.prt';

PART_NAME
 R1304 'Q_RES_0402LF-10K,1%,1/16W,CHIP,CS31002FB08':;

SECTION_NUMBER 1
 '@T6G_MB_LIB.T6G(SCH_1):PAGE82_I171@PURE_QUANTA.Q_RES(CHIPS)':
 C_PATH='@t6g_mb_lib.t6g(sch_1):page82_i171@pure_quanta.q_res(chips)',
 P_PATH='@t6g_mb_lib.t6g(sch_1):page83_i171@pure_quanta.q_res(chips)',
 PATH='I171',
 DRAWING='@T6G_MB_LIB.T6G(SCH_1):PAGE82',
 WATTAGE='1/16W',
 TOLERANCE='1%',
 MATERIAL='CHIP',
 PHYS_PAGE='83',
 XY='(-7050,4575)',
 ROT='0',
 VER='1',
 PACK_TYPE='0402LF',
 LOCATION='R1304',
 CDS_LIB='pure_quanta',
 CDS_PART_NAME='Q_RES_0402LF-10K,1%,1/16W,CHIP,CS31002FB08',
 PART_NUMBER='CS31002FB08',
 VALUE='10K',
 PRIM_FILE='./archive_libs/logical/q_res/chips/chips.prt';

PART_NAME
 R1305 'Q_RES_0402LF-4.7K,1%,1/16W,EMPTY,CS24702FB06':;

SECTION_NUMBER 1
 '@T6G_MB_LIB.T6G(SCH_1):PAGE466_I72@PURE_QUANTA.Q_RES(CHIPS)':
 C_PATH='@t6g_mb_lib.t6g(sch_1):page466_i72@pure_quanta.q_res(chips)',
 P_PATH='@t6g_mb_lib.t6g(sch_1):page357_i72@pure_quanta.q_res(chips)',
 PATH='I72',
 DRAWING='@T6G_MB_LIB.T6G(SCH_1):PAGE466',
 WATTAGE='1/16W',
 TOLERANCE='1%',
 MATERIAL='EMPTY',
 PHYS_PAGE='357',
 XY='(-7200,1475)',
 ROT='0',
 VER='1',
 PACK_TYPE='0402LF',
 LOCATION='R1305',
 CDS_LIB='pure_quanta',
 CDS_PART_NAME='Q_RES_0402LF-4.7K,1%,1/16W,EMPTY,CS24702FB06',
 PART_NUMBER='CS24702FB06',
 VALUE='4.7K',
 PRIM_FILE='./archive_libs/logical/q_res/chips/chips.prt';

PART_NAME
 R1306 'Q_RES_0402LF-4.7K,1%,1/16W,EMPTY,CS24702FB06':;

SECTION_NUMBER 1
 '@T6G_MB_LIB.T6G(SCH_1):PAGE466_I12@PURE_QUANTA.Q_RES(CHIPS)':
 C_PATH='@t6g_mb_lib.t6g(sch_1):page466_i12@pure_quanta.q_res(chips)',
 P_PATH='@t6g_mb_lib.t6g(sch_1):page357_i12@pure_quanta.q_res(chips)',
 PATH='I12',
 DRAWING='@T6G_MB_LIB.T6G(SCH_1):PAGE466',
 WATTAGE='1/16W',
 TOLERANCE='1%',
 MATERIAL='EMPTY',
 PHYS_PAGE='357',
 XY='(-6650,5775)',
 ROT='0',
 VER='1',
 PACK_TYPE='0402LF',
 LOCATION='R1306',
 CDS_LIB='pure_quanta',
 CDS_PART_NAME='Q_RES_0402LF-4.7K,1%,1/16W,EMPTY,CS24702FB06',
 PART_NUMBER='CS24702FB06',
 VALUE='4.7K',
 PRIM_FILE='./archive_libs/logical/q_res/chips/chips.prt';

PART_NAME
 R1307 'Q_RES_0402LF-4.7K,1%,1/16W,EMPTY,CS24702FB06':;

SECTION_NUMBER 1
 '@T6G_MB_LIB.T6G(SCH_1):PAGE466_I44@PURE_QUANTA.Q_RES(CHIPS)':
 C_PATH='@t6g_mb_lib.t6g(sch_1):page466_i44@pure_quanta.q_res(chips)',
 P_PATH='@t6g_mb_lib.t6g(sch_1):page357_i44@pure_quanta.q_res(chips)',
 PATH='I44',
 DRAWING='@T6G_MB_LIB.T6G(SCH_1):PAGE466',
 WATTAGE='1/16W',
 TOLERANCE='1%',
 MATERIAL='EMPTY',
 PHYS_PAGE='357',
 XY='(-6000,3750)',
 ROT='0',
 VER='1',
 PACK_TYPE='0402LF',
 LOCATION='R1307',
 CDS_LIB='pure_quanta',
 CDS_PART_NAME='Q_RES_0402LF-4.7K,1%,1/16W,EMPTY,CS24702FB06',
 PART_NUMBER='CS24702FB06',
 VALUE='4.7K',
 PRIM_FILE='./archive_libs/logical/q_res/chips/chips.prt';

PART_NAME
 R1308 'Q_RES_0402LF-4.7K,1%,1/16W,CHIP,CS24702FB06':;

SECTION_NUMBER 1
 '@T6G_MB_LIB.T6G(SCH_1):PAGE466_I96@PURE_QUANTA.Q_RES(CHIPS)':
 C_PATH='@t6g_mb_lib.t6g(sch_1):page466_i96@pure_quanta.q_res(chips)',
 P_PATH='@t6g_mb_lib.t6g(sch_1):page357_i96@pure_quanta.q_res(chips)',
 PATH='I96',
 DRAWING='@T6G_MB_LIB.T6G(SCH_1):PAGE466',
 WATTAGE='1/16W',
 TOLERANCE='1%',
 MATERIAL='CHIP',
 PHYS_PAGE='357',
 XY='(-7200,1425)',
 ROT='0',
 VER='1',
 PACK_TYPE='0402LF',
 LOCATION='R1308',
 CDS_LIB='pure_quanta',
 CDS_PART_NAME='Q_RES_0402LF-4.7K,1%,1/16W,CHIP,CS24702FB06',
 PART_NUMBER='CS24702FB06',
 VALUE='4.7K',
 PRIM_FILE='./archive_libs/logical/q_res/chips/chips.prt';

PART_NAME
 R1309 'Q_RES_0402LF-4.7K,1%,1/16W,EMPTY,CS24702FB06':;

SECTION_NUMBER 1
 '@T6G_MB_LIB.T6G(SCH_1):PAGE466_I13@PURE_QUANTA.Q_RES(CHIPS)':
 C_PATH='@t6g_mb_lib.t6g(sch_1):page466_i13@pure_quanta.q_res(chips)',
 P_PATH='@t6g_mb_lib.t6g(sch_1):page357_i13@pure_quanta.q_res(chips)',
 PATH='I13',
 DRAWING='@T6G_MB_LIB.T6G(SCH_1):PAGE466',
 WATTAGE='1/16W',
 TOLERANCE='1%',
 MATERIAL='EMPTY',
 PHYS_PAGE='357',
 XY='(-6650,5725)',
 ROT='0',
 VER='1',
 PACK_TYPE='0402LF',
 LOCATION='R1309',
 CDS_LIB='pure_quanta',
 CDS_PART_NAME='Q_RES_0402LF-4.7K,1%,1/16W,EMPTY,CS24702FB06',
 PART_NUMBER='CS24702FB06',
 VALUE='4.7K',
 PRIM_FILE='./archive_libs/logical/q_res/chips/chips.prt';

PART_NAME
 R1310 'Q_RES_0402LF-4.7K,1%,1/16W,EMPTY,CS24702FB06':;

SECTION_NUMBER 1
 '@T6G_MB_LIB.T6G(SCH_1):PAGE466_I45@PURE_QUANTA.Q_RES(CHIPS)':
 C_PATH='@t6g_mb_lib.t6g(sch_1):page466_i45@pure_quanta.q_res(chips)',
 P_PATH='@t6g_mb_lib.t6g(sch_1):page357_i45@pure_quanta.q_res(chips)',
 PATH='I45',
 DRAWING='@T6G_MB_LIB.T6G(SCH_1):PAGE466',
 WATTAGE='1/16W',
 TOLERANCE='1%',
 MATERIAL='EMPTY',
 PHYS_PAGE='357',
 XY='(-6000,3675)',
 ROT='0',
 VER='1',
 PACK_TYPE='0402LF',
 LOCATION='R1310',
 CDS_LIB='pure_quanta',
 CDS_PART_NAME='Q_RES_0402LF-4.7K,1%,1/16W,EMPTY,CS24702FB06',
 PART_NUMBER='CS24702FB06',
 VALUE='4.7K',
 PRIM_FILE='./archive_libs/logical/q_res/chips/chips.prt';

PART_NAME
 R1311 'Q_RES_0402LF-33,5%,1/16W,CHIP,CS03302JB10':;

SECTION_NUMBER 1
 '@T6G_MB_LIB.T6G(SCH_1):PAGE132_I16@PURE_QUANTA.Q_RES(CHIPS)':
 C_PATH='@t6g_mb_lib.t6g(sch_1):page132_i16@pure_quanta.q_res(chips)',
 P_PATH='@t6g_mb_lib.t6g(sch_1):page155_i16@pure_quanta.q_res(chips)',
 PATH='I16',
 DRAWING='@T6G_MB_LIB.T6G(SCH_1):PAGE132',
 WATTAGE='1/16W',
 TOLERANCE='5%',
 MATERIAL='CHIP',
 PHYS_PAGE='155',
 XY='(-1525,4400)',
 ROT='0',
 VER='1',
 PACK_TYPE='0402LF',
 LOCATION='R1311',
 CDS_LIB='pure_quanta',
 CDS_PART_NAME='Q_RES_0402LF-33,5%,1/16W,CHIP,CS03302JB10',
 PART_NUMBER='CS03302JB10',
 VALUE='33',
 PRIM_FILE='./archive_libs/logical/q_res/chips/chips.prt';

PART_NAME
 R1312 'Q_RES_0402LF-0,5%,1/16W,CHIP,CS00002JB13':;

SECTION_NUMBER 1
 '@T6G_MB_LIB.T6G(SCH_1):PAGE251_I79@PURE_QUANTA.Q_RES(CHIPS)':
 C_PATH='@t6g_mb_lib.t6g(sch_1):page251_i79@pure_quanta.q_res(chips)',
 P_PATH='@t6g_mb_lib.t6g(sch_1):page252_i79@pure_quanta.q_res(chips)',
 PATH='I79',
 DRAWING='@T6G_MB_LIB.T6G(SCH_1):PAGE251',
 WATTAGE='1/16W',
 TOLERANCE='5%',
 MATERIAL='CHIP',
 PHYS_PAGE='252',
 XY='(-2950,4100)',
 ROT='0',
 VER='1',
 PACK_TYPE='0402LF',
 LOCATION='R1312',
 CDS_LIB='pure_quanta',
 CDS_PART_NAME='Q_RES_0402LF-0,5%,1/16W,CHIP,CS00002JB13',
 PART_NUMBER='CS00002JB13',
 VALUE='0',
 PRIM_FILE='./archive_libs/logical/q_res/chips/chips.prt';

PART_NAME
 R1313 'Q_RES_0402LF-4.7K,5%,1/16W,CHIP,CS24702JB10':;

SECTION_NUMBER 1
 '@T6G_MB_LIB.T6G(SCH_1):PAGE148_I383@PURE_QUANTA.Q_RES(CHIPS)':
 C_PATH='@t6g_mb_lib.t6g(sch_1):page148_i383@pure_quanta.q_res(chips)',
 P_PATH='@t6g_mb_lib.t6g(sch_1):page171_i383@pure_quanta.q_res(chips)',
 PATH='I383',
 DRAWING='@T6G_MB_LIB.T6G(SCH_1):PAGE148',
 WATTAGE='1/16W',
 TOLERANCE='5%',
 MATERIAL='CHIP',
 PHYS_PAGE='171',
 XY='(-4225,2900)',
 ROT='0',
 VER='2',
 PACK_TYPE='0402LF',
 LOCATION='R1313',
 CDS_LIB='pure_quanta',
 CDS_PART_NAME='Q_RES_0402LF-4.7K,5%,1/16W,CHIP,CS24702JB10',
 PART_NUMBER='CS24702JB10',
 VALUE='4.7K',
 PRIM_FILE='./archive_libs/logical/q_res/chips/chips.prt';

PART_NAME
 R1314 'Q_RES_0402LF-4.7K,5%,1/16W,EMPTY,CS24702JB10':;

SECTION_NUMBER 1
 '@T6G_MB_LIB.T6G(SCH_1):PAGE82_I54@PURE_QUANTA.Q_RES(CHIPS)':
 C_PATH='@t6g_mb_lib.t6g(sch_1):page82_i54@pure_quanta.q_res(chips)',
 P_PATH='@t6g_mb_lib.t6g(sch_1):page83_i54@pure_quanta.q_res(chips)',
 PATH='I54',
 DRAWING='@T6G_MB_LIB.T6G(SCH_1):PAGE82',
 WATTAGE='1/16W',
 TOLERANCE='5%',
 MATERIAL='EMPTY',
 PHYS_PAGE='83',
 XY='(-7050,4200)',
 ROT='0',
 VER='1',
 PACK_TYPE='0402LF',
 LOCATION='R1314',
 CDS_LIB='pure_quanta',
 CDS_PART_NAME='Q_RES_0402LF-4.7K,5%,1/16W,EMPTY,CS24702JB10',
 PART_NUMBER='CS24702JB10',
 VALUE='4.7K',
 PRIM_FILE='./archive_libs/logical/q_res/chips/chips.prt';

PART_NAME
 R1315 'Q_RES_0402LF-0,5%,1/16W,CHIP,CS00002JB13':;

SECTION_NUMBER 1
 '@T6G_MB_LIB.T6G(SCH_1):PAGE251_I80@PURE_QUANTA.Q_RES(CHIPS)':
 C_PATH='@t6g_mb_lib.t6g(sch_1):page251_i80@pure_quanta.q_res(chips)',
 P_PATH='@t6g_mb_lib.t6g(sch_1):page252_i80@pure_quanta.q_res(chips)',
 PATH='I80',
 DRAWING='@T6G_MB_LIB.T6G(SCH_1):PAGE251',
 WATTAGE='1/16W',
 TOLERANCE='5%',
 MATERIAL='CHIP',
 PHYS_PAGE='252',
 XY='(-2950,4050)',
 ROT='0',
 VER='1',
 PACK_TYPE='0402LF',
 LOCATION='R1315',
 CDS_LIB='pure_quanta',
 CDS_PART_NAME='Q_RES_0402LF-0,5%,1/16W,CHIP,CS00002JB13',
 PART_NUMBER='CS00002JB13',
 VALUE='0',
 PRIM_FILE='./archive_libs/logical/q_res/chips/chips.prt';

PART_NAME
 R1316 'Q_RES_0402LF-2.2K,5%,1/16W,CHIP,CS22202JB07':;

SECTION_NUMBER 1
 '@T6G_MB_LIB.T6G(SCH_1):PAGE251_I83@PURE_QUANTA.Q_RES(CHIPS)':
 C_PATH='@t6g_mb_lib.t6g(sch_1):page251_i83@pure_quanta.q_res(chips)',
 P_PATH='@t6g_mb_lib.t6g(sch_1):page252_i83@pure_quanta.q_res(chips)',
 PATH='I83',
 DRAWING='@T6G_MB_LIB.T6G(SCH_1):PAGE251',
 WATTAGE='1/16W',
 TOLERANCE='5%',
 MATERIAL='CHIP',
 PHYS_PAGE='252',
 XY='(-2525,800)',
 ROT='0',
 VER='1',
 PACK_TYPE='0402LF',
 LOCATION='R1316',
 CDS_LIB='pure_quanta',
 CDS_PART_NAME='Q_RES_0402LF-2.2K,5%,1/16W,CHIP,CS22202JB07',
 PART_NUMBER='CS22202JB07',
 VALUE='2.2K',
 PRIM_FILE='./archive_libs/logical/q_res/chips/chips.prt';

PART_NAME
 R1317 'Q_RES_0402LF-4.7K,1%,1/16W,EMPTY,CS24702FB06':;

SECTION_NUMBER 1
 '@T6G_MB_LIB.T6G(SCH_1):PAGE466_I95@PURE_QUANTA.Q_RES(CHIPS)':
 C_PATH='@t6g_mb_lib.t6g(sch_1):page466_i95@pure_quanta.q_res(chips)',
 P_PATH='@t6g_mb_lib.t6g(sch_1):page357_i95@pure_quanta.q_res(chips)',
 PATH='I95',
 DRAWING='@T6G_MB_LIB.T6G(SCH_1):PAGE466',
 WATTAGE='1/16W',
 TOLERANCE='1%',
 MATERIAL='EMPTY',
 PHYS_PAGE='357',
 XY='(-6100,1750)',
 ROT='0',
 VER='2',
 PACK_TYPE='0402LF',
 LOCATION='R1317',
 CDS_LIB='pure_quanta',
 CDS_PART_NAME='Q_RES_0402LF-4.7K,1%,1/16W,EMPTY,CS24702FB06',
 PART_NUMBER='CS24702FB06',
 VALUE='4.7K',
 PRIM_FILE='./archive_libs/logical/q_res/chips/chips.prt';

PART_NAME
 R1318 'Q_RES_0402LF-4.7K,5%,1/16W,CHIP,CS24702JB10':;

SECTION_NUMBER 1
 '@T6G_MB_LIB.T6G(SCH_1):PAGE148_I378@PURE_QUANTA.Q_RES(CHIPS)':
 C_PATH='@t6g_mb_lib.t6g(sch_1):page148_i378@pure_quanta.q_res(chips)',
 P_PATH='@t6g_mb_lib.t6g(sch_1):page171_i378@pure_quanta.q_res(chips)',
 PATH='I378',
 DRAWING='@T6G_MB_LIB.T6G(SCH_1):PAGE148',
 WATTAGE='1/16W',
 TOLERANCE='5%',
 MATERIAL='CHIP',
 PHYS_PAGE='171',
 XY='(-5400,1000)',
 ROT='0',
 VER='2',
 PACK_TYPE='0402LF',
 LOCATION='R1318',
 CDS_LIB='pure_quanta',
 CDS_PART_NAME='Q_RES_0402LF-4.7K,5%,1/16W,CHIP,CS24702JB10',
 PART_NUMBER='CS24702JB10',
 VALUE='4.7K',
 PRIM_FILE='./archive_libs/logical/q_res/chips/chips.prt';

PART_NAME
 R1319 'Q_RES_0402LF-2K,1%,1/16W,EMPTY,CS22002FB07':;

SECTION_NUMBER 1
 '@T6G_MB_LIB.T6G(SCH_1):PAGE349_I138@PURE_QUANTA.Q_RES(CHIPS)':
 C_PATH='@t6g_mb_lib.t6g(sch_1):page349_i138@pure_quanta.q_res(chips)',
 P_PATH='@t6g_mb_lib.t6g(sch_1):page151_i138@pure_quanta.q_res(chips)',
 PATH='I138',
 DRAWING='@T6G_MB_LIB.T6G(SCH_1):PAGE349',
 WATTAGE='1/16W',
 TOLERANCE='1%',
 MATERIAL='EMPTY',
 PHYS_PAGE='151',
 XY='(4275,5275)',
 ROT='0',
 VER='1',
 PACK_TYPE='0402LF',
 LOCATION='R1319',
 CDS_LIB='pure_quanta',
 CDS_PART_NAME='Q_RES_0402LF-2K,1%,1/16W,EMPTY,CS22002FB07',
 PART_NUMBER='CS22002FB07',
 VALUE='2K',
 PRIM_FILE='./archive_libs/logical/q_res/chips/chips.prt';

PART_NAME
 R1320 'Q_RES_0402LF-4.7K,1%,1/16W,CHIP,CS24702FB06':;

SECTION_NUMBER 1
 '@T6G_MB_LIB.T6G(SCH_1):PAGE466_I17@PURE_QUANTA.Q_RES(CHIPS)':
 C_PATH='@t6g_mb_lib.t6g(sch_1):page466_i17@pure_quanta.q_res(chips)',
 P_PATH='@t6g_mb_lib.t6g(sch_1):page357_i17@pure_quanta.q_res(chips)',
 PATH='I17',
 DRAWING='@T6G_MB_LIB.T6G(SCH_1):PAGE466',
 WATTAGE='1/16W',
 TOLERANCE='1%',
 MATERIAL='CHIP',
 PHYS_PAGE='357',
 XY='(-5550,6075)',
 ROT='0',
 VER='2',
 PACK_TYPE='0402LF',
 LOCATION='R1320',
 CDS_LIB='pure_quanta',
 CDS_PART_NAME='Q_RES_0402LF-4.7K,1%,1/16W,CHIP,CS24702FB06',
 PART_NUMBER='CS24702FB06',
 VALUE='4.7K',
 PRIM_FILE='./archive_libs/logical/q_res/chips/chips.prt';

PART_NAME
 R1321 'Q_RES_0402LF-33,5%,1/16W,CHIP,CS03302JB10':;

SECTION_NUMBER 1
 '@T6G_MB_LIB.T6G(SCH_1):PAGE349_I10@PURE_QUANTA.Q_RES(CHIPS)':
 C_PATH='@t6g_mb_lib.t6g(sch_1):page349_i10@pure_quanta.q_res(chips)',
 P_PATH='@t6g_mb_lib.t6g(sch_1):page151_i10@pure_quanta.q_res(chips)',
 PATH='I10',
 DRAWING='@T6G_MB_LIB.T6G(SCH_1):PAGE349',
 WATTAGE='1/16W',
 TOLERANCE='5%',
 MATERIAL='CHIP',
 PHYS_PAGE='151',
 XY='(-525,2100)',
 ROT='0',
 VER='1',
 PACK_TYPE='0402LF',
 LOCATION='R1321',
 CDS_LIB='pure_quanta',
 CDS_PART_NAME='Q_RES_0402LF-33,5%,1/16W,CHIP,CS03302JB10',
 PART_NUMBER='CS03302JB10',
 VALUE='33',
 PRIM_FILE='./archive_libs/logical/q_res/chips/chips.prt';

PART_NAME
 R1322 'Q_RES_0402LF-4.7K,1%,1/16W,CHIP,CS24702FB06':;

SECTION_NUMBER 1
 '@T6G_MB_LIB.T6G(SCH_1):PAGE466_I39@PURE_QUANTA.Q_RES(CHIPS)':
 C_PATH='@t6g_mb_lib.t6g(sch_1):page466_i39@pure_quanta.q_res(chips)',
 P_PATH='@t6g_mb_lib.t6g(sch_1):page357_i39@pure_quanta.q_res(chips)',
 PATH='I39',
 DRAWING='@T6G_MB_LIB.T6G(SCH_1):PAGE466',
 WATTAGE='1/16W',
 TOLERANCE='1%',
 MATERIAL='CHIP',
 PHYS_PAGE='357',
 XY='(-4900,4025)',
 ROT='0',
 VER='2',
 PACK_TYPE='0402LF',
 LOCATION='R1322',
 CDS_LIB='pure_quanta',
 CDS_PART_NAME='Q_RES_0402LF-4.7K,1%,1/16W,CHIP,CS24702FB06',
 PART_NUMBER='CS24702FB06',
 VALUE='4.7K',
 PRIM_FILE='./archive_libs/logical/q_res/chips/chips.prt';

PART_NAME
 R1323 'Q_RES_2512LF-0.002,1%,2W,CHIP,CS+002AFR06':;

SECTION_NUMBER 1
 '@T6G_MB_LIB.T6G(SCH_1):PAGE466_I84@PURE_QUANTA.Q_RES(CHIPS)':
 C_PATH='@t6g_mb_lib.t6g(sch_1):page466_i84@pure_quanta.q_res(chips)',
 P_PATH='@t6g_mb_lib.t6g(sch_1):page357_i84@pure_quanta.q_res(chips)',
 PATH='I84',
 DRAWING='@T6G_MB_LIB.T6G(SCH_1):PAGE466',
 WATTAGE='2W',
 TOLERANCE='1%',
 MATERIAL='CHIP',
 PHYS_PAGE='357',
 XY='(-8275,750)',
 ROT='0',
 VER='1',
 PACK_TYPE='2512LF',
 LOCATION='R1323',
 CDS_LIB='pure_quanta',
 CDS_PART_NAME='Q_RES_2512LF-0.002,1%,2W,CHIP,CS+002AFR06',
 PART_NUMBER='CS+002AFR06',
 VALUE='0.002',
 PRIM_FILE='./archive_libs/logical/q_res/chips/chips.prt';

PART_NAME
 R1324 'Q_RES_2512LF-0.002,1%,2W,CHIP,CS+002AFR06':;

SECTION_NUMBER 1
 '@T6G_MB_LIB.T6G(SCH_1):PAGE466_I2@PURE_QUANTA.Q_RES(CHIPS)':
 C_PATH='@t6g_mb_lib.t6g(sch_1):page466_i2@pure_quanta.q_res(chips)',
 P_PATH='@t6g_mb_lib.t6g(sch_1):page357_i2@pure_quanta.q_res(chips)',
 PATH='I2',
 DRAWING='@T6G_MB_LIB.T6G(SCH_1):PAGE466',
 WATTAGE='2W',
 TOLERANCE='1%',
 MATERIAL='CHIP',
 PHYS_PAGE='357',
 XY='(-7725,5075)',
 ROT='0',
 VER='1',
 PACK_TYPE='2512LF',
 LOCATION='R1324',
 CDS_LIB='pure_quanta',
 CDS_PART_NAME='Q_RES_2512LF-0.002,1%,2W,CHIP,CS+002AFR06',
 PART_NUMBER='CS+002AFR06',
 VALUE='0.002',
 PRIM_FILE='./archive_libs/logical/q_res/chips/chips.prt';

PART_NAME
 R1325 'Q_RES_2512LF-0.002,1%,2W,CHIP,CS+002AFR06':;

SECTION_NUMBER 1
 '@T6G_MB_LIB.T6G(SCH_1):PAGE466_I53@PURE_QUANTA.Q_RES(CHIPS)':
 C_PATH='@t6g_mb_lib.t6g(sch_1):page466_i53@pure_quanta.q_res(chips)',
 P_PATH='@t6g_mb_lib.t6g(sch_1):page357_i53@pure_quanta.q_res(chips)',
 PATH='I53',
 DRAWING='@T6G_MB_LIB.T6G(SCH_1):PAGE466',
 WATTAGE='2W',
 TOLERANCE='1%',
 MATERIAL='CHIP',
 PHYS_PAGE='357',
 XY='(-7075,3025)',
 ROT='0',
 VER='1',
 PACK_TYPE='2512LF',
 LOCATION='R1325',
 CDS_LIB='pure_quanta',
 CDS_PART_NAME='Q_RES_2512LF-0.002,1%,2W,CHIP,CS+002AFR06',
 PART_NUMBER='CS+002AFR06',
 VALUE='0.002',
 PRIM_FILE='./archive_libs/logical/q_res/chips/chips.prt';

PART_NAME
 R1326 'Q_RES_0402LF-1K,1%,1/16W,EMPTY,CS21002FB06':;

SECTION_NUMBER 1
 '@T6G_MB_LIB.T6G(SCH_1):PAGE466_I90@PURE_QUANTA.Q_RES(CHIPS)':
 C_PATH='@t6g_mb_lib.t6g(sch_1):page466_i90@pure_quanta.q_res(chips)',
 P_PATH='@t6g_mb_lib.t6g(sch_1):page357_i90@pure_quanta.q_res(chips)',
 PATH='I90',
 DRAWING='@T6G_MB_LIB.T6G(SCH_1):PAGE466',
 WATTAGE='1/16W',
 TOLERANCE='1%',
 MATERIAL='EMPTY',
 PHYS_PAGE='357',
 XY='(-2575,1800)',
 ROT='0',
 VER='2',
 PACK_TYPE='0402LF',
 LOCATION='R1326',
 CDS_LIB='pure_quanta',
 CDS_PART_NAME='Q_RES_0402LF-1K,1%,1/16W,EMPTY,CS21002FB06',
 PART_NUMBER='CS21002FB06',
 VALUE='1K',
 PRIM_FILE='./archive_libs/logical/q_res/chips/chips.prt';

PART_NAME
 R1327 'Q_RES_0402LF-1K,1%,1/16W,EMPTY,CS21002FB06':;

SECTION_NUMBER 1
 '@T6G_MB_LIB.T6G(SCH_1):PAGE466_I85@PURE_QUANTA.Q_RES(CHIPS)':
 C_PATH='@t6g_mb_lib.t6g(sch_1):page466_i85@pure_quanta.q_res(chips)',
 P_PATH='@t6g_mb_lib.t6g(sch_1):page357_i85@pure_quanta.q_res(chips)',
 PATH='I85',
 DRAWING='@T6G_MB_LIB.T6G(SCH_1):PAGE466',
 WATTAGE='1/16W',
 TOLERANCE='1%',
 MATERIAL='EMPTY',
 PHYS_PAGE='357',
 XY='(-2025,6150)',
 ROT='0',
 VER='2',
 PACK_TYPE='0402LF',
 LOCATION='R1327',
 CDS_LIB='pure_quanta',
 CDS_PART_NAME='Q_RES_0402LF-1K,1%,1/16W,EMPTY,CS21002FB06',
 PART_NUMBER='CS21002FB06',
 VALUE='1K',
 PRIM_FILE='./archive_libs/logical/q_res/chips/chips.prt';

PART_NAME
 R1328 'Q_RES_0402LF-1K,1%,1/16W,EMPTY,CS21002FB06':;

SECTION_NUMBER 1
 '@T6G_MB_LIB.T6G(SCH_1):PAGE466_I87@PURE_QUANTA.Q_RES(CHIPS)':
 C_PATH='@t6g_mb_lib.t6g(sch_1):page466_i87@pure_quanta.q_res(chips)',
 P_PATH='@t6g_mb_lib.t6g(sch_1):page357_i87@pure_quanta.q_res(chips)',
 PATH='I87',
 DRAWING='@T6G_MB_LIB.T6G(SCH_1):PAGE466',
 WATTAGE='1/16W',
 TOLERANCE='1%',
 MATERIAL='EMPTY',
 PHYS_PAGE='357',
 XY='(-1400,4100)',
 ROT='0',
 VER='2',
 PACK_TYPE='0402LF',
 LOCATION='R1328',
 CDS_LIB='pure_quanta',
 CDS_PART_NAME='Q_RES_0402LF-1K,1%,1/16W,EMPTY,CS21002FB06',
 PART_NUMBER='CS21002FB06',
 VALUE='1K',
 PRIM_FILE='./archive_libs/logical/q_res/chips/chips.prt';

PART_NAME
 R1329 'Q_RES_0402LF-0,5%,1/16W,CHIP,CS00002JB13':;

SECTION_NUMBER 1
 '@T6G_MB_LIB.T6G(SCH_1):PAGE81_I178@PURE_QUANTA.Q_RES(CHIPS)':
 C_PATH='@t6g_mb_lib.t6g(sch_1):page81_i178@pure_quanta.q_res(chips)',
 P_PATH='@t6g_mb_lib.t6g(sch_1):page82_i178@pure_quanta.q_res(chips)',
 PATH='I178',
 DRAWING='@T6G_MB_LIB.T6G(SCH_1):PAGE81',
 BOM_COST='MEM',
 WATTAGE='1/16W',
 TOLERANCE='5%',
 MATERIAL='CHIP',
 PHYS_PAGE='82',
 XY='(-6350,3875)',
 ROT='0',
 VER='1',
 PACK_TYPE='0402LF',
 LOCATION='R1329',
 CDS_LIB='pure_quanta',
 CDS_PART_NAME='Q_RES_0402LF-0,5%,1/16W,CHIP,CS00002JB13',
 PART_NUMBER='CS00002JB13',
 VALUE='0',
 PRIM_FILE='./archive_libs/logical/q_res/chips/chips.prt';

PART_NAME
 R1330 'Q_RES_0402LF-0,5%,1/16W,EMPTY,CS00002JB13':;

SECTION_NUMBER 1
 '@T6G_MB_LIB.T6G(SCH_1):PAGE136_I131@PURE_QUANTA.Q_RES(CHIPS)':
 C_PATH='@t6g_mb_lib.t6g(sch_1):page136_i131@pure_quanta.q_res(chips)',
 P_PATH='@t6g_mb_lib.t6g(sch_1):page159_i131@pure_quanta.q_res(chips)',
 PATH='I131',
 DRAWING='@T6G_MB_LIB.T6G(SCH_1):PAGE136',
 WATTAGE='1/16W',
 TOLERANCE='5%',
 MATERIAL='EMPTY',
 PHYS_PAGE='159',
 XY='(-3175,5325)',
 ROT='0',
 VER='1',
 PACK_TYPE='0402LF',
 LOCATION='R1330',
 CDS_LIB='pure_quanta',
 CDS_PART_NAME='Q_RES_0402LF-0,5%,1/16W,EMPTY,CS00002JB13',
 PART_NUMBER='CS00002JB13',
 VALUE='0',
 PRIM_FILE='./archive_libs/logical/q_res/chips/chips.prt';

PART_NAME
 R1331 'Q_RES_0402LF-0,5%,1/16W,EMPTY,CS00002JB13':;

SECTION_NUMBER 1
 '@T6G_MB_LIB.T6G(SCH_1):PAGE136_I132@PURE_QUANTA.Q_RES(CHIPS)':
 C_PATH='@t6g_mb_lib.t6g(sch_1):page136_i132@pure_quanta.q_res(chips)',
 P_PATH='@t6g_mb_lib.t6g(sch_1):page159_i132@pure_quanta.q_res(chips)',
 PATH='I132',
 DRAWING='@T6G_MB_LIB.T6G(SCH_1):PAGE136',
 WATTAGE='1/16W',
 TOLERANCE='5%',
 MATERIAL='EMPTY',
 PHYS_PAGE='159',
 XY='(-3175,5275)',
 ROT='0',
 VER='1',
 PACK_TYPE='0402LF',
 LOCATION='R1331',
 CDS_LIB='pure_quanta',
 CDS_PART_NAME='Q_RES_0402LF-0,5%,1/16W,EMPTY,CS00002JB13',
 PART_NUMBER='CS00002JB13',
 VALUE='0',
 PRIM_FILE='./archive_libs/logical/q_res/chips/chips.prt';

PART_NAME
 R1332 'Q_RES_0402LF-0,5%,1/16W,EMPTY,CS00002JB13':;

SECTION_NUMBER 1
 '@T6G_MB_LIB.T6G(SCH_1):PAGE136_I134@PURE_QUANTA.Q_RES(CHIPS)':
 C_PATH='@t6g_mb_lib.t6g(sch_1):page136_i134@pure_quanta.q_res(chips)',
 P_PATH='@t6g_mb_lib.t6g(sch_1):page159_i134@pure_quanta.q_res(chips)',
 PATH='I134',
 DRAWING='@T6G_MB_LIB.T6G(SCH_1):PAGE136',
 WATTAGE='1/16W',
 TOLERANCE='5%',
 MATERIAL='EMPTY',
 PHYS_PAGE='159',
 XY='(-3125,3925)',
 ROT='0',
 VER='1',
 PACK_TYPE='0402LF',
 LOCATION='R1332',
 CDS_LIB='pure_quanta',
 CDS_PART_NAME='Q_RES_0402LF-0,5%,1/16W,EMPTY,CS00002JB13',
 PART_NUMBER='CS00002JB13',
 VALUE='0',
 PRIM_FILE='./archive_libs/logical/q_res/chips/chips.prt';

PART_NAME
 R1333 'Q_RES_0402LF-0,5%,1/16W,EMPTY,CS00002JB13':;

SECTION_NUMBER 1
 '@T6G_MB_LIB.T6G(SCH_1):PAGE136_I133@PURE_QUANTA.Q_RES(CHIPS)':
 C_PATH='@t6g_mb_lib.t6g(sch_1):page136_i133@pure_quanta.q_res(chips)',
 P_PATH='@t6g_mb_lib.t6g(sch_1):page159_i133@pure_quanta.q_res(chips)',
 PATH='I133',
 DRAWING='@T6G_MB_LIB.T6G(SCH_1):PAGE136',
 WATTAGE='1/16W',
 TOLERANCE='5%',
 MATERIAL='EMPTY',
 PHYS_PAGE='159',
 XY='(-3125,3875)',
 ROT='0',
 VER='1',
 PACK_TYPE='0402LF',
 LOCATION='R1333',
 CDS_LIB='pure_quanta',
 CDS_PART_NAME='Q_RES_0402LF-0,5%,1/16W,EMPTY,CS00002JB13',
 PART_NUMBER='CS00002JB13',
 VALUE='0',
 PRIM_FILE='./archive_libs/logical/q_res/chips/chips.prt';

PART_NAME
 R1334 'Q_RES_0402LF-0,5%,1/16W,EMPTY,CS00002JB13':;

SECTION_NUMBER 1
 '@T6G_MB_LIB.T6G(SCH_1):PAGE136_I139@PURE_QUANTA.Q_RES(CHIPS)':
 C_PATH='@t6g_mb_lib.t6g(sch_1):page136_i139@pure_quanta.q_res(chips)',
 P_PATH='@t6g_mb_lib.t6g(sch_1):page159_i139@pure_quanta.q_res(chips)',
 PATH='I139',
 DRAWING='@T6G_MB_LIB.T6G(SCH_1):PAGE136',
 WATTAGE='1/16W',
 TOLERANCE='5%',
 MATERIAL='EMPTY',
 PHYS_PAGE='159',
 XY='(-3075,2400)',
 ROT='0',
 VER='1',
 PACK_TYPE='0402LF',
 LOCATION='R1334',
 CDS_LIB='pure_quanta',
 CDS_PART_NAME='Q_RES_0402LF-0,5%,1/16W,EMPTY,CS00002JB13',
 PART_NUMBER='CS00002JB13',
 VALUE='0',
 PRIM_FILE='./archive_libs/logical/q_res/chips/chips.prt';

PART_NAME
 R1335 'Q_RES_0402LF-0,5%,1/16W,EMPTY,CS00002JB13':;

SECTION_NUMBER 1
 '@T6G_MB_LIB.T6G(SCH_1):PAGE136_I140@PURE_QUANTA.Q_RES(CHIPS)':
 C_PATH='@t6g_mb_lib.t6g(sch_1):page136_i140@pure_quanta.q_res(chips)',
 P_PATH='@t6g_mb_lib.t6g(sch_1):page159_i140@pure_quanta.q_res(chips)',
 PATH='I140',
 DRAWING='@T6G_MB_LIB.T6G(SCH_1):PAGE136',
 WATTAGE='1/16W',
 TOLERANCE='5%',
 MATERIAL='EMPTY',
 PHYS_PAGE='159',
 XY='(-3075,2350)',
 ROT='0',
 VER='1',
 PACK_TYPE='0402LF',
 LOCATION='R1335',
 CDS_LIB='pure_quanta',
 CDS_PART_NAME='Q_RES_0402LF-0,5%,1/16W,EMPTY,CS00002JB13',
 PART_NUMBER='CS00002JB13',
 VALUE='0',
 PRIM_FILE='./archive_libs/logical/q_res/chips/chips.prt';

PART_NAME
 R1336 'Q_RES_0402LF-0,5%,1/16W,EMPTY,CS00002JB13':;

SECTION_NUMBER 1
 '@T6G_MB_LIB.T6G(SCH_1):PAGE136_I143@PURE_QUANTA.Q_RES(CHIPS)':
 C_PATH='@t6g_mb_lib.t6g(sch_1):page136_i143@pure_quanta.q_res(chips)',
 P_PATH='@t6g_mb_lib.t6g(sch_1):page159_i143@pure_quanta.q_res(chips)',
 PATH='I143',
 DRAWING='@T6G_MB_LIB.T6G(SCH_1):PAGE136',
 WATTAGE='1/16W',
 TOLERANCE='5%',
 MATERIAL='EMPTY',
 PHYS_PAGE='159',
 XY='(-3025,950)',
 ROT='0',
 VER='1',
 PACK_TYPE='0402LF',
 LOCATION='R1336',
 CDS_LIB='pure_quanta',
 CDS_PART_NAME='Q_RES_0402LF-0,5%,1/16W,EMPTY,CS00002JB13',
 PART_NUMBER='CS00002JB13',
 VALUE='0',
 PRIM_FILE='./archive_libs/logical/q_res/chips/chips.prt';

PART_NAME
 R1337 'Q_RES_0402LF-0,5%,1/16W,EMPTY,CS00002JB13':;

SECTION_NUMBER 1
 '@T6G_MB_LIB.T6G(SCH_1):PAGE136_I144@PURE_QUANTA.Q_RES(CHIPS)':
 C_PATH='@t6g_mb_lib.t6g(sch_1):page136_i144@pure_quanta.q_res(chips)',
 P_PATH='@t6g_mb_lib.t6g(sch_1):page159_i144@pure_quanta.q_res(chips)',
 PATH='I144',
 DRAWING='@T6G_MB_LIB.T6G(SCH_1):PAGE136',
 WATTAGE='1/16W',
 TOLERANCE='5%',
 MATERIAL='EMPTY',
 PHYS_PAGE='159',
 XY='(-3025,900)',
 ROT='0',
 VER='1',
 PACK_TYPE='0402LF',
 LOCATION='R1337',
 CDS_LIB='pure_quanta',
 CDS_PART_NAME='Q_RES_0402LF-0,5%,1/16W,EMPTY,CS00002JB13',
 PART_NUMBER='CS00002JB13',
 VALUE='0',
 PRIM_FILE='./archive_libs/logical/q_res/chips/chips.prt';

PART_NAME
 R1338 'Q_RES_0402LF-4.7K,5%,1/16W,CHIP,CS24702JB10':;

SECTION_NUMBER 1
 '@T6G_MB_LIB.T6G(SCH_1):PAGE83_I29@PURE_QUANTA.Q_RES(CHIPS)':
 C_PATH='@t6g_mb_lib.t6g(sch_1):page83_i29@pure_quanta.q_res(chips)',
 P_PATH='@t6g_mb_lib.t6g(sch_1):page84_i29@pure_quanta.q_res(chips)',
 PATH='I29',
 DRAWING='@T6G_MB_LIB.T6G(SCH_1):PAGE83',
 BOM_COST='OCP3.0 ',
 WATTAGE='1/16W',
 TOLERANCE='5%',
 MATERIAL='CHIP',
 PHYS_PAGE='84',
 XY='(-925,5775)',
 ROT='0',
 VER='2',
 PACK_TYPE='0402LF',
 LOCATION='R1338',
 CDS_LIB='pure_quanta',
 CDS_PART_NAME='Q_RES_0402LF-4.7K,5%,1/16W,CHIP,CS24702JB10',
 PART_NUMBER='CS24702JB10',
 VALUE='4.7K',
 PRIM_FILE='./archive_libs/logical/q_res/chips/chips.prt';

PART_NAME
 R1339 'Q_RES_0402LF-0,5%,1/16W,CHIP,CS00002JB13':;

SECTION_NUMBER 1
 '@T6G_MB_LIB.T6G(SCH_1):PAGE81_I180@PURE_QUANTA.Q_RES(CHIPS)':
 C_PATH='@t6g_mb_lib.t6g(sch_1):page81_i180@pure_quanta.q_res(chips)',
 P_PATH='@t6g_mb_lib.t6g(sch_1):page82_i180@pure_quanta.q_res(chips)',
 PATH='I180',
 DRAWING='@T6G_MB_LIB.T6G(SCH_1):PAGE81',
 BOM_COST='MEM',
 WATTAGE='1/16W',
 TOLERANCE='5%',
 MATERIAL='CHIP',
 PHYS_PAGE='82',
 XY='(-3275,3775)',
 ROT='2',
 VER='1',
 PACK_TYPE='0402LF',
 LOCATION='R1339',
 CDS_LIB='pure_quanta',
 CDS_PART_NAME='Q_RES_0402LF-0,5%,1/16W,CHIP,CS00002JB13',
 PART_NUMBER='CS00002JB13',
 VALUE='0',
 PRIM_FILE='./archive_libs/logical/q_res/chips/chips.prt';

PART_NAME
 R1340 'Q_RES_0402LF-0,5%,1/16W,CHIP,CS00002JB13':;

SECTION_NUMBER 1
 '@T6G_MB_LIB.T6G(SCH_1):PAGE81_I176@PURE_QUANTA.Q_RES(CHIPS)':
 C_PATH='@t6g_mb_lib.t6g(sch_1):page81_i176@pure_quanta.q_res(chips)',
 P_PATH='@t6g_mb_lib.t6g(sch_1):page82_i176@pure_quanta.q_res(chips)',
 PATH='I176',
 DRAWING='@T6G_MB_LIB.T6G(SCH_1):PAGE81',
 BOM_COST='MEM',
 WATTAGE='1/16W',
 TOLERANCE='5%',
 MATERIAL='CHIP',
 PHYS_PAGE='82',
 XY='(-3225,4775)',
 ROT='0',
 VER='1',
 PACK_TYPE='0402LF',
 LOCATION='R1340',
 CDS_LIB='pure_quanta',
 CDS_PART_NAME='Q_RES_0402LF-0,5%,1/16W,CHIP,CS00002JB13',
 PART_NUMBER='CS00002JB13',
 VALUE='0',
 PRIM_FILE='./archive_libs/logical/q_res/chips/chips.prt';

PART_NAME
 R1341 'Q_RES_0402LF-2.2K,5%,1/16W,CHIP,CS22202JB07':;

SECTION_NUMBER 1
 '@T6G_MB_LIB.T6G(SCH_1):PAGE251_I84@PURE_QUANTA.Q_RES(CHIPS)':
 C_PATH='@t6g_mb_lib.t6g(sch_1):page251_i84@pure_quanta.q_res(chips)',
 P_PATH='@t6g_mb_lib.t6g(sch_1):page252_i84@pure_quanta.q_res(chips)',
 PATH='I84',
 DRAWING='@T6G_MB_LIB.T6G(SCH_1):PAGE251',
 WATTAGE='1/16W',
 TOLERANCE='5%',
 MATERIAL='CHIP',
 PHYS_PAGE='252',
 XY='(-2525,750)',
 ROT='0',
 VER='1',
 PACK_TYPE='0402LF',
 LOCATION='R1341',
 CDS_LIB='pure_quanta',
 CDS_PART_NAME='Q_RES_0402LF-2.2K,5%,1/16W,CHIP,CS22202JB07',
 PART_NUMBER='CS22202JB07',
 VALUE='2.2K',
 PRIM_FILE='./archive_libs/logical/q_res/chips/chips.prt';

PART_NAME
 R1342 'Q_RES_0402LF-10K,1%,1/16W,CHIP,CS31002FB08':;

SECTION_NUMBER 1
 '@T6G_MB_LIB.T6G(SCH_1):PAGE148_I369@PURE_QUANTA.Q_RES(CHIPS)':
 C_PATH='@t6g_mb_lib.t6g(sch_1):page148_i369@pure_quanta.q_res(chips)',
 P_PATH='@t6g_mb_lib.t6g(sch_1):page171_i369@pure_quanta.q_res(chips)',
 PATH='I369',
 DRAWING='@T6G_MB_LIB.T6G(SCH_1):PAGE148',
 WATTAGE='1/16W',
 TOLERANCE='1%',
 MATERIAL='CHIP',
 PHYS_PAGE='171',
 XY='(-8025,5025)',
 ROT='0',
 VER='2',
 PACK_TYPE='0402LF',
 LOCATION='R1342',
 CDS_LIB='pure_quanta',
 CDS_PART_NAME='Q_RES_0402LF-10K,1%,1/16W,CHIP,CS31002FB08',
 PART_NUMBER='CS31002FB08',
 VALUE='10K',
 PRIM_FILE='./archive_libs/logical/q_res/chips/chips.prt';

PART_NAME
 R1343 'Q_RES_0402LF-4.7K,5%,1/16W,EMPTY,CS24702JB10':;

SECTION_NUMBER 1
 '@T6G_MB_LIB.T6G(SCH_1):PAGE148_I339@PURE_QUANTA.Q_RES(CHIPS)':
 C_PATH='@t6g_mb_lib.t6g(sch_1):page148_i339@pure_quanta.q_res(chips)',
 P_PATH='@t6g_mb_lib.t6g(sch_1):page171_i339@pure_quanta.q_res(chips)',
 PATH='I339',
 DRAWING='@T6G_MB_LIB.T6G(SCH_1):PAGE148',
 BOM_COST='OCP3.0 ',
 WATTAGE='1/16W',
 TOLERANCE='5%',
 MATERIAL='EMPTY',
 PHYS_PAGE='171',
 XY='(-6575,5500)',
 ROT='0',
 VER='2',
 PACK_TYPE='0402LF',
 LOCATION='R1343',
 CDS_LIB='pure_quanta',
 CDS_PART_NAME='Q_RES_0402LF-4.7K,5%,1/16W,EMPTY,CS24702JB10',
 PART_NUMBER='CS24702JB10',
 VALUE='4.7K',
 PRIM_FILE='./archive_libs/logical/q_res/chips/chips.prt';

PART_NAME
 R1344 'Q_RES_0402LF-33.2,1%,1/16W,CHIP,CS03322FB03':;

SECTION_NUMBER 1
 '@T6G_MB_LIB.T6G(SCH_1):PAGE253_I23@PURE_QUANTA.Q_RES(CHIPS)':
 C_PATH='@t6g_mb_lib.t6g(sch_1):page253_i23@pure_quanta.q_res(chips)',
 P_PATH='@t6g_mb_lib.t6g(sch_1):page251_i23@pure_quanta.q_res(chips)',
 PATH='I23',
 DRAWING='@T6G_MB_LIB.T6G(SCH_1):PAGE253',
 WATTAGE='1/16W',
 TOLERANCE='1%',
 MATERIAL='CHIP',
 PHYS_PAGE='251',
 XY='(-4950,2525)',
 ROT='0',
 VER='1',
 PACK_TYPE='0402LF',
 LOCATION='R1344',
 CDS_LIB='pure_quanta',
 CDS_PART_NAME='Q_RES_0402LF-33.2,1%,1/16W,CHIP,CS03322FB03',
 PART_NUMBER='CS03322FB03',
 VALUE='33.2',
 PRIM_FILE='./archive_libs/logical/q_res/chips/chips.prt';

PART_NAME
 R1345 'Q_RES_0402LF-33.2,1%,1/16W,CHIP,CS03322FB03':;

SECTION_NUMBER 1
 '@T6G_MB_LIB.T6G(SCH_1):PAGE253_I24@PURE_QUANTA.Q_RES(CHIPS)':
 C_PATH='@t6g_mb_lib.t6g(sch_1):page253_i24@pure_quanta.q_res(chips)',
 P_PATH='@t6g_mb_lib.t6g(sch_1):page251_i24@pure_quanta.q_res(chips)',
 PATH='I24',
 DRAWING='@T6G_MB_LIB.T6G(SCH_1):PAGE253',
 WATTAGE='1/16W',
 TOLERANCE='1%',
 MATERIAL='CHIP',
 PHYS_PAGE='251',
 XY='(-4950,2475)',
 ROT='0',
 VER='1',
 PACK_TYPE='0402LF',
 LOCATION='R1345',
 CDS_LIB='pure_quanta',
 CDS_PART_NAME='Q_RES_0402LF-33.2,1%,1/16W,CHIP,CS03322FB03',
 PART_NUMBER='CS03322FB03',
 VALUE='33.2',
 PRIM_FILE='./archive_libs/logical/q_res/chips/chips.prt';

PART_NAME
 R1346 'Q_RES_0402LF-33.2,1%,1/16W,CHIP,CS03322FB03':;

SECTION_NUMBER 1
 '@T6G_MB_LIB.T6G(SCH_1):PAGE253_I25@PURE_QUANTA.Q_RES(CHIPS)':
 C_PATH='@t6g_mb_lib.t6g(sch_1):page253_i25@pure_quanta.q_res(chips)',
 P_PATH='@t6g_mb_lib.t6g(sch_1):page251_i25@pure_quanta.q_res(chips)',
 PATH='I25',
 DRAWING='@T6G_MB_LIB.T6G(SCH_1):PAGE253',
 WATTAGE='1/16W',
 TOLERANCE='1%',
 MATERIAL='CHIP',
 PHYS_PAGE='251',
 XY='(-4950,2225)',
 ROT='0',
 VER='1',
 PACK_TYPE='0402LF',
 LOCATION='R1346',
 CDS_LIB='pure_quanta',
 CDS_PART_NAME='Q_RES_0402LF-33.2,1%,1/16W,CHIP,CS03322FB03',
 PART_NUMBER='CS03322FB03',
 VALUE='33.2',
 PRIM_FILE='./archive_libs/logical/q_res/chips/chips.prt';

PART_NAME
 R1347 'Q_RES_0402LF-33.2,1%,1/16W,CHIP,CS03322FB03':;

SECTION_NUMBER 1
 '@T6G_MB_LIB.T6G(SCH_1):PAGE253_I26@PURE_QUANTA.Q_RES(CHIPS)':
 C_PATH='@t6g_mb_lib.t6g(sch_1):page253_i26@pure_quanta.q_res(chips)',
 P_PATH='@t6g_mb_lib.t6g(sch_1):page251_i26@pure_quanta.q_res(chips)',
 PATH='I26',
 DRAWING='@T6G_MB_LIB.T6G(SCH_1):PAGE253',
 WATTAGE='1/16W',
 TOLERANCE='1%',
 MATERIAL='CHIP',
 PHYS_PAGE='251',
 XY='(-4950,2175)',
 ROT='0',
 VER='1',
 PACK_TYPE='0402LF',
 LOCATION='R1347',
 CDS_LIB='pure_quanta',
 CDS_PART_NAME='Q_RES_0402LF-33.2,1%,1/16W,CHIP,CS03322FB03',
 PART_NUMBER='CS03322FB03',
 VALUE='33.2',
 PRIM_FILE='./archive_libs/logical/q_res/chips/chips.prt';

PART_NAME
 R1348 'Q_RES_0402LF-33.2,1%,1/16W,CHIP,CS03322FB03':;

SECTION_NUMBER 1
 '@T6G_MB_LIB.T6G(SCH_1):PAGE253_I27@PURE_QUANTA.Q_RES(CHIPS)':
 C_PATH='@t6g_mb_lib.t6g(sch_1):page253_i27@pure_quanta.q_res(chips)',
 P_PATH='@t6g_mb_lib.t6g(sch_1):page251_i27@pure_quanta.q_res(chips)',
 PATH='I27',
 DRAWING='@T6G_MB_LIB.T6G(SCH_1):PAGE253',
 WATTAGE='1/16W',
 TOLERANCE='1%',
 MATERIAL='CHIP',
 PHYS_PAGE='251',
 XY='(-4950,1875)',
 ROT='0',
 VER='1',
 PACK_TYPE='0402LF',
 LOCATION='R1348',
 CDS_LIB='pure_quanta',
 CDS_PART_NAME='Q_RES_0402LF-33.2,1%,1/16W,CHIP,CS03322FB03',
 PART_NUMBER='CS03322FB03',
 VALUE='33.2',
 PRIM_FILE='./archive_libs/logical/q_res/chips/chips.prt';

PART_NAME
 R1349 'Q_RES_0402LF-33.2,1%,1/16W,CHIP,CS03322FB03':;

SECTION_NUMBER 1
 '@T6G_MB_LIB.T6G(SCH_1):PAGE253_I28@PURE_QUANTA.Q_RES(CHIPS)':
 C_PATH='@t6g_mb_lib.t6g(sch_1):page253_i28@pure_quanta.q_res(chips)',
 P_PATH='@t6g_mb_lib.t6g(sch_1):page251_i28@pure_quanta.q_res(chips)',
 PATH='I28',
 DRAWING='@T6G_MB_LIB.T6G(SCH_1):PAGE253',
 WATTAGE='1/16W',
 TOLERANCE='1%',
 MATERIAL='CHIP',
 PHYS_PAGE='251',
 XY='(-4950,1825)',
 ROT='0',
 VER='1',
 PACK_TYPE='0402LF',
 LOCATION='R1349',
 CDS_LIB='pure_quanta',
 CDS_PART_NAME='Q_RES_0402LF-33.2,1%,1/16W,CHIP,CS03322FB03',
 PART_NUMBER='CS03322FB03',
 VALUE='33.2',
 PRIM_FILE='./archive_libs/logical/q_res/chips/chips.prt';

PART_NAME
 R1350 'Q_RES_0402LF-0,5%,1/16W,CHIP,CS00002JB13':;

SECTION_NUMBER 1
 '@T6G_MB_LIB.T6G(SCH_1):PAGE466_I94@PURE_QUANTA.Q_RES(CHIPS)':
 C_PATH='@t6g_mb_lib.t6g(sch_1):page466_i94@pure_quanta.q_res(chips)',
 P_PATH='@t6g_mb_lib.t6g(sch_1):page357_i94@pure_quanta.q_res(chips)',
 PATH='I94',
 DRAWING='@T6G_MB_LIB.T6G(SCH_1):PAGE466',
 WATTAGE='1/16W',
 TOLERANCE='5%',
 MATERIAL='CHIP',
 PHYS_PAGE='357',
 XY='(-6025,1300)',
 ROT='0',
 VER='2',
 PACK_TYPE='0402LF',
 LOCATION='R1350',
 CDS_LIB='pure_quanta',
 CDS_PART_NAME='Q_RES_0402LF-0,5%,1/16W,CHIP,CS00002JB13',
 PART_NUMBER='CS00002JB13',
 VALUE='0',
 PRIM_FILE='./archive_libs/logical/q_res/chips/chips.prt';

PART_NAME
 R1351 'Q_RES_0402LF-2.2K,5%,1/16W,CHIP,CS22202JB07':;

SECTION_NUMBER 1
 '@T6G_MB_LIB.T6G(SCH_1):PAGE82_I72@PURE_QUANTA.Q_RES(CHIPS)':
 C_PATH='@t6g_mb_lib.t6g(sch_1):page82_i72@pure_quanta.q_res(chips)',
 P_PATH='@t6g_mb_lib.t6g(sch_1):page83_i72@pure_quanta.q_res(chips)',
 PATH='I72',
 DRAWING='@T6G_MB_LIB.T6G(SCH_1):PAGE82',
 WATTAGE='1/16W',
 TOLERANCE='5%',
 MATERIAL='CHIP',
 PHYS_PAGE='83',
 XY='(-4925,5275)',
 ROT='0',
 VER='1',
 PACK_TYPE='0402LF',
 LOCATION='R1351',
 CDS_LIB='pure_quanta',
 CDS_PART_NAME='Q_RES_0402LF-2.2K,5%,1/16W,CHIP,CS22202JB07',
 PART_NUMBER='CS22202JB07',
 VALUE='2.2K',
 PRIM_FILE='./archive_libs/logical/q_res/chips/chips.prt';

PART_NAME
 R1352 'Q_RES_0402LF-0,5%,1/16W,CHIP,CS00002JB13':;

SECTION_NUMBER 1
 '@T6G_MB_LIB.T6G(SCH_1):PAGE149_I132@PURE_QUANTA.Q_RES(CHIPS)':
 C_PATH='@t6g_mb_lib.t6g(sch_1):page149_i132@pure_quanta.q_res(chips)',
 P_PATH='@t6g_mb_lib.t6g(sch_1):page172_i132@pure_quanta.q_res(chips)',
 PATH='I132',
 DRAWING='@T6G_MB_LIB.T6G(SCH_1):PAGE149',
 WATTAGE='1/16W',
 TOLERANCE='5%',
 MATERIAL='CHIP',
 PHYS_PAGE='172',
 XY='(-3975,5950)',
 ROT='0',
 VER='1',
 PACK_TYPE='0402LF',
 LOCATION='R1352',
 CDS_LIB='pure_quanta',
 CDS_PART_NAME='Q_RES_0402LF-0,5%,1/16W,CHIP,CS00002JB13',
 PART_NUMBER='CS00002JB13',
 VALUE='0',
 PRIM_FILE='./archive_libs/logical/q_res/chips/chips.prt';

PART_NAME
 R1353 'Q_RES_0402LF-0,5%,1/16W,CHIP,CS00002JB13':;

SECTION_NUMBER 1
 '@T6G_MB_LIB.T6G(SCH_1):PAGE149_I133@PURE_QUANTA.Q_RES(CHIPS)':
 C_PATH='@t6g_mb_lib.t6g(sch_1):page149_i133@pure_quanta.q_res(chips)',
 P_PATH='@t6g_mb_lib.t6g(sch_1):page172_i133@pure_quanta.q_res(chips)',
 PATH='I133',
 DRAWING='@T6G_MB_LIB.T6G(SCH_1):PAGE149',
 WATTAGE='1/16W',
 TOLERANCE='5%',
 MATERIAL='CHIP',
 PHYS_PAGE='172',
 XY='(-3975,5900)',
 ROT='0',
 VER='1',
 PACK_TYPE='0402LF',
 LOCATION='R1353',
 CDS_LIB='pure_quanta',
 CDS_PART_NAME='Q_RES_0402LF-0,5%,1/16W,CHIP,CS00002JB13',
 PART_NUMBER='CS00002JB13',
 VALUE='0',
 PRIM_FILE='./archive_libs/logical/q_res/chips/chips.prt';

PART_NAME
 R1354 'Q_RES_0402LF-0,5%,1/16W,CHIP,CS00002JB13':;

SECTION_NUMBER 1
 '@T6G_MB_LIB.T6G(SCH_1):PAGE149_I109@PURE_QUANTA.Q_RES(CHIPS)':
 C_PATH='@t6g_mb_lib.t6g(sch_1):page149_i109@pure_quanta.q_res(chips)',
 P_PATH='@t6g_mb_lib.t6g(sch_1):page172_i109@pure_quanta.q_res(chips)',
 PATH='I109',
 DRAWING='@T6G_MB_LIB.T6G(SCH_1):PAGE149',
 WATTAGE='1/16W',
 TOLERANCE='5%',
 MATERIAL='CHIP',
 PHYS_PAGE='172',
 XY='(-3975,5850)',
 ROT='0',
 VER='1',
 PACK_TYPE='0402LF',
 LOCATION='R1354',
 CDS_LIB='pure_quanta',
 CDS_PART_NAME='Q_RES_0402LF-0,5%,1/16W,CHIP,CS00002JB13',
 PART_NUMBER='CS00002JB13',
 VALUE='0',
 PRIM_FILE='./archive_libs/logical/q_res/chips/chips.prt';

PART_NAME
 R1355 'Q_RES_0402LF-0,5%,1/16W,CHIP,CS00002JB13':;

SECTION_NUMBER 1
 '@T6G_MB_LIB.T6G(SCH_1):PAGE466_I92@PURE_QUANTA.Q_RES(CHIPS)':
 C_PATH='@t6g_mb_lib.t6g(sch_1):page466_i92@pure_quanta.q_res(chips)',
 P_PATH='@t6g_mb_lib.t6g(sch_1):page357_i92@pure_quanta.q_res(chips)',
 PATH='I92',
 DRAWING='@T6G_MB_LIB.T6G(SCH_1):PAGE466',
 WATTAGE='1/16W',
 TOLERANCE='5%',
 MATERIAL='CHIP',
 PHYS_PAGE='357',
 XY='(-5475,5600)',
 ROT='0',
 VER='2',
 PACK_TYPE='0402LF',
 LOCATION='R1355',
 CDS_LIB='pure_quanta',
 CDS_PART_NAME='Q_RES_0402LF-0,5%,1/16W,CHIP,CS00002JB13',
 PART_NUMBER='CS00002JB13',
 VALUE='0',
 PRIM_FILE='./archive_libs/logical/q_res/chips/chips.prt';

PART_NAME
 R1356 'Q_RES_0402LF-4.7K,5%,1/16W,CHIP,CS24702JB10':;

SECTION_NUMBER 1
 '@T6G_MB_LIB.T6G(SCH_1):PAGE144_I77@PURE_QUANTA.Q_RES(CHIPS)':
 C_PATH='@t6g_mb_lib.t6g(sch_1):page144_i77@pure_quanta.q_res(chips)',
 P_PATH='@t6g_mb_lib.t6g(sch_1):page167_i77@pure_quanta.q_res(chips)',
 PATH='I77',
 DRAWING='@T6G_MB_LIB.T6G(SCH_1):PAGE144',
 WATTAGE='1/16W',
 TOLERANCE='5%',
 MATERIAL='CHIP',
 PHYS_PAGE='167',
 XY='(-1775,5750)',
 ROT='0',
 VER='2',
 PACK_TYPE='0402LF',
 LOCATION='R1356',
 CDS_LIB='pure_quanta',
 CDS_PART_NAME='Q_RES_0402LF-4.7K,5%,1/16W,CHIP,CS24702JB10',
 PART_NUMBER='CS24702JB10',
 VALUE='4.7K',
 PRIM_FILE='./archive_libs/logical/q_res/chips/chips.prt';

PART_NAME
 R1357 'Q_RES_0402LF-2.2K,5%,1/16W,CHIP,CS22202JB07':;

SECTION_NUMBER 1
 '@T6G_MB_LIB.T6G(SCH_1):PAGE144_I74@PURE_QUANTA.Q_RES(CHIPS)':
 C_PATH='@t6g_mb_lib.t6g(sch_1):page144_i74@pure_quanta.q_res(chips)',
 P_PATH='@t6g_mb_lib.t6g(sch_1):page167_i74@pure_quanta.q_res(chips)',
 PATH='I74',
 DRAWING='@T6G_MB_LIB.T6G(SCH_1):PAGE144',
 WATTAGE='1/16W',
 TOLERANCE='5%',
 MATERIAL='CHIP',
 PHYS_PAGE='167',
 XY='(-1775,4100)',
 ROT='0',
 VER='2',
 PACK_TYPE='0402LF',
 LOCATION='R1357',
 CDS_LIB='pure_quanta',
 CDS_PART_NAME='Q_RES_0402LF-2.2K,5%,1/16W,CHIP,CS22202JB07',
 PART_NUMBER='CS22202JB07',
 VALUE='2.2K',
 PRIM_FILE='./archive_libs/logical/q_res/chips/chips.prt';

PART_NAME
 R1358 'Q_RES_0402LF-10K,5%,1/16W,EMPTY,CS31002JB08':;

SECTION_NUMBER 1
 '@T6G_MB_LIB.T6G(SCH_1):PAGE144_I72@PURE_QUANTA.Q_RES(CHIPS)':
 C_PATH='@t6g_mb_lib.t6g(sch_1):page144_i72@pure_quanta.q_res(chips)',
 P_PATH='@t6g_mb_lib.t6g(sch_1):page167_i72@pure_quanta.q_res(chips)',
 PATH='I72',
 DRAWING='@T6G_MB_LIB.T6G(SCH_1):PAGE144',
 WATTAGE='1/16W',
 TOLERANCE='5%',
 MATERIAL='EMPTY',
 PHYS_PAGE='167',
 XY='(-1525,2600)',
 ROT='2',
 VER='2',
 PACK_TYPE='0402LF',
 LOCATION='R1358',
 CDS_LIB='pure_quanta',
 CDS_PART_NAME='Q_RES_0402LF-10K,5%,1/16W,EMPTY,CS31002JB08',
 PART_NUMBER='CS31002JB08',
 VALUE='10K',
 PRIM_FILE='./archive_libs/logical/q_res/chips/chips.prt';

PART_NAME
 R1359 'Q_RES_0402LF-0,5%,1/16W,CHIP,CS00002JB13':;

SECTION_NUMBER 1
 '@T6G_MB_LIB.T6G(SCH_1):PAGE80_I158@PURE_QUANTA.Q_RES(CHIPS)':
 C_PATH='@t6g_mb_lib.t6g(sch_1):page80_i158@pure_quanta.q_res(chips)',
 P_PATH='@t6g_mb_lib.t6g(sch_1):page81_i158@pure_quanta.q_res(chips)',
 PATH='I158',
 DRAWING='@T6G_MB_LIB.T6G(SCH_1):PAGE80',
 BOM_COST='MEM',
 WATTAGE='1/16W',
 TOLERANCE='5%',
 MATERIAL='CHIP',
 PHYS_PAGE='81',
 XY='(-3225,4375)',
 ROT='0',
 VER='1',
 PACK_TYPE='0402LF',
 LOCATION='R1359',
 CDS_LIB='pure_quanta',
 CDS_PART_NAME='Q_RES_0402LF-0,5%,1/16W,CHIP,CS00002JB13',
 PART_NUMBER='CS00002JB13',
 VALUE='0',
 PRIM_FILE='./archive_libs/logical/q_res/chips/chips.prt';

PART_NAME
 R1360 'Q_RES_0402LF-0,5%,1/16W,CHIP,CS00002JB13':;

SECTION_NUMBER 1
 '@T6G_MB_LIB.T6G(SCH_1):PAGE466_I93@PURE_QUANTA.Q_RES(CHIPS)':
 C_PATH='@t6g_mb_lib.t6g(sch_1):page466_i93@pure_quanta.q_res(chips)',
 P_PATH='@t6g_mb_lib.t6g(sch_1):page357_i93@pure_quanta.q_res(chips)',
 PATH='I93',
 DRAWING='@T6G_MB_LIB.T6G(SCH_1):PAGE466',
 WATTAGE='1/16W',
 TOLERANCE='5%',
 MATERIAL='CHIP',
 PHYS_PAGE='357',
 XY='(-4825,3550)',
 ROT='0',
 VER='2',
 PACK_TYPE='0402LF',
 LOCATION='R1360',
 CDS_LIB='pure_quanta',
 CDS_PART_NAME='Q_RES_0402LF-0,5%,1/16W,CHIP,CS00002JB13',
 PART_NUMBER='CS00002JB13',
 VALUE='0',
 PRIM_FILE='./archive_libs/logical/q_res/chips/chips.prt';

PART_NAME
 R1361 'Q_RES_0201LF-4.7K,5%,1/20W,CHIP,CS24701JE04':;

SECTION_NUMBER 1
 '@T6G_MB_LIB.T6G(SCH_1):PAGE377_I104@PURE_QUANTA.Q_RES(CHIPS)':
 C_PATH='@t6g_mb_lib.t6g(sch_1):page377_i104@pure_quanta.q_res(chips)',
 P_PATH='@t6g_mb_lib.t6g(sch_1):page185_i104@pure_quanta.q_res(chips)',
 PATH='I104',
 DRAWING='@T6G_MB_LIB.T6G(SCH_1):PAGE377',
 SEC_TYPE='0201LF',
 WATTAGE='1/20W',
 TOLERANCE='5%',
 MATERIAL='CHIP',
 PHYS_PAGE='185',
 XY='(-2400,2625)',
 ROT='0',
 VER='1',
 PACK_TYPE='0201LF',
 LOCATION='R1361',
 SEC='1',
 CDS_LIB='pure_quanta',
 CDS_PART_NAME='Q_RES_0201LF-4.7K,5%,1/20W,CHIP,CS24701JE04',
 PART_NUMBER='CS24701JE04',
 VALUE='4.7K',
 PRIM_FILE='./archive_libs/logical/q_res/chips/chips.prt';

PART_NAME
 R1362 'Q_RES_0402LF-33,5%,1/16W,CHIP,CS03302JB10':;

SECTION_NUMBER 1
 '@T6G_MB_LIB.T6G(SCH_1):PAGE273_I130@PURE_QUANTA.Q_RES(CHIPS)':
 C_PATH='@t6g_mb_lib.t6g(sch_1):page273_i130@pure_quanta.q_res(chips)',
 P_PATH='@t6g_mb_lib.t6g(sch_1):page188_i130@pure_quanta.q_res(chips)',
 PATH='I130',
 DRAWING='@T6G_MB_LIB.T6G(SCH_1):PAGE273',
 BOM_COST='MEM',
 WATTAGE='1/16W',
 TOLERANCE='5%',
 MATERIAL='CHIP',
 PHYS_PAGE='188',
 XY='(-3925,2600)',
 ROT='0',
 VER='1',
 PACK_TYPE='0402LF',
 LOCATION='R1362',
 CDS_LIB='pure_quanta',
 CDS_PART_NAME='Q_RES_0402LF-33,5%,1/16W,CHIP,CS03302JB10',
 PART_NUMBER='CS03302JB10',
 VALUE='33',
 PRIM_FILE='./archive_libs/logical/q_res/chips/chips.prt';

PART_NAME
 R1363 'Q_RES_0402LF-33,5%,1/16W,CHIP,CS03302JB10':;

SECTION_NUMBER 1
 '@T6G_MB_LIB.T6G(SCH_1):PAGE264_I17@PURE_QUANTA.Q_RES(CHIPS)':
 C_PATH='@t6g_mb_lib.t6g(sch_1):page264_i17@pure_quanta.q_res(chips)',
 P_PATH='@t6g_mb_lib.t6g(sch_1):page259_i17@pure_quanta.q_res(chips)',
 PATH='I17',
 DRAWING='@T6G_MB_LIB.T6G(SCH_1):PAGE264',
 BOM_COST='MEM',
 WATTAGE='1/16W',
 TOLERANCE='5%',
 MATERIAL='CHIP',
 PHYS_PAGE='259',
 XY='(-3575,2025)',
 ROT='0',
 VER='1',
 PACK_TYPE='0402LF',
 LOCATION='R1363',
 CDS_LIB='pure_quanta',
 CDS_PART_NAME='Q_RES_0402LF-33,5%,1/16W,CHIP,CS03302JB10',
 PART_NUMBER='CS03302JB10',
 VALUE='33',
 PRIM_FILE='./archive_libs/logical/q_res/chips/chips.prt';

PART_NAME
 R1364 'Q_RES_0201LF-1K,1%,1/20W,CHIP,CS21001FE07':;

SECTION_NUMBER 1
 '@T6G_MB_LIB.T6G(SCH_1):PAGE385_I111@PURE_QUANTA.Q_RES(CHIPS)':
 C_PATH='@t6g_mb_lib.t6g(sch_1):page385_i111@pure_quanta.q_res(chips)',
 P_PATH='@t6g_mb_lib.t6g(sch_1):page276_i111@pure_quanta.q_res(chips)',
 PATH='I111',
 DRAWING='@T6G_MB_LIB.T6G(SCH_1):PAGE385',
 WATTAGE='1/20W',
 TOLERANCE='1%',
 MATERIAL='CHIP',
 PHYS_PAGE='276',
 XY='(-2700,3200)',
 ROT='0',
 VER='1',
 PACK_TYPE='0201LF',
 LOCATION='R1364',
 CDS_LIB='pure_quanta',
 CDS_PART_NAME='Q_RES_0201LF-1K,1%,1/20W,CHIP,CS21001FE07',
 PART_NUMBER='CS21001FE07',
 VALUE='1K',
 PRIM_FILE='./archive_libs/logical/q_res/chips/chips.prt';

PART_NAME
 R1365 'Q_RES_0201LF-4.7K,5%,1/20W,CHIP,CS24701JE04':;

SECTION_NUMBER 1
 '@T6G_MB_LIB.T6G(SCH_1):PAGE385_I123@PURE_QUANTA.Q_RES(CHIPS)':
 C_PATH='@t6g_mb_lib.t6g(sch_1):page385_i123@pure_quanta.q_res(chips)',
 P_PATH='@t6g_mb_lib.t6g(sch_1):page276_i123@pure_quanta.q_res(chips)',
 PATH='I123',
 DRAWING='@T6G_MB_LIB.T6G(SCH_1):PAGE385',
 WATTAGE='1/20W',
 TOLERANCE='5%',
 MATERIAL='CHIP',
 PHYS_PAGE='276',
 XY='(-650,825)',
 ROT='0',
 VER='2',
 PACK_TYPE='0201LF',
 LOCATION='R1365',
 CDS_LIB='pure_quanta',
 CDS_PART_NAME='Q_RES_0201LF-4.7K,5%,1/20W,CHIP,CS24701JE04',
 PART_NUMBER='CS24701JE04',
 VALUE='4.7K',
 PRIM_FILE='./archive_libs/logical/q_res/chips/chips.prt';

PART_NAME
 R1366 'Q_RES_0201LF-4.7K,5%,1/20W,CHIP,CS24701JE04':;

SECTION_NUMBER 1
 '@T6G_MB_LIB.T6G(SCH_1):PAGE377_I122@PURE_QUANTA.Q_RES(CHIPS)':
 C_PATH='@t6g_mb_lib.t6g(sch_1):page377_i122@pure_quanta.q_res(chips)',
 P_PATH='@t6g_mb_lib.t6g(sch_1):page185_i122@pure_quanta.q_res(chips)',
 PATH='I122',
 DRAWING='@T6G_MB_LIB.T6G(SCH_1):PAGE377',
 WATTAGE='1/20W',
 TOLERANCE='5%',
 MATERIAL='CHIP',
 PHYS_PAGE='185',
 XY='(-5550,2650)',
 ROT='0',
 VER='1',
 PACK_TYPE='0201LF',
 LOCATION='R1366',
 CDS_LIB='pure_quanta',
 CDS_PART_NAME='Q_RES_0201LF-4.7K,5%,1/20W,CHIP,CS24701JE04',
 PART_NUMBER='CS24701JE04',
 VALUE='4.7K',
 PRIM_FILE='./archive_libs/logical/q_res/chips/chips.prt';

PART_NAME
 R1367 'Q_RES_0201LF-4.7K,5%,1/20W,CHIP,CS24701JE04':;

SECTION_NUMBER 1
 '@T6G_MB_LIB.T6G(SCH_1):PAGE377_I121@PURE_QUANTA.Q_RES(CHIPS)':
 C_PATH='@t6g_mb_lib.t6g(sch_1):page377_i121@pure_quanta.q_res(chips)',
 P_PATH='@t6g_mb_lib.t6g(sch_1):page185_i121@pure_quanta.q_res(chips)',
 PATH='I121',
 DRAWING='@T6G_MB_LIB.T6G(SCH_1):PAGE377',
 WATTAGE='1/20W',
 TOLERANCE='5%',
 MATERIAL='CHIP',
 PHYS_PAGE='185',
 XY='(-5550,2600)',
 ROT='0',
 VER='1',
 PACK_TYPE='0201LF',
 LOCATION='R1367',
 CDS_LIB='pure_quanta',
 CDS_PART_NAME='Q_RES_0201LF-4.7K,5%,1/20W,CHIP,CS24701JE04',
 PART_NUMBER='CS24701JE04',
 VALUE='4.7K',
 PRIM_FILE='./archive_libs/logical/q_res/chips/chips.prt';

PART_NAME
 R1368 'Q_RES_0201LF-4.7K,5%,1/20W,CHIP,CS24701JE04':;

SECTION_NUMBER 1
 '@T6G_MB_LIB.T6G(SCH_1):PAGE385_I119@PURE_QUANTA.Q_RES(CHIPS)':
 C_PATH='@t6g_mb_lib.t6g(sch_1):page385_i119@pure_quanta.q_res(chips)',
 P_PATH='@t6g_mb_lib.t6g(sch_1):page276_i119@pure_quanta.q_res(chips)',
 PATH='I119',
 DRAWING='@T6G_MB_LIB.T6G(SCH_1):PAGE385',
 WATTAGE='1/20W',
 TOLERANCE='5%',
 MATERIAL='CHIP',
 PHYS_PAGE='276',
 XY='(-2675,2250)',
 ROT='0',
 VER='1',
 PACK_TYPE='0201LF',
 LOCATION='R1368',
 CDS_LIB='pure_quanta',
 CDS_PART_NAME='Q_RES_0201LF-4.7K,5%,1/20W,CHIP,CS24701JE04',
 PART_NUMBER='CS24701JE04',
 VALUE='4.7K',
 PRIM_FILE='./archive_libs/logical/q_res/chips/chips.prt';

PART_NAME
 R1369 'Q_RES_0201LF-1K,1%,1/20W,EMPTY,CS21001FE07':;

SECTION_NUMBER 1
 '@T6G_MB_LIB.T6G(SCH_1):PAGE385_I116@PURE_QUANTA.Q_RES(CHIPS)':
 C_PATH='@t6g_mb_lib.t6g(sch_1):page385_i116@pure_quanta.q_res(chips)',
 P_PATH='@t6g_mb_lib.t6g(sch_1):page276_i116@pure_quanta.q_res(chips)',
 PATH='I116',
 DRAWING='@T6G_MB_LIB.T6G(SCH_1):PAGE385',
 WATTAGE='1/20W',
 TOLERANCE='1%',
 MATERIAL='EMPTY',
 PHYS_PAGE='276',
 XY='(-1350,3875)',
 ROT='0',
 VER='2',
 PACK_TYPE='0201LF',
 LOCATION='R1369',
 CDS_LIB='pure_quanta',
 CDS_PART_NAME='Q_RES_0201LF-1K,1%,1/20W,EMPTY,CS21001FE07',
 PART_NUMBER='CS21001FE07',
 VALUE='1K',
 PRIM_FILE='./archive_libs/logical/q_res/chips/chips.prt';

PART_NAME
 R1370 'Q_RES_0201LF-10K,1%,1/20W,CHIP,CS31001FE17':;

SECTION_NUMBER 1
 '@T6G_MB_LIB.T6G(SCH_1):PAGE385_I114@PURE_QUANTA.Q_RES(CHIPS)':
 C_PATH='@t6g_mb_lib.t6g(sch_1):page385_i114@pure_quanta.q_res(chips)',
 P_PATH='@t6g_mb_lib.t6g(sch_1):page276_i114@pure_quanta.q_res(chips)',
 PATH='I114',
 DRAWING='@T6G_MB_LIB.T6G(SCH_1):PAGE385',
 WATTAGE='1/20W',
 TOLERANCE='1%',
 MATERIAL='CHIP',
 PHYS_PAGE='276',
 XY='(-1350,3350)',
 ROT='0',
 VER='2',
 PACK_TYPE='0201LF',
 LOCATION='R1370',
 CDS_LIB='pure_quanta',
 CDS_PART_NAME='Q_RES_0201LF-10K,1%,1/20W,CHIP,CS31001FE17',
 PART_NUMBER='CS31001FE17',
 VALUE='10K',
 PRIM_FILE='./archive_libs/logical/q_res/chips/chips.prt';

PART_NAME
 R1371 'Q_RES_0201LF-4.7K,5%,1/20W,CHIP,CS24701JE04':;

SECTION_NUMBER 1
 '@T6G_MB_LIB.T6G(SCH_1):PAGE377_I124@PURE_QUANTA.Q_RES(CHIPS)':
 C_PATH='@t6g_mb_lib.t6g(sch_1):page377_i124@pure_quanta.q_res(chips)',
 P_PATH='@t6g_mb_lib.t6g(sch_1):page185_i124@pure_quanta.q_res(chips)',
 PATH='I124',
 DRAWING='@T6G_MB_LIB.T6G(SCH_1):PAGE377',
 WATTAGE='1/20W',
 TOLERANCE='5%',
 MATERIAL='CHIP',
 PHYS_PAGE='185',
 XY='(-5550,2550)',
 ROT='0',
 VER='1',
 PACK_TYPE='0201LF',
 LOCATION='R1371',
 CDS_LIB='pure_quanta',
 CDS_PART_NAME='Q_RES_0201LF-4.7K,5%,1/20W,CHIP,CS24701JE04',
 PART_NUMBER='CS24701JE04',
 VALUE='4.7K',
 PRIM_FILE='./archive_libs/logical/q_res/chips/chips.prt';

PART_NAME
 R1372 'Q_RES_0201LF-1K,1%,1/20W,CHIP,CS21001FE07':;

SECTION_NUMBER 1
 '@T6G_MB_LIB.T6G(SCH_1):PAGE392_I115@PURE_QUANTA.Q_RES(CHIPS)':
 C_PATH='@t6g_mb_lib.t6g(sch_1):page392_i115@pure_quanta.q_res(chips)',
 P_PATH='@t6g_mb_lib.t6g(sch_1):page331_i115@pure_quanta.q_res(chips)',
 PATH='I115',
 DRAWING='@T6G_MB_LIB.T6G(SCH_1):PAGE392',
 WATTAGE='1/20W',
 TOLERANCE='1%',
 MATERIAL='CHIP',
 PHYS_PAGE='331',
 XY='(-2550,3100)',
 ROT='0',
 VER='1',
 PACK_TYPE='0201LF',
 LOCATION='R1372',
 CDS_LIB='pure_quanta',
 CDS_PART_NAME='Q_RES_0201LF-1K,1%,1/20W,CHIP,CS21001FE07',
 PART_NUMBER='CS21001FE07',
 VALUE='1K',
 PRIM_FILE='./archive_libs/logical/q_res/chips/chips.prt';

PART_NAME
 R1373 'Q_RES_0201LF-4.7K,5%,1/20W,CHIP,CS24701JE04':;

SECTION_NUMBER 1
 '@T6G_MB_LIB.T6G(SCH_1):PAGE392_I150@PURE_QUANTA.Q_RES(CHIPS)':
 C_PATH='@t6g_mb_lib.t6g(sch_1):page392_i150@pure_quanta.q_res(chips)',
 P_PATH='@t6g_mb_lib.t6g(sch_1):page331_i150@pure_quanta.q_res(chips)',
 PATH='I150',
 DRAWING='@T6G_MB_LIB.T6G(SCH_1):PAGE392',
 WATTAGE='1/20W',
 TOLERANCE='5%',
 MATERIAL='CHIP',
 PHYS_PAGE='331',
 XY='(-650,675)',
 ROT='0',
 VER='2',
 PACK_TYPE='0201LF',
 LOCATION='R1373',
 CDS_LIB='pure_quanta',
 CDS_PART_NAME='Q_RES_0201LF-4.7K,5%,1/20W,CHIP,CS24701JE04',
 PART_NUMBER='CS24701JE04',
 VALUE='4.7K',
 PRIM_FILE='./archive_libs/logical/q_res/chips/chips.prt';

PART_NAME
 R1374 'Q_RES_0201LF-4.7K,5%,1/20W,CHIP,CS24701JE04':;

SECTION_NUMBER 1
 '@T6G_MB_LIB.T6G(SCH_1):PAGE377_I123@PURE_QUANTA.Q_RES(CHIPS)':
 C_PATH='@t6g_mb_lib.t6g(sch_1):page377_i123@pure_quanta.q_res(chips)',
 P_PATH='@t6g_mb_lib.t6g(sch_1):page185_i123@pure_quanta.q_res(chips)',
 PATH='I123',
 DRAWING='@T6G_MB_LIB.T6G(SCH_1):PAGE377',
 WATTAGE='1/20W',
 TOLERANCE='5%',
 MATERIAL='CHIP',
 PHYS_PAGE='185',
 XY='(-5550,2500)',
 ROT='0',
 VER='1',
 PACK_TYPE='0201LF',
 LOCATION='R1374',
 CDS_LIB='pure_quanta',
 CDS_PART_NAME='Q_RES_0201LF-4.7K,5%,1/20W,CHIP,CS24701JE04',
 PART_NUMBER='CS24701JE04',
 VALUE='4.7K',
 PRIM_FILE='./archive_libs/logical/q_res/chips/chips.prt';

PART_NAME
 R1375 'Q_RES_0201LF-4.7K,5%,1/20W,CHIP,CS24701JE04':;

SECTION_NUMBER 1
 '@T6G_MB_LIB.T6G(SCH_1):PAGE377_I125@PURE_QUANTA.Q_RES(CHIPS)':
 C_PATH='@t6g_mb_lib.t6g(sch_1):page377_i125@pure_quanta.q_res(chips)',
 P_PATH='@t6g_mb_lib.t6g(sch_1):page185_i125@pure_quanta.q_res(chips)',
 PATH='I125',
 DRAWING='@T6G_MB_LIB.T6G(SCH_1):PAGE377',
 WATTAGE='1/20W',
 TOLERANCE='5%',
 MATERIAL='CHIP',
 PHYS_PAGE='185',
 XY='(-5550,2450)',
 ROT='0',
 VER='1',
 PACK_TYPE='0201LF',
 LOCATION='R1375',
 CDS_LIB='pure_quanta',
 CDS_PART_NAME='Q_RES_0201LF-4.7K,5%,1/20W,CHIP,CS24701JE04',
 PART_NUMBER='CS24701JE04',
 VALUE='4.7K',
 PRIM_FILE='./archive_libs/logical/q_res/chips/chips.prt';

PART_NAME
 R1376 'Q_RES_0201LF-4.7K,5%,1/20W,CHIP,CS24701JE04':;

SECTION_NUMBER 1
 '@T6G_MB_LIB.T6G(SCH_1):PAGE392_I111@PURE_QUANTA.Q_RES(CHIPS)':
 C_PATH='@t6g_mb_lib.t6g(sch_1):page392_i111@pure_quanta.q_res(chips)',
 P_PATH='@t6g_mb_lib.t6g(sch_1):page331_i111@pure_quanta.q_res(chips)',
 PATH='I111',
 DRAWING='@T6G_MB_LIB.T6G(SCH_1):PAGE392',
 WATTAGE='1/20W',
 TOLERANCE='5%',
 MATERIAL='CHIP',
 PHYS_PAGE='331',
 XY='(-2525,2150)',
 ROT='0',
 VER='1',
 PACK_TYPE='0201LF',
 LOCATION='R1376',
 CDS_LIB='pure_quanta',
 CDS_PART_NAME='Q_RES_0201LF-4.7K,5%,1/20W,CHIP,CS24701JE04',
 PART_NUMBER='CS24701JE04',
 VALUE='4.7K',
 PRIM_FILE='./archive_libs/logical/q_res/chips/chips.prt';

PART_NAME
 R1377 'Q_RES_0201LF-1K,1%,1/20W,EMPTY,CS21001FE07':;

SECTION_NUMBER 1
 '@T6G_MB_LIB.T6G(SCH_1):PAGE392_I125@PURE_QUANTA.Q_RES(CHIPS)':
 C_PATH='@t6g_mb_lib.t6g(sch_1):page392_i125@pure_quanta.q_res(chips)',
 P_PATH='@t6g_mb_lib.t6g(sch_1):page331_i125@pure_quanta.q_res(chips)',
 PATH='I125',
 DRAWING='@T6G_MB_LIB.T6G(SCH_1):PAGE392',
 WATTAGE='1/20W',
 TOLERANCE='1%',
 MATERIAL='EMPTY',
 PHYS_PAGE='331',
 XY='(-1450,3700)',
 ROT='0',
 VER='2',
 PACK_TYPE='0201LF',
 LOCATION='R1377',
 CDS_LIB='pure_quanta',
 CDS_PART_NAME='Q_RES_0201LF-1K,1%,1/20W,EMPTY,CS21001FE07',
 PART_NUMBER='CS21001FE07',
 VALUE='1K',
 PRIM_FILE='./archive_libs/logical/q_res/chips/chips.prt';

PART_NAME
 R1378 'Q_RES_0201LF-10K,1%,1/20W,CHIP,CS31001FE17':;

SECTION_NUMBER 1
 '@T6G_MB_LIB.T6G(SCH_1):PAGE392_I126@PURE_QUANTA.Q_RES(CHIPS)':
 C_PATH='@t6g_mb_lib.t6g(sch_1):page392_i126@pure_quanta.q_res(chips)',
 P_PATH='@t6g_mb_lib.t6g(sch_1):page331_i126@pure_quanta.q_res(chips)',
 PATH='I126',
 DRAWING='@T6G_MB_LIB.T6G(SCH_1):PAGE392',
 WATTAGE='1/20W',
 TOLERANCE='1%',
 MATERIAL='CHIP',
 PHYS_PAGE='331',
 XY='(-1450,3175)',
 ROT='0',
 VER='2',
 PACK_TYPE='0201LF',
 LOCATION='R1378',
 CDS_LIB='pure_quanta',
 CDS_PART_NAME='Q_RES_0201LF-10K,1%,1/20W,CHIP,CS31001FE17',
 PART_NUMBER='CS31001FE17',
 VALUE='10K',
 PRIM_FILE='./archive_libs/logical/q_res/chips/chips.prt';

PART_NAME
 R1379 'Q_RES_0201LF-4.7K,5%,1/20W,CHIP,CS24701JE04':;

SECTION_NUMBER 1
 '@T6G_MB_LIB.T6G(SCH_1):PAGE377_I126@PURE_QUANTA.Q_RES(CHIPS)':
 C_PATH='@t6g_mb_lib.t6g(sch_1):page377_i126@pure_quanta.q_res(chips)',
 P_PATH='@t6g_mb_lib.t6g(sch_1):page185_i126@pure_quanta.q_res(chips)',
 PATH='I126',
 DRAWING='@T6G_MB_LIB.T6G(SCH_1):PAGE377',
 WATTAGE='1/20W',
 TOLERANCE='5%',
 MATERIAL='CHIP',
 PHYS_PAGE='185',
 XY='(-5550,2400)',
 ROT='0',
 VER='1',
 PACK_TYPE='0201LF',
 LOCATION='R1379',
 CDS_LIB='pure_quanta',
 CDS_PART_NAME='Q_RES_0201LF-4.7K,5%,1/20W,CHIP,CS24701JE04',
 PART_NUMBER='CS24701JE04',
 VALUE='4.7K',
 PRIM_FILE='./archive_libs/logical/q_res/chips/chips.prt';

PART_NAME
 R1380 'Q_RES_0201LF-1K,1%,1/20W,CHIP,CS21001FE07':;

SECTION_NUMBER 1
 '@T6G_MB_LIB.T6G(SCH_1):PAGE401_I112@PURE_QUANTA.Q_RES(CHIPS)':
 C_PATH='@t6g_mb_lib.t6g(sch_1):page401_i112@pure_quanta.q_res(chips)',
 P_PATH='@t6g_mb_lib.t6g(sch_1):page320_i112@pure_quanta.q_res(chips)',
 PATH='I112',
 DRAWING='@T6G_MB_LIB.T6G(SCH_1):PAGE401',
 WATTAGE='1/20W',
 TOLERANCE='1%',
 MATERIAL='CHIP',
 PHYS_PAGE='320',
 XY='(-2700,3350)',
 ROT='0',
 VER='1',
 PACK_TYPE='0201LF',
 LOCATION='R1380',
 CDS_LIB='pure_quanta',
 CDS_PART_NAME='Q_RES_0201LF-1K,1%,1/20W,CHIP,CS21001FE07',
 PART_NUMBER='CS21001FE07',
 VALUE='1K',
 PRIM_FILE='./archive_libs/logical/q_res/chips/chips.prt';

PART_NAME
 R1381 'Q_RES_0201LF-4.7K,5%,1/20W,CHIP,CS24701JE04':;

SECTION_NUMBER 1
 '@T6G_MB_LIB.T6G(SCH_1):PAGE401_I144@PURE_QUANTA.Q_RES(CHIPS)':
 C_PATH='@t6g_mb_lib.t6g(sch_1):page401_i144@pure_quanta.q_res(chips)',
 P_PATH='@t6g_mb_lib.t6g(sch_1):page320_i144@pure_quanta.q_res(chips)',
 PATH='I144',
 DRAWING='@T6G_MB_LIB.T6G(SCH_1):PAGE401',
 WATTAGE='1/20W',
 TOLERANCE='5%',
 MATERIAL='CHIP',
 PHYS_PAGE='320',
 XY='(-650,750)',
 ROT='0',
 VER='2',
 PACK_TYPE='0201LF',
 LOCATION='R1381',
 CDS_LIB='pure_quanta',
 CDS_PART_NAME='Q_RES_0201LF-4.7K,5%,1/20W,CHIP,CS24701JE04',
 PART_NUMBER='CS24701JE04',
 VALUE='4.7K',
 PRIM_FILE='./archive_libs/logical/q_res/chips/chips.prt';

PART_NAME
 R1382 'Q_RES_0201LF-4.7K,5%,1/20W,CHIP,CS24701JE04':;

SECTION_NUMBER 1
 '@T6G_MB_LIB.T6G(SCH_1):PAGE377_I127@PURE_QUANTA.Q_RES(CHIPS)':
 C_PATH='@t6g_mb_lib.t6g(sch_1):page377_i127@pure_quanta.q_res(chips)',
 P_PATH='@t6g_mb_lib.t6g(sch_1):page185_i127@pure_quanta.q_res(chips)',
 PATH='I127',
 DRAWING='@T6G_MB_LIB.T6G(SCH_1):PAGE377',
 WATTAGE='1/20W',
 TOLERANCE='5%',
 MATERIAL='CHIP',
 PHYS_PAGE='185',
 XY='(-5550,2350)',
 ROT='0',
 VER='1',
 PACK_TYPE='0201LF',
 LOCATION='R1382',
 CDS_LIB='pure_quanta',
 CDS_PART_NAME='Q_RES_0201LF-4.7K,5%,1/20W,CHIP,CS24701JE04',
 PART_NUMBER='CS24701JE04',
 VALUE='4.7K',
 PRIM_FILE='./archive_libs/logical/q_res/chips/chips.prt';

PART_NAME
 R1383 'Q_RES_0201LF-4.7K,5%,1/20W,CHIP,CS24701JE04':;

SECTION_NUMBER 1
 '@T6G_MB_LIB.T6G(SCH_1):PAGE377_I128@PURE_QUANTA.Q_RES(CHIPS)':
 C_PATH='@t6g_mb_lib.t6g(sch_1):page377_i128@pure_quanta.q_res(chips)',
 P_PATH='@t6g_mb_lib.t6g(sch_1):page185_i128@pure_quanta.q_res(chips)',
 PATH='I128',
 DRAWING='@T6G_MB_LIB.T6G(SCH_1):PAGE377',
 WATTAGE='1/20W',
 TOLERANCE='5%',
 MATERIAL='CHIP',
 PHYS_PAGE='185',
 XY='(-5550,2300)',
 ROT='0',
 VER='1',
 PACK_TYPE='0201LF',
 LOCATION='R1383',
 CDS_LIB='pure_quanta',
 CDS_PART_NAME='Q_RES_0201LF-4.7K,5%,1/20W,CHIP,CS24701JE04',
 PART_NUMBER='CS24701JE04',
 VALUE='4.7K',
 PRIM_FILE='./archive_libs/logical/q_res/chips/chips.prt';

PART_NAME
 R1384 'Q_RES_0402LF-2K,1%,1/16W,EMPTY,CS22002FB07':;

SECTION_NUMBER 1
 '@T6G_MB_LIB.T6G(SCH_1):PAGE349_I136@PURE_QUANTA.Q_RES(CHIPS)':
 C_PATH='@t6g_mb_lib.t6g(sch_1):page349_i136@pure_quanta.q_res(chips)',
 P_PATH='@t6g_mb_lib.t6g(sch_1):page151_i136@pure_quanta.q_res(chips)',
 PATH='I136',
 DRAWING='@T6G_MB_LIB.T6G(SCH_1):PAGE349',
 WATTAGE='1/16W',
 TOLERANCE='1%',
 MATERIAL='EMPTY',
 PHYS_PAGE='151',
 XY='(4275,5025)',
 ROT='0',
 VER='1',
 PACK_TYPE='0402LF',
 LOCATION='R1384',
 CDS_LIB='pure_quanta',
 CDS_PART_NAME='Q_RES_0402LF-2K,1%,1/16W,EMPTY,CS22002FB07',
 PART_NUMBER='CS22002FB07',
 VALUE='2K',
 PRIM_FILE='./archive_libs/logical/q_res/chips/chips.prt';

PART_NAME
 R1385 'Q_RES_0402LF-2K,1%,1/16W,EMPTY,CS22002FB07':;

SECTION_NUMBER 1
 '@T6G_MB_LIB.T6G(SCH_1):PAGE349_I135@PURE_QUANTA.Q_RES(CHIPS)':
 C_PATH='@t6g_mb_lib.t6g(sch_1):page349_i135@pure_quanta.q_res(chips)',
 P_PATH='@t6g_mb_lib.t6g(sch_1):page151_i135@pure_quanta.q_res(chips)',
 PATH='I135',
 DRAWING='@T6G_MB_LIB.T6G(SCH_1):PAGE349',
 WATTAGE='1/16W',
 TOLERANCE='1%',
 MATERIAL='EMPTY',
 PHYS_PAGE='151',
 XY='(4275,4975)',
 ROT='0',
 VER='1',
 PACK_TYPE='0402LF',
 LOCATION='R1385',
 CDS_LIB='pure_quanta',
 CDS_PART_NAME='Q_RES_0402LF-2K,1%,1/16W,EMPTY,CS22002FB07',
 PART_NUMBER='CS22002FB07',
 VALUE='2K',
 PRIM_FILE='./archive_libs/logical/q_res/chips/chips.prt';

PART_NAME
 R1386 'Q_RES_0402LF-2K,1%,1/16W,EMPTY,CS22002FB07':;

SECTION_NUMBER 1
 '@T6G_MB_LIB.T6G(SCH_1):PAGE349_I134@PURE_QUANTA.Q_RES(CHIPS)':
 C_PATH='@t6g_mb_lib.t6g(sch_1):page349_i134@pure_quanta.q_res(chips)',
 P_PATH='@t6g_mb_lib.t6g(sch_1):page151_i134@pure_quanta.q_res(chips)',
 PATH='I134',
 DRAWING='@T6G_MB_LIB.T6G(SCH_1):PAGE349',
 WATTAGE='1/16W',
 TOLERANCE='1%',
 MATERIAL='EMPTY',
 PHYS_PAGE='151',
 XY='(4275,4775)',
 ROT='0',
 VER='1',
 PACK_TYPE='0402LF',
 LOCATION='R1386',
 CDS_LIB='pure_quanta',
 CDS_PART_NAME='Q_RES_0402LF-2K,1%,1/16W,EMPTY,CS22002FB07',
 PART_NUMBER='CS22002FB07',
 VALUE='2K',
 PRIM_FILE='./archive_libs/logical/q_res/chips/chips.prt';

PART_NAME
 R1387 'Q_RES_0201LF-4.7K,5%,1/20W,CHIP,CS24701JE04':;

SECTION_NUMBER 1
 '@T6G_MB_LIB.T6G(SCH_1):PAGE401_I108@PURE_QUANTA.Q_RES(CHIPS)':
 C_PATH='@t6g_mb_lib.t6g(sch_1):page401_i108@pure_quanta.q_res(chips)',
 P_PATH='@t6g_mb_lib.t6g(sch_1):page320_i108@pure_quanta.q_res(chips)',
 PATH='I108',
 DRAWING='@T6G_MB_LIB.T6G(SCH_1):PAGE401',
 WATTAGE='1/20W',
 TOLERANCE='5%',
 MATERIAL='CHIP',
 PHYS_PAGE='320',
 XY='(-2675,2400)',
 ROT='0',
 VER='1',
 PACK_TYPE='0201LF',
 LOCATION='R1387',
 CDS_LIB='pure_quanta',
 CDS_PART_NAME='Q_RES_0201LF-4.7K,5%,1/20W,CHIP,CS24701JE04',
 PART_NUMBER='CS24701JE04',
 VALUE='4.7K',
 PRIM_FILE='./archive_libs/logical/q_res/chips/chips.prt';

PART_NAME
 R1388 'Q_RES_0201LF-1K,1%,1/20W,EMPTY,CS21001FE07':;

SECTION_NUMBER 1
 '@T6G_MB_LIB.T6G(SCH_1):PAGE401_I125@PURE_QUANTA.Q_RES(CHIPS)':
 C_PATH='@t6g_mb_lib.t6g(sch_1):page401_i125@pure_quanta.q_res(chips)',
 P_PATH='@t6g_mb_lib.t6g(sch_1):page320_i125@pure_quanta.q_res(chips)',
 PATH='I125',
 DRAWING='@T6G_MB_LIB.T6G(SCH_1):PAGE401',
 WATTAGE='1/20W',
 TOLERANCE='1%',
 MATERIAL='EMPTY',
 PHYS_PAGE='320',
 XY='(-1525,4025)',
 ROT='0',
 VER='2',
 PACK_TYPE='0201LF',
 LOCATION='R1388',
 CDS_LIB='pure_quanta',
 CDS_PART_NAME='Q_RES_0201LF-1K,1%,1/20W,EMPTY,CS21001FE07',
 PART_NUMBER='CS21001FE07',
 VALUE='1K',
 PRIM_FILE='./archive_libs/logical/q_res/chips/chips.prt';

PART_NAME
 R1389 'Q_RES_0201LF-10K,1%,1/20W,CHIP,CS31001FE17':;

SECTION_NUMBER 1
 '@T6G_MB_LIB.T6G(SCH_1):PAGE401_I124@PURE_QUANTA.Q_RES(CHIPS)':
 C_PATH='@t6g_mb_lib.t6g(sch_1):page401_i124@pure_quanta.q_res(chips)',
 P_PATH='@t6g_mb_lib.t6g(sch_1):page320_i124@pure_quanta.q_res(chips)',
 PATH='I124',
 DRAWING='@T6G_MB_LIB.T6G(SCH_1):PAGE401',
 WATTAGE='1/20W',
 TOLERANCE='1%',
 MATERIAL='CHIP',
 PHYS_PAGE='320',
 XY='(-1525,3500)',
 ROT='0',
 VER='2',
 PACK_TYPE='0201LF',
 LOCATION='R1389',
 CDS_LIB='pure_quanta',
 CDS_PART_NAME='Q_RES_0201LF-10K,1%,1/20W,CHIP,CS31001FE17',
 PART_NUMBER='CS31001FE17',
 VALUE='10K',
 PRIM_FILE='./archive_libs/logical/q_res/chips/chips.prt';

PART_NAME
 R1390 'Q_RES_0201LF-4.7K,5%,1/20W,CHIP,CS24701JE04':;

SECTION_NUMBER 1
 '@T6G_MB_LIB.T6G(SCH_1):PAGE377_I105@PURE_QUANTA.Q_RES(CHIPS)':
 C_PATH='@t6g_mb_lib.t6g(sch_1):page377_i105@pure_quanta.q_res(chips)',
 P_PATH='@t6g_mb_lib.t6g(sch_1):page185_i105@pure_quanta.q_res(chips)',
 PATH='I105',
 DRAWING='@T6G_MB_LIB.T6G(SCH_1):PAGE377',
 WATTAGE='1/20W',
 TOLERANCE='5%',
 MATERIAL='CHIP',
 PHYS_PAGE='185',
 XY='(-2400,2575)',
 ROT='0',
 VER='1',
 PACK_TYPE='0201LF',
 LOCATION='R1390',
 CDS_LIB='pure_quanta',
 CDS_PART_NAME='Q_RES_0201LF-4.7K,5%,1/20W,CHIP,CS24701JE04',
 PART_NUMBER='CS24701JE04',
 VALUE='4.7K',
 PRIM_FILE='./archive_libs/logical/q_res/chips/chips.prt';

PART_NAME
 R1391 'Q_RES_0201LF-1K,1%,1/20W,CHIP,CS21001FE07':;

SECTION_NUMBER 1
 '@T6G_MB_LIB.T6G(SCH_1):PAGE408_I84@PURE_QUANTA.Q_RES(CHIPS)':
 C_PATH='@t6g_mb_lib.t6g(sch_1):page408_i84@pure_quanta.q_res(chips)',
 P_PATH='@t6g_mb_lib.t6g(sch_1):page287_i84@pure_quanta.q_res(chips)',
 PATH='I84',
 DRAWING='@T6G_MB_LIB.T6G(SCH_1):PAGE408',
 WATTAGE='1/20W',
 TOLERANCE='1%',
 MATERIAL='CHIP',
 PHYS_PAGE='287',
 XY='(-2700,3250)',
 ROT='0',
 VER='1',
 PACK_TYPE='0201LF',
 LOCATION='R1391',
 CDS_LIB='pure_quanta',
 CDS_PART_NAME='Q_RES_0201LF-1K,1%,1/20W,CHIP,CS21001FE07',
 PART_NUMBER='CS21001FE07',
 VALUE='1K',
 PRIM_FILE='./archive_libs/logical/q_res/chips/chips.prt';

PART_NAME
 R1392 'Q_RES_0201LF-4.7K,5%,1/20W,CHIP,CS24701JE04':;

SECTION_NUMBER 1
 '@T6G_MB_LIB.T6G(SCH_1):PAGE408_I119@PURE_QUANTA.Q_RES(CHIPS)':
 C_PATH='@t6g_mb_lib.t6g(sch_1):page408_i119@pure_quanta.q_res(chips)',
 P_PATH='@t6g_mb_lib.t6g(sch_1):page287_i119@pure_quanta.q_res(chips)',
 PATH='I119',
 DRAWING='@T6G_MB_LIB.T6G(SCH_1):PAGE408',
 WATTAGE='1/20W',
 TOLERANCE='5%',
 MATERIAL='CHIP',
 PHYS_PAGE='287',
 XY='(-825,725)',
 ROT='0',
 VER='2',
 PACK_TYPE='0201LF',
 LOCATION='R1392',
 CDS_LIB='pure_quanta',
 CDS_PART_NAME='Q_RES_0201LF-4.7K,5%,1/20W,CHIP,CS24701JE04',
 PART_NUMBER='CS24701JE04',
 VALUE='4.7K',
 PRIM_FILE='./archive_libs/logical/q_res/chips/chips.prt';

PART_NAME
 R1393 'Q_RES_0201LF-4.7K,5%,1/20W,CHIP,CS24701JE04':;

SECTION_NUMBER 1
 '@T6G_MB_LIB.T6G(SCH_1):PAGE377_I106@PURE_QUANTA.Q_RES(CHIPS)':
 C_PATH='@t6g_mb_lib.t6g(sch_1):page377_i106@pure_quanta.q_res(chips)',
 P_PATH='@t6g_mb_lib.t6g(sch_1):page185_i106@pure_quanta.q_res(chips)',
 PATH='I106',
 DRAWING='@T6G_MB_LIB.T6G(SCH_1):PAGE377',
 WATTAGE='1/20W',
 TOLERANCE='5%',
 MATERIAL='CHIP',
 PHYS_PAGE='185',
 XY='(-2400,2525)',
 ROT='0',
 VER='1',
 PACK_TYPE='0201LF',
 LOCATION='R1393',
 CDS_LIB='pure_quanta',
 CDS_PART_NAME='Q_RES_0201LF-4.7K,5%,1/20W,CHIP,CS24701JE04',
 PART_NUMBER='CS24701JE04',
 VALUE='4.7K',
 PRIM_FILE='./archive_libs/logical/q_res/chips/chips.prt';

PART_NAME
 R1394 'Q_RES_0201LF-4.7K,5%,1/20W,CHIP,CS24701JE04':;

SECTION_NUMBER 1
 '@T6G_MB_LIB.T6G(SCH_1):PAGE377_I107@PURE_QUANTA.Q_RES(CHIPS)':
 C_PATH='@t6g_mb_lib.t6g(sch_1):page377_i107@pure_quanta.q_res(chips)',
 P_PATH='@t6g_mb_lib.t6g(sch_1):page185_i107@pure_quanta.q_res(chips)',
 PATH='I107',
 DRAWING='@T6G_MB_LIB.T6G(SCH_1):PAGE377',
 WATTAGE='1/20W',
 TOLERANCE='5%',
 MATERIAL='CHIP',
 PHYS_PAGE='185',
 XY='(-2400,2475)',
 ROT='0',
 VER='1',
 PACK_TYPE='0201LF',
 LOCATION='R1394',
 CDS_LIB='pure_quanta',
 CDS_PART_NAME='Q_RES_0201LF-4.7K,5%,1/20W,CHIP,CS24701JE04',
 PART_NUMBER='CS24701JE04',
 VALUE='4.7K',
 PRIM_FILE='./archive_libs/logical/q_res/chips/chips.prt';

PART_NAME
 R1395 'Q_RES_0201LF-4.7K,5%,1/20W,CHIP,CS24701JE04':;

SECTION_NUMBER 1
 '@T6G_MB_LIB.T6G(SCH_1):PAGE408_I94@PURE_QUANTA.Q_RES(CHIPS)':
 C_PATH='@t6g_mb_lib.t6g(sch_1):page408_i94@pure_quanta.q_res(chips)',
 P_PATH='@t6g_mb_lib.t6g(sch_1):page287_i94@pure_quanta.q_res(chips)',
 PATH='I94',
 DRAWING='@T6G_MB_LIB.T6G(SCH_1):PAGE408',
 WATTAGE='1/20W',
 TOLERANCE='5%',
 MATERIAL='CHIP',
 PHYS_PAGE='287',
 XY='(-2675,2300)',
 ROT='0',
 VER='1',
 PACK_TYPE='0201LF',
 LOCATION='R1395',
 CDS_LIB='pure_quanta',
 CDS_PART_NAME='Q_RES_0201LF-4.7K,5%,1/20W,CHIP,CS24701JE04',
 PART_NUMBER='CS24701JE04',
 VALUE='4.7K',
 PRIM_FILE='./archive_libs/logical/q_res/chips/chips.prt';

PART_NAME
 R1396 'Q_RES_0402LF-10K,1%,1/16W,CHIP,CS31002FB08':;

SECTION_NUMBER 1
 '@T6G_MB_LIB.T6G(SCH_1):PAGE345_I66@PURE_QUANTA.Q_RES(CHIPS)':
 C_PATH='@t6g_mb_lib.t6g(sch_1):page345_i66@pure_quanta.q_res(chips)',
 P_PATH='@t6g_mb_lib.t6g(sch_1):page144_i66@pure_quanta.q_res(chips)',
 PATH='I66',
 DRAWING='@T6G_MB_LIB.T6G(SCH_1):PAGE345',
 WATTAGE='1/16W',
 TOLERANCE='1%',
 MATERIAL='CHIP',
 PHYS_PAGE='144',
 XY='(10550,3200)',
 ROT='0',
 VER='1',
 PACK_TYPE='0402LF',
 LOCATION='R1396',
 CDS_LIB='pure_quanta',
 CDS_PART_NAME='Q_RES_0402LF-10K,1%,1/16W,CHIP,CS31002FB08',
 PART_NUMBER='CS31002FB08',
 VALUE='10K',
 PRIM_FILE='./archive_libs/logical/q_res/chips/chips.prt';

PART_NAME
 R1397 'Q_RES_0201LF-1K,1%,1/20W,EMPTY,CS21001FE07':;

SECTION_NUMBER 1
 '@T6G_MB_LIB.T6G(SCH_1):PAGE408_I99@PURE_QUANTA.Q_RES(CHIPS)':
 C_PATH='@t6g_mb_lib.t6g(sch_1):page408_i99@pure_quanta.q_res(chips)',
 P_PATH='@t6g_mb_lib.t6g(sch_1):page287_i99@pure_quanta.q_res(chips)',
 PATH='I99',
 DRAWING='@T6G_MB_LIB.T6G(SCH_1):PAGE408',
 WATTAGE='1/20W',
 TOLERANCE='1%',
 MATERIAL='EMPTY',
 PHYS_PAGE='287',
 XY='(-1275,3700)',
 ROT='0',
 VER='2',
 PACK_TYPE='0201LF',
 LOCATION='R1397',
 CDS_LIB='pure_quanta',
 CDS_PART_NAME='Q_RES_0201LF-1K,1%,1/20W,EMPTY,CS21001FE07',
 PART_NUMBER='CS21001FE07',
 VALUE='1K',
 PRIM_FILE='./archive_libs/logical/q_res/chips/chips.prt';

PART_NAME
 R1398 'Q_RES_0201LF-10K,1%,1/20W,CHIP,CS31001FE17':;

SECTION_NUMBER 1
 '@T6G_MB_LIB.T6G(SCH_1):PAGE408_I98@PURE_QUANTA.Q_RES(CHIPS)':
 C_PATH='@t6g_mb_lib.t6g(sch_1):page408_i98@pure_quanta.q_res(chips)',
 P_PATH='@t6g_mb_lib.t6g(sch_1):page287_i98@pure_quanta.q_res(chips)',
 PATH='I98',
 DRAWING='@T6G_MB_LIB.T6G(SCH_1):PAGE408',
 WATTAGE='1/20W',
 TOLERANCE='1%',
 MATERIAL='CHIP',
 PHYS_PAGE='287',
 XY='(-1275,3175)',
 ROT='0',
 VER='2',
 PACK_TYPE='0201LF',
 LOCATION='R1398',
 CDS_LIB='pure_quanta',
 CDS_PART_NAME='Q_RES_0201LF-10K,1%,1/20W,CHIP,CS31001FE17',
 PART_NUMBER='CS31001FE17',
 VALUE='10K',
 PRIM_FILE='./archive_libs/logical/q_res/chips/chips.prt';

PART_NAME
 R1399 'Q_RES_0201LF-4.7K,5%,1/20W,CHIP,CS24701JE04':;

SECTION_NUMBER 1
 '@T6G_MB_LIB.T6G(SCH_1):PAGE377_I108@PURE_QUANTA.Q_RES(CHIPS)':
 C_PATH='@t6g_mb_lib.t6g(sch_1):page377_i108@pure_quanta.q_res(chips)',
 P_PATH='@t6g_mb_lib.t6g(sch_1):page185_i108@pure_quanta.q_res(chips)',
 PATH='I108',
 DRAWING='@T6G_MB_LIB.T6G(SCH_1):PAGE377',
 WATTAGE='1/20W',
 TOLERANCE='5%',
 MATERIAL='CHIP',
 PHYS_PAGE='185',
 XY='(-2400,2425)',
 ROT='0',
 VER='1',
 PACK_TYPE='0201LF',
 LOCATION='R1399',
 CDS_LIB='pure_quanta',
 CDS_PART_NAME='Q_RES_0201LF-4.7K,5%,1/20W,CHIP,CS24701JE04',
 PART_NUMBER='CS24701JE04',
 VALUE='4.7K',
 PRIM_FILE='./archive_libs/logical/q_res/chips/chips.prt';

PART_NAME
 R1400 'Q_RES_0201LF-1K,1%,1/20W,CHIP,CS21001FE07':;

SECTION_NUMBER 1
 '@T6G_MB_LIB.T6G(SCH_1):PAGE419_I84@PURE_QUANTA.Q_RES(CHIPS)':
 C_PATH='@t6g_mb_lib.t6g(sch_1):page419_i84@pure_quanta.q_res(chips)',
 P_PATH='@t6g_mb_lib.t6g(sch_1):page298_i84@pure_quanta.q_res(chips)',
 PATH='I84',
 DRAWING='@T6G_MB_LIB.T6G(SCH_1):PAGE419',
 WATTAGE='1/20W',
 TOLERANCE='1%',
 MATERIAL='CHIP',
 PHYS_PAGE='298',
 XY='(-2725,3150)',
 ROT='0',
 VER='1',
 PACK_TYPE='0201LF',
 LOCATION='R1400',
 CDS_LIB='pure_quanta',
 CDS_PART_NAME='Q_RES_0201LF-1K,1%,1/20W,CHIP,CS21001FE07',
 PART_NUMBER='CS21001FE07',
 VALUE='1K',
 PRIM_FILE='./archive_libs/logical/q_res/chips/chips.prt';

PART_NAME
 R1401 'Q_RES_0201LF-4.7K,5%,1/20W,CHIP,CS24701JE04':;

SECTION_NUMBER 1
 '@T6G_MB_LIB.T6G(SCH_1):PAGE419_I120@PURE_QUANTA.Q_RES(CHIPS)':
 C_PATH='@t6g_mb_lib.t6g(sch_1):page419_i120@pure_quanta.q_res(chips)',
 P_PATH='@t6g_mb_lib.t6g(sch_1):page298_i120@pure_quanta.q_res(chips)',
 PATH='I120',
 DRAWING='@T6G_MB_LIB.T6G(SCH_1):PAGE419',
 WATTAGE='1/20W',
 TOLERANCE='5%',
 MATERIAL='CHIP',
 PHYS_PAGE='298',
 XY='(-625,675)',
 ROT='0',
 VER='2',
 PACK_TYPE='0201LF',
 LOCATION='R1401',
 CDS_LIB='pure_quanta',
 CDS_PART_NAME='Q_RES_0201LF-4.7K,5%,1/20W,CHIP,CS24701JE04',
 PART_NUMBER='CS24701JE04',
 VALUE='4.7K',
 PRIM_FILE='./archive_libs/logical/q_res/chips/chips.prt';

PART_NAME
 R1402 'Q_RES_0201LF-4.7K,5%,1/20W,CHIP,CS24701JE04':;

SECTION_NUMBER 1
 '@T6G_MB_LIB.T6G(SCH_1):PAGE377_I109@PURE_QUANTA.Q_RES(CHIPS)':
 C_PATH='@t6g_mb_lib.t6g(sch_1):page377_i109@pure_quanta.q_res(chips)',
 P_PATH='@t6g_mb_lib.t6g(sch_1):page185_i109@pure_quanta.q_res(chips)',
 PATH='I109',
 DRAWING='@T6G_MB_LIB.T6G(SCH_1):PAGE377',
 WATTAGE='1/20W',
 TOLERANCE='5%',
 MATERIAL='CHIP',
 PHYS_PAGE='185',
 XY='(-2400,2375)',
 ROT='0',
 VER='1',
 PACK_TYPE='0201LF',
 LOCATION='R1402',
 CDS_LIB='pure_quanta',
 CDS_PART_NAME='Q_RES_0201LF-4.7K,5%,1/20W,CHIP,CS24701JE04',
 PART_NUMBER='CS24701JE04',
 VALUE='4.7K',
 PRIM_FILE='./archive_libs/logical/q_res/chips/chips.prt';

PART_NAME
 R1403 'Q_RES_0201LF-4.7K,5%,1/20W,CHIP,CS24701JE04':;

SECTION_NUMBER 1
 '@T6G_MB_LIB.T6G(SCH_1):PAGE377_I110@PURE_QUANTA.Q_RES(CHIPS)':
 C_PATH='@t6g_mb_lib.t6g(sch_1):page377_i110@pure_quanta.q_res(chips)',
 P_PATH='@t6g_mb_lib.t6g(sch_1):page185_i110@pure_quanta.q_res(chips)',
 PATH='I110',
 DRAWING='@T6G_MB_LIB.T6G(SCH_1):PAGE377',
 WATTAGE='1/20W',
 TOLERANCE='5%',
 MATERIAL='CHIP',
 PHYS_PAGE='185',
 XY='(-2400,2325)',
 ROT='0',
 VER='1',
 PACK_TYPE='0201LF',
 LOCATION='R1403',
 CDS_LIB='pure_quanta',
 CDS_PART_NAME='Q_RES_0201LF-4.7K,5%,1/20W,CHIP,CS24701JE04',
 PART_NUMBER='CS24701JE04',
 VALUE='4.7K',
 PRIM_FILE='./archive_libs/logical/q_res/chips/chips.prt';

PART_NAME
 R1404 'Q_RES_0201LF-4.7K,5%,1/20W,CHIP,CS24701JE04':;

SECTION_NUMBER 1
 '@T6G_MB_LIB.T6G(SCH_1):PAGE419_I99@PURE_QUANTA.Q_RES(CHIPS)':
 C_PATH='@t6g_mb_lib.t6g(sch_1):page419_i99@pure_quanta.q_res(chips)',
 P_PATH='@t6g_mb_lib.t6g(sch_1):page298_i99@pure_quanta.q_res(chips)',
 PATH='I99',
 DRAWING='@T6G_MB_LIB.T6G(SCH_1):PAGE419',
 WATTAGE='1/20W',
 TOLERANCE='5%',
 MATERIAL='CHIP',
 PHYS_PAGE='298',
 XY='(-2700,2200)',
 ROT='0',
 VER='1',
 PACK_TYPE='0201LF',
 LOCATION='R1404',
 CDS_LIB='pure_quanta',
 CDS_PART_NAME='Q_RES_0201LF-4.7K,5%,1/20W,CHIP,CS24701JE04',
 PART_NUMBER='CS24701JE04',
 VALUE='4.7K',
 PRIM_FILE='./archive_libs/logical/q_res/chips/chips.prt';

PART_NAME
 R1405 'Q_RES_0201LF-1K,1%,1/20W,EMPTY,CS21001FE07':;

SECTION_NUMBER 1
 '@T6G_MB_LIB.T6G(SCH_1):PAGE419_I96@PURE_QUANTA.Q_RES(CHIPS)':
 C_PATH='@t6g_mb_lib.t6g(sch_1):page419_i96@pure_quanta.q_res(chips)',
 P_PATH='@t6g_mb_lib.t6g(sch_1):page298_i96@pure_quanta.q_res(chips)',
 PATH='I96',
 DRAWING='@T6G_MB_LIB.T6G(SCH_1):PAGE419',
 WATTAGE='1/20W',
 TOLERANCE='1%',
 MATERIAL='EMPTY',
 PHYS_PAGE='298',
 XY='(-1375,3750)',
 ROT='0',
 VER='2',
 PACK_TYPE='0201LF',
 LOCATION='R1405',
 CDS_LIB='pure_quanta',
 CDS_PART_NAME='Q_RES_0201LF-1K,1%,1/20W,EMPTY,CS21001FE07',
 PART_NUMBER='CS21001FE07',
 VALUE='1K',
 PRIM_FILE='./archive_libs/logical/q_res/chips/chips.prt';

PART_NAME
 R1406 'Q_RES_0201LF-10K,1%,1/20W,CHIP,CS31001FE17':;

SECTION_NUMBER 1
 '@T6G_MB_LIB.T6G(SCH_1):PAGE419_I95@PURE_QUANTA.Q_RES(CHIPS)':
 C_PATH='@t6g_mb_lib.t6g(sch_1):page419_i95@pure_quanta.q_res(chips)',
 P_PATH='@t6g_mb_lib.t6g(sch_1):page298_i95@pure_quanta.q_res(chips)',
 PATH='I95',
 DRAWING='@T6G_MB_LIB.T6G(SCH_1):PAGE419',
 WATTAGE='1/20W',
 TOLERANCE='1%',
 MATERIAL='CHIP',
 PHYS_PAGE='298',
 XY='(-1375,3225)',
 ROT='0',
 VER='2',
 PACK_TYPE='0201LF',
 LOCATION='R1406',
 CDS_LIB='pure_quanta',
 CDS_PART_NAME='Q_RES_0201LF-10K,1%,1/20W,CHIP,CS31001FE17',
 PART_NUMBER='CS31001FE17',
 VALUE='10K',
 PRIM_FILE='./archive_libs/logical/q_res/chips/chips.prt';

PART_NAME
 R1407 'Q_RES_0201LF-4.7K,5%,1/20W,CHIP,CS24701JE04':;

SECTION_NUMBER 1
 '@T6G_MB_LIB.T6G(SCH_1):PAGE377_I111@PURE_QUANTA.Q_RES(CHIPS)':
 C_PATH='@t6g_mb_lib.t6g(sch_1):page377_i111@pure_quanta.q_res(chips)',
 P_PATH='@t6g_mb_lib.t6g(sch_1):page185_i111@pure_quanta.q_res(chips)',
 PATH='I111',
 DRAWING='@T6G_MB_LIB.T6G(SCH_1):PAGE377',
 WATTAGE='1/20W',
 TOLERANCE='5%',
 MATERIAL='CHIP',
 PHYS_PAGE='185',
 XY='(-2400,2275)',
 ROT='0',
 VER='1',
 PACK_TYPE='0201LF',
 LOCATION='R1407',
 CDS_LIB='pure_quanta',
 CDS_PART_NAME='Q_RES_0201LF-4.7K,5%,1/20W,CHIP,CS24701JE04',
 PART_NUMBER='CS24701JE04',
 VALUE='4.7K',
 PRIM_FILE='./archive_libs/logical/q_res/chips/chips.prt';

PART_NAME
 R1408 'Q_RES_0201LF-1K,1%,1/20W,CHIP,CS21001FE07':;

SECTION_NUMBER 1
 '@T6G_MB_LIB.T6G(SCH_1):PAGE430_I85@PURE_QUANTA.Q_RES(CHIPS)':
 C_PATH='@t6g_mb_lib.t6g(sch_1):page430_i85@pure_quanta.q_res(chips)',
 P_PATH='@t6g_mb_lib.t6g(sch_1):page309_i85@pure_quanta.q_res(chips)',
 PATH='I85',
 DRAWING='@T6G_MB_LIB.T6G(SCH_1):PAGE430',
 WATTAGE='1/20W',
 TOLERANCE='1%',
 MATERIAL='CHIP',
 PHYS_PAGE='309',
 XY='(-2700,3250)',
 ROT='0',
 VER='1',
 PACK_TYPE='0201LF',
 LOCATION='R1408',
 CDS_LIB='pure_quanta',
 CDS_PART_NAME='Q_RES_0201LF-1K,1%,1/20W,CHIP,CS21001FE07',
 PART_NUMBER='CS21001FE07',
 VALUE='1K',
 PRIM_FILE='./archive_libs/logical/q_res/chips/chips.prt';

PART_NAME
 R1409 'Q_RES_0201LF-4.7K,5%,1/20W,CHIP,CS24701JE04':;

SECTION_NUMBER 1
 '@T6G_MB_LIB.T6G(SCH_1):PAGE430_I117@PURE_QUANTA.Q_RES(CHIPS)':
 C_PATH='@t6g_mb_lib.t6g(sch_1):page430_i117@pure_quanta.q_res(chips)',
 P_PATH='@t6g_mb_lib.t6g(sch_1):page309_i117@pure_quanta.q_res(chips)',
 PATH='I117',
 DRAWING='@T6G_MB_LIB.T6G(SCH_1):PAGE430',
 WATTAGE='1/20W',
 TOLERANCE='5%',
 MATERIAL='CHIP',
 PHYS_PAGE='309',
 XY='(-425,750)',
 ROT='0',
 VER='2',
 PACK_TYPE='0201LF',
 LOCATION='R1409',
 CDS_LIB='pure_quanta',
 CDS_PART_NAME='Q_RES_0201LF-4.7K,5%,1/20W,CHIP,CS24701JE04',
 PART_NUMBER='CS24701JE04',
 VALUE='4.7K',
 PRIM_FILE='./archive_libs/logical/q_res/chips/chips.prt';

PART_NAME
 R1410 'Q_RES_0201LF-1K,1%,1/20W,CHIP,CS21001FE07':;

SECTION_NUMBER 1
 '@T6G_MB_LIB.T6G(SCH_1):PAGE377_I164@PURE_QUANTA.Q_RES(CHIPS)':
 C_PATH='@t6g_mb_lib.t6g(sch_1):page377_i164@pure_quanta.q_res(chips)',
 P_PATH='@t6g_mb_lib.t6g(sch_1):page185_i164@pure_quanta.q_res(chips)',
 PATH='I164',
 DRAWING='@T6G_MB_LIB.T6G(SCH_1):PAGE377',
 WATTAGE='1/20W',
 TOLERANCE='1%',
 MATERIAL='CHIP',
 PHYS_PAGE='185',
 XY='(-5725,3675)',
 ROT='0',
 VER='1',
 PACK_TYPE='0201LF',
 LOCATION='R1410',
 CDS_LIB='pure_quanta',
 CDS_PART_NAME='Q_RES_0201LF-1K,1%,1/20W,CHIP,CS21001FE07',
 PART_NUMBER='CS21001FE07',
 VALUE='1K',
 PRIM_FILE='./archive_libs/logical/q_res/chips/chips.prt';

PART_NAME
 R1411 'Q_RES_0201LF-1K,1%,1/20W,CHIP,CS21001FE07':;

SECTION_NUMBER 1
 '@T6G_MB_LIB.T6G(SCH_1):PAGE377_I165@PURE_QUANTA.Q_RES(CHIPS)':
 C_PATH='@t6g_mb_lib.t6g(sch_1):page377_i165@pure_quanta.q_res(chips)',
 P_PATH='@t6g_mb_lib.t6g(sch_1):page185_i165@pure_quanta.q_res(chips)',
 PATH='I165',
 DRAWING='@T6G_MB_LIB.T6G(SCH_1):PAGE377',
 WATTAGE='1/20W',
 TOLERANCE='1%',
 MATERIAL='CHIP',
 PHYS_PAGE='185',
 XY='(-5725,3625)',
 ROT='0',
 VER='1',
 PACK_TYPE='0201LF',
 LOCATION='R1411',
 CDS_LIB='pure_quanta',
 CDS_PART_NAME='Q_RES_0201LF-1K,1%,1/20W,CHIP,CS21001FE07',
 PART_NUMBER='CS21001FE07',
 VALUE='1K',
 PRIM_FILE='./archive_libs/logical/q_res/chips/chips.prt';

PART_NAME
 R1412 'Q_RES_0201LF-4.7K,5%,1/20W,CHIP,CS24701JE04':;

SECTION_NUMBER 1
 '@T6G_MB_LIB.T6G(SCH_1):PAGE430_I101@PURE_QUANTA.Q_RES(CHIPS)':
 C_PATH='@t6g_mb_lib.t6g(sch_1):page430_i101@pure_quanta.q_res(chips)',
 P_PATH='@t6g_mb_lib.t6g(sch_1):page309_i101@pure_quanta.q_res(chips)',
 PATH='I101',
 DRAWING='@T6G_MB_LIB.T6G(SCH_1):PAGE430',
 WATTAGE='1/20W',
 TOLERANCE='5%',
 MATERIAL='CHIP',
 PHYS_PAGE='309',
 XY='(-2675,2300)',
 ROT='0',
 VER='1',
 PACK_TYPE='0201LF',
 LOCATION='R1412',
 CDS_LIB='pure_quanta',
 CDS_PART_NAME='Q_RES_0201LF-4.7K,5%,1/20W,CHIP,CS24701JE04',
 PART_NUMBER='CS24701JE04',
 VALUE='4.7K',
 PRIM_FILE='./archive_libs/logical/q_res/chips/chips.prt';

PART_NAME
 R1413 'Q_RES_0201LF-1K,1%,1/20W,EMPTY,CS21001FE07':;

SECTION_NUMBER 1
 '@T6G_MB_LIB.T6G(SCH_1):PAGE430_I97@PURE_QUANTA.Q_RES(CHIPS)':
 C_PATH='@t6g_mb_lib.t6g(sch_1):page430_i97@pure_quanta.q_res(chips)',
 P_PATH='@t6g_mb_lib.t6g(sch_1):page309_i97@pure_quanta.q_res(chips)',
 PATH='I97',
 DRAWING='@T6G_MB_LIB.T6G(SCH_1):PAGE430',
 WATTAGE='1/20W',
 TOLERANCE='1%',
 MATERIAL='EMPTY',
 PHYS_PAGE='309',
 XY='(-1325,3775)',
 ROT='0',
 VER='2',
 PACK_TYPE='0201LF',
 LOCATION='R1413',
 CDS_LIB='pure_quanta',
 CDS_PART_NAME='Q_RES_0201LF-1K,1%,1/20W,EMPTY,CS21001FE07',
 PART_NUMBER='CS21001FE07',
 VALUE='1K',
 PRIM_FILE='./archive_libs/logical/q_res/chips/chips.prt';

PART_NAME
 R1414 'Q_RES_0201LF-10K,1%,1/20W,CHIP,CS31001FE17':;

SECTION_NUMBER 1
 '@T6G_MB_LIB.T6G(SCH_1):PAGE430_I96@PURE_QUANTA.Q_RES(CHIPS)':
 C_PATH='@t6g_mb_lib.t6g(sch_1):page430_i96@pure_quanta.q_res(chips)',
 P_PATH='@t6g_mb_lib.t6g(sch_1):page309_i96@pure_quanta.q_res(chips)',
 PATH='I96',
 DRAWING='@T6G_MB_LIB.T6G(SCH_1):PAGE430',
 WATTAGE='1/20W',
 TOLERANCE='1%',
 MATERIAL='CHIP',
 PHYS_PAGE='309',
 XY='(-1325,3250)',
 ROT='0',
 VER='2',
 PACK_TYPE='0201LF',
 LOCATION='R1414',
 CDS_LIB='pure_quanta',
 CDS_PART_NAME='Q_RES_0201LF-10K,1%,1/20W,CHIP,CS31001FE17',
 PART_NUMBER='CS31001FE17',
 VALUE='10K',
 PRIM_FILE='./archive_libs/logical/q_res/chips/chips.prt';

PART_NAME
 R1415 'Q_RES_0201LF-1K,1%,1/20W,CHIP,CS21001FE07':;

SECTION_NUMBER 1
 '@T6G_MB_LIB.T6G(SCH_1):PAGE377_I166@PURE_QUANTA.Q_RES(CHIPS)':
 C_PATH='@t6g_mb_lib.t6g(sch_1):page377_i166@pure_quanta.q_res(chips)',
 P_PATH='@t6g_mb_lib.t6g(sch_1):page185_i166@pure_quanta.q_res(chips)',
 PATH='I166',
 DRAWING='@T6G_MB_LIB.T6G(SCH_1):PAGE377',
 WATTAGE='1/20W',
 TOLERANCE='1%',
 MATERIAL='CHIP',
 PHYS_PAGE='185',
 XY='(-5725,3575)',
 ROT='0',
 VER='1',
 PACK_TYPE='0201LF',
 LOCATION='R1415',
 CDS_LIB='pure_quanta',
 CDS_PART_NAME='Q_RES_0201LF-1K,1%,1/20W,CHIP,CS21001FE07',
 PART_NUMBER='CS21001FE07',
 VALUE='1K',
 PRIM_FILE='./archive_libs/logical/q_res/chips/chips.prt';

PART_NAME
 R1416 'Q_RES_0201LF-1K,1%,1/20W,CHIP,CS21001FE07':;

SECTION_NUMBER 1
 '@T6G_MB_LIB.T6G(SCH_1):PAGE451_I102@PURE_QUANTA.Q_RES(CHIPS)':
 C_PATH='@t6g_mb_lib.t6g(sch_1):page451_i102@pure_quanta.q_res(chips)',
 P_PATH='@t6g_mb_lib.t6g(sch_1):page342_i102@pure_quanta.q_res(chips)',
 PATH='I102',
 DRAWING='@T6G_MB_LIB.T6G(SCH_1):PAGE451',
 WATTAGE='1/20W',
 TOLERANCE='1%',
 MATERIAL='CHIP',
 PHYS_PAGE='342',
 XY='(-2675,3225)',
 ROT='0',
 VER='1',
 PACK_TYPE='0201LF',
 LOCATION='R1416',
 CDS_LIB='pure_quanta',
 CDS_PART_NAME='Q_RES_0201LF-1K,1%,1/20W,CHIP,CS21001FE07',
 PART_NUMBER='CS21001FE07',
 VALUE='1K',
 PRIM_FILE='./archive_libs/logical/q_res/chips/chips.prt';

PART_NAME
 R1417 'Q_RES_0201LF-4.7K,5%,1/20W,CHIP,CS24701JE04':;

SECTION_NUMBER 1
 '@T6G_MB_LIB.T6G(SCH_1):PAGE451_I136@PURE_QUANTA.Q_RES(CHIPS)':
 C_PATH='@t6g_mb_lib.t6g(sch_1):page451_i136@pure_quanta.q_res(chips)',
 P_PATH='@t6g_mb_lib.t6g(sch_1):page342_i136@pure_quanta.q_res(chips)',
 PATH='I136',
 DRAWING='@T6G_MB_LIB.T6G(SCH_1):PAGE451',
 WATTAGE='1/20W',
 TOLERANCE='5%',
 MATERIAL='CHIP',
 PHYS_PAGE='342',
 XY='(-600,725)',
 ROT='0',
 VER='2',
 PACK_TYPE='0201LF',
 LOCATION='R1417',
 CDS_LIB='pure_quanta',
 CDS_PART_NAME='Q_RES_0201LF-4.7K,5%,1/20W,CHIP,CS24701JE04',
 PART_NUMBER='CS24701JE04',
 VALUE='4.7K',
 PRIM_FILE='./archive_libs/logical/q_res/chips/chips.prt';

PART_NAME
 R1418 'Q_RES_0201LF-1K,1%,1/20W,CHIP,CS21001FE07':;

SECTION_NUMBER 1
 '@T6G_MB_LIB.T6G(SCH_1):PAGE377_I167@PURE_QUANTA.Q_RES(CHIPS)':
 C_PATH='@t6g_mb_lib.t6g(sch_1):page377_i167@pure_quanta.q_res(chips)',
 P_PATH='@t6g_mb_lib.t6g(sch_1):page185_i167@pure_quanta.q_res(chips)',
 PATH='I167',
 DRAWING='@T6G_MB_LIB.T6G(SCH_1):PAGE377',
 WATTAGE='1/20W',
 TOLERANCE='1%',
 MATERIAL='CHIP',
 PHYS_PAGE='185',
 XY='(-5725,3525)',
 ROT='0',
 VER='1',
 PACK_TYPE='0201LF',
 LOCATION='R1418',
 CDS_LIB='pure_quanta',
 CDS_PART_NAME='Q_RES_0201LF-1K,1%,1/20W,CHIP,CS21001FE07',
 PART_NUMBER='CS21001FE07',
 VALUE='1K',
 PRIM_FILE='./archive_libs/logical/q_res/chips/chips.prt';

PART_NAME
 R1419 'Q_RES_0402LF-4.7K,5%,1/16W,CHIP,CS24702JB10':;

SECTION_NUMBER 1
 '@T6G_MB_LIB.T6G(SCH_1):PAGE141_I91@PURE_QUANTA.Q_RES(CHIPS)':
 C_PATH='@t6g_mb_lib.t6g(sch_1):page141_i91@pure_quanta.q_res(chips)',
 P_PATH='@t6g_mb_lib.t6g(sch_1):page164_i91@pure_quanta.q_res(chips)',
 PATH='I91',
 DRAWING='@T6G_MB_LIB.T6G(SCH_1):PAGE141',
 WATTAGE='1/16W',
 TOLERANCE='5%',
 MATERIAL='CHIP',
 PHYS_PAGE='164',
 XY='(-6875,2550)',
 ROT='0',
 VER='2',
 PACK_TYPE='0402LF',
 LOCATION='R1419',
 CDS_LIB='pure_quanta',
 CDS_PART_NAME='Q_RES_0402LF-4.7K,5%,1/16W,CHIP,CS24702JB10',
 PART_NUMBER='CS24702JB10',
 VALUE='4.7K',
 PRIM_FILE='./archive_libs/logical/q_res/chips/chips.prt';

PART_NAME
 R1420 'Q_RES_0201LF-1K,1%,1/20W,CHIP,CS21001FE07':;

SECTION_NUMBER 1
 '@T6G_MB_LIB.T6G(SCH_1):PAGE377_I168@PURE_QUANTA.Q_RES(CHIPS)':
 C_PATH='@t6g_mb_lib.t6g(sch_1):page377_i168@pure_quanta.q_res(chips)',
 P_PATH='@t6g_mb_lib.t6g(sch_1):page185_i168@pure_quanta.q_res(chips)',
 PATH='I168',
 DRAWING='@T6G_MB_LIB.T6G(SCH_1):PAGE377',
 WATTAGE='1/20W',
 TOLERANCE='1%',
 MATERIAL='CHIP',
 PHYS_PAGE='185',
 XY='(-5725,3475)',
 ROT='0',
 VER='1',
 PACK_TYPE='0201LF',
 LOCATION='R1420',
 CDS_LIB='pure_quanta',
 CDS_PART_NAME='Q_RES_0201LF-1K,1%,1/20W,CHIP,CS21001FE07',
 PART_NUMBER='CS21001FE07',
 VALUE='1K',
 PRIM_FILE='./archive_libs/logical/q_res/chips/chips.prt';

PART_NAME
 R1421 'Q_RES_0201LF-4.7K,5%,1/20W,CHIP,CS24701JE04':;

SECTION_NUMBER 1
 '@T6G_MB_LIB.T6G(SCH_1):PAGE451_I98@PURE_QUANTA.Q_RES(CHIPS)':
 C_PATH='@t6g_mb_lib.t6g(sch_1):page451_i98@pure_quanta.q_res(chips)',
 P_PATH='@t6g_mb_lib.t6g(sch_1):page342_i98@pure_quanta.q_res(chips)',
 PATH='I98',
 DRAWING='@T6G_MB_LIB.T6G(SCH_1):PAGE451',
 WATTAGE='1/20W',
 TOLERANCE='5%',
 MATERIAL='CHIP',
 PHYS_PAGE='342',
 XY='(-2650,2275)',
 ROT='0',
 VER='1',
 PACK_TYPE='0201LF',
 LOCATION='R1421',
 CDS_LIB='pure_quanta',
 CDS_PART_NAME='Q_RES_0201LF-4.7K,5%,1/20W,CHIP,CS24701JE04',
 PART_NUMBER='CS24701JE04',
 VALUE='4.7K',
 PRIM_FILE='./archive_libs/logical/q_res/chips/chips.prt';

PART_NAME
 R1422 'Q_RES_0402LF-100,1%,1/16W,CHIP,CS11002FB07':;

SECTION_NUMBER 1
 '@T6G_MB_LIB.T6G(SCH_1):PAGE84_I104@PURE_QUANTA.Q_RES(CHIPS)':
 C_PATH='@t6g_mb_lib.t6g(sch_1):page84_i104@pure_quanta.q_res(chips)',
 P_PATH='@t6g_mb_lib.t6g(sch_1):page85_i104@pure_quanta.q_res(chips)',
 PATH='I104',
 DRAWING='@T6G_MB_LIB.T6G(SCH_1):PAGE84',
 WATTAGE='1/16W',
 TOLERANCE='1%',
 MATERIAL='CHIP',
 PHYS_PAGE='85',
 XY='(-8650,6275)',
 ROT='2',
 VER='2',
 PACK_TYPE='0402LF',
 LOCATION='R1422',
 CDS_LIB='pure_quanta',
 CDS_PART_NAME='Q_RES_0402LF-100,1%,1/16W,CHIP,CS11002FB07',
 PART_NUMBER='CS11002FB07',
 VALUE='100',
 PRIM_FILE='./archive_libs/logical/q_res/chips/chips.prt';

PART_NAME
 R1423 'Q_RES_0402LF-0,5%,1/16W,CHIP,CS00002JB13':;

SECTION_NUMBER 1
 '@T6G_MB_LIB.T6G(SCH_1):PAGE141_I232@PURE_QUANTA.Q_RES(CHIPS)':
 C_PATH='@t6g_mb_lib.t6g(sch_1):page141_i232@pure_quanta.q_res(chips)',
 P_PATH='@t6g_mb_lib.t6g(sch_1):page164_i232@pure_quanta.q_res(chips)',
 PATH='I232',
 DRAWING='@T6G_MB_LIB.T6G(SCH_1):PAGE141',
 WATTAGE='1/16W',
 TOLERANCE='5%',
 MATERIAL='CHIP',
 PHYS_PAGE='164',
 XY='(-5825,3400)',
 ROT='0',
 VER='1',
 PACK_TYPE='0402LF',
 LOCATION='R1423',
 CDS_LIB='pure_quanta',
 CDS_PART_NAME='Q_RES_0402LF-0,5%,1/16W,CHIP,CS00002JB13',
 PART_NUMBER='CS00002JB13',
 VALUE='0',
 PRIM_FILE='./archive_libs/logical/q_res/chips/chips.prt';

PART_NAME
 R1424 'Q_RES_0402LF-2.2K,5%,1/16W,CHIP,CS22202JB07':;

SECTION_NUMBER 1
 '@T6G_MB_LIB.T6G(SCH_1):PAGE55_I292@PURE_QUANTA.Q_RES(CHIPS)':
 C_PATH='@t6g_mb_lib.t6g(sch_1):page55_i292@pure_quanta.q_res(chips)',
 P_PATH='@t6g_mb_lib.t6g(sch_1):page55_i292@pure_quanta.q_res(chips)',
 PATH='I292',
 DRAWING='@T6G_MB_LIB.T6G(SCH_1):PAGE55',
 WATTAGE='1/16W',
 TOLERANCE='5%',
 MATERIAL='CHIP',
 PHYS_PAGE='55',
 XY='(-7050,4875)',
 ROT='0',
 VER='1',
 PACK_TYPE='0402LF',
 LOCATION='R1424',
 CDS_LIB='pure_quanta',
 CDS_PART_NAME='Q_RES_0402LF-2.2K,5%,1/16W,CHIP,CS22202JB07',
 PART_NUMBER='CS22202JB07',
 VALUE='2.2K',
 PRIM_FILE='./archive_libs/logical/q_res/chips/chips.prt';

PART_NAME
 R1425 'Q_RES_0402LF-0,5%,1/16W,CHIP,CS00002JB13':;

SECTION_NUMBER 1
 '@T6G_MB_LIB.T6G(SCH_1):PAGE141_I221@PURE_QUANTA.Q_RES(CHIPS)':
 C_PATH='@t6g_mb_lib.t6g(sch_1):page141_i221@pure_quanta.q_res(chips)',
 P_PATH='@t6g_mb_lib.t6g(sch_1):page164_i221@pure_quanta.q_res(chips)',
 PATH='I221',
 DRAWING='@T6G_MB_LIB.T6G(SCH_1):PAGE141',
 WATTAGE='1/16W',
 TOLERANCE='5%',
 MATERIAL='CHIP',
 PHYS_PAGE='164',
 XY='(-3050,3450)',
 ROT='0',
 VER='1',
 PACK_TYPE='0402LF',
 LOCATION='R1425',
 CDS_LIB='pure_quanta',
 CDS_PART_NAME='Q_RES_0402LF-0,5%,1/16W,CHIP,CS00002JB13',
 PART_NUMBER='CS00002JB13',
 VALUE='0',
 PRIM_FILE='./archive_libs/logical/q_res/chips/chips.prt';

PART_NAME
 R1426 'Q_RES_0201LF-1K,1%,1/20W,EMPTY,CS21001FE07':;

SECTION_NUMBER 1
 '@T6G_MB_LIB.T6G(SCH_1):PAGE451_I114@PURE_QUANTA.Q_RES(CHIPS)':
 C_PATH='@t6g_mb_lib.t6g(sch_1):page451_i114@pure_quanta.q_res(chips)',
 P_PATH='@t6g_mb_lib.t6g(sch_1):page342_i114@pure_quanta.q_res(chips)',
 PATH='I114',
 DRAWING='@T6G_MB_LIB.T6G(SCH_1):PAGE451',
 WATTAGE='1/20W',
 TOLERANCE='1%',
 MATERIAL='EMPTY',
 PHYS_PAGE='342',
 XY='(-1500,3825)',
 ROT='0',
 VER='2',
 PACK_TYPE='0201LF',
 LOCATION='R1426',
 CDS_LIB='pure_quanta',
 CDS_PART_NAME='Q_RES_0201LF-1K,1%,1/20W,EMPTY,CS21001FE07',
 PART_NUMBER='CS21001FE07',
 VALUE='1K',
 PRIM_FILE='./archive_libs/logical/q_res/chips/chips.prt';

PART_NAME
 R1427 'Q_RES_0201LF-10K,1%,1/20W,CHIP,CS31001FE17':;

SECTION_NUMBER 1
 '@T6G_MB_LIB.T6G(SCH_1):PAGE451_I113@PURE_QUANTA.Q_RES(CHIPS)':
 C_PATH='@t6g_mb_lib.t6g(sch_1):page451_i113@pure_quanta.q_res(chips)',
 P_PATH='@t6g_mb_lib.t6g(sch_1):page342_i113@pure_quanta.q_res(chips)',
 PATH='I113',
 DRAWING='@T6G_MB_LIB.T6G(SCH_1):PAGE451',
 WATTAGE='1/20W',
 TOLERANCE='1%',
 MATERIAL='CHIP',
 PHYS_PAGE='342',
 XY='(-1500,3300)',
 ROT='0',
 VER='2',
 PACK_TYPE='0201LF',
 LOCATION='R1427',
 CDS_LIB='pure_quanta',
 CDS_PART_NAME='Q_RES_0201LF-10K,1%,1/20W,CHIP,CS31001FE17',
 PART_NUMBER='CS31001FE17',
 VALUE='10K',
 PRIM_FILE='./archive_libs/logical/q_res/chips/chips.prt';

PART_NAME
 R1428 'Q_RES_0201LF-1K,1%,1/20W,CHIP,CS21001FE07':;

SECTION_NUMBER 1
 '@T6G_MB_LIB.T6G(SCH_1):PAGE377_I169@PURE_QUANTA.Q_RES(CHIPS)':
 C_PATH='@t6g_mb_lib.t6g(sch_1):page377_i169@pure_quanta.q_res(chips)',
 P_PATH='@t6g_mb_lib.t6g(sch_1):page185_i169@pure_quanta.q_res(chips)',
 PATH='I169',
 DRAWING='@T6G_MB_LIB.T6G(SCH_1):PAGE377',
 WATTAGE='1/20W',
 TOLERANCE='1%',
 MATERIAL='CHIP',
 PHYS_PAGE='185',
 XY='(-5725,3425)',
 ROT='0',
 VER='1',
 PACK_TYPE='0201LF',
 LOCATION='R1428',
 CDS_LIB='pure_quanta',
 CDS_PART_NAME='Q_RES_0201LF-1K,1%,1/20W,CHIP,CS21001FE07',
 PART_NUMBER='CS21001FE07',
 VALUE='1K',
 PRIM_FILE='./archive_libs/logical/q_res/chips/chips.prt';

PART_NAME
 R1429 'Q_RES_0201LF-1K,1%,1/20W,CHIP,CS21001FE07':;

SECTION_NUMBER 1
 '@T6G_MB_LIB.T6G(SCH_1):PAGE462_I103@PURE_QUANTA.Q_RES(CHIPS)':
 C_PATH='@t6g_mb_lib.t6g(sch_1):page462_i103@pure_quanta.q_res(chips)',
 P_PATH='@t6g_mb_lib.t6g(sch_1):page353_i103@pure_quanta.q_res(chips)',
 PATH='I103',
 DRAWING='@T6G_MB_LIB.T6G(SCH_1):PAGE462',
 WATTAGE='1/20W',
 TOLERANCE='1%',
 MATERIAL='CHIP',
 PHYS_PAGE='353',
 XY='(-2750,3250)',
 ROT='0',
 VER='1',
 PACK_TYPE='0201LF',
 LOCATION='R1429',
 CDS_LIB='pure_quanta',
 CDS_PART_NAME='Q_RES_0201LF-1K,1%,1/20W,CHIP,CS21001FE07',
 PART_NUMBER='CS21001FE07',
 VALUE='1K',
 PRIM_FILE='./archive_libs/logical/q_res/chips/chips.prt';

PART_NAME
 R1430 'Q_RES_0201LF-4.7K,5%,1/20W,CHIP,CS24701JE04':;

SECTION_NUMBER 1
 '@T6G_MB_LIB.T6G(SCH_1):PAGE462_I136@PURE_QUANTA.Q_RES(CHIPS)':
 C_PATH='@t6g_mb_lib.t6g(sch_1):page462_i136@pure_quanta.q_res(chips)',
 P_PATH='@t6g_mb_lib.t6g(sch_1):page353_i136@pure_quanta.q_res(chips)',
 PATH='I136',
 DRAWING='@T6G_MB_LIB.T6G(SCH_1):PAGE462',
 WATTAGE='1/20W',
 TOLERANCE='5%',
 MATERIAL='CHIP',
 PHYS_PAGE='353',
 XY='(-575,725)',
 ROT='0',
 VER='2',
 PACK_TYPE='0201LF',
 LOCATION='R1430',
 CDS_LIB='pure_quanta',
 CDS_PART_NAME='Q_RES_0201LF-4.7K,5%,1/20W,CHIP,CS24701JE04',
 PART_NUMBER='CS24701JE04',
 VALUE='4.7K',
 PRIM_FILE='./archive_libs/logical/q_res/chips/chips.prt';

PART_NAME
 R1431 'Q_RES_0201LF-1K,1%,1/20W,CHIP,CS21001FE07':;

SECTION_NUMBER 1
 '@T6G_MB_LIB.T6G(SCH_1):PAGE377_I170@PURE_QUANTA.Q_RES(CHIPS)':
 C_PATH='@t6g_mb_lib.t6g(sch_1):page377_i170@pure_quanta.q_res(chips)',
 P_PATH='@t6g_mb_lib.t6g(sch_1):page185_i170@pure_quanta.q_res(chips)',
 PATH='I170',
 DRAWING='@T6G_MB_LIB.T6G(SCH_1):PAGE377',
 WATTAGE='1/20W',
 TOLERANCE='1%',
 MATERIAL='CHIP',
 PHYS_PAGE='185',
 XY='(-5725,3375)',
 ROT='0',
 VER='1',
 PACK_TYPE='0201LF',
 LOCATION='R1431',
 CDS_LIB='pure_quanta',
 CDS_PART_NAME='Q_RES_0201LF-1K,1%,1/20W,CHIP,CS21001FE07',
 PART_NUMBER='CS21001FE07',
 VALUE='1K',
 PRIM_FILE='./archive_libs/logical/q_res/chips/chips.prt';

PART_NAME
 R1432 'Q_RES_0201LF-1K,1%,1/20W,CHIP,CS21001FE07':;

SECTION_NUMBER 1
 '@T6G_MB_LIB.T6G(SCH_1):PAGE377_I171@PURE_QUANTA.Q_RES(CHIPS)':
 C_PATH='@t6g_mb_lib.t6g(sch_1):page377_i171@pure_quanta.q_res(chips)',
 P_PATH='@t6g_mb_lib.t6g(sch_1):page185_i171@pure_quanta.q_res(chips)',
 PATH='I171',
 DRAWING='@T6G_MB_LIB.T6G(SCH_1):PAGE377',
 WATTAGE='1/20W',
 TOLERANCE='1%',
 MATERIAL='CHIP',
 PHYS_PAGE='185',
 XY='(-5725,3325)',
 ROT='0',
 VER='1',
 PACK_TYPE='0201LF',
 LOCATION='R1432',
 CDS_LIB='pure_quanta',
 CDS_PART_NAME='Q_RES_0201LF-1K,1%,1/20W,CHIP,CS21001FE07',
 PART_NUMBER='CS21001FE07',
 VALUE='1K',
 PRIM_FILE='./archive_libs/logical/q_res/chips/chips.prt';

PART_NAME
 R1433 'Q_RES_0201LF-4.7K,5%,1/20W,CHIP,CS24701JE04':;

SECTION_NUMBER 1
 '@T6G_MB_LIB.T6G(SCH_1):PAGE462_I98@PURE_QUANTA.Q_RES(CHIPS)':
 C_PATH='@t6g_mb_lib.t6g(sch_1):page462_i98@pure_quanta.q_res(chips)',
 P_PATH='@t6g_mb_lib.t6g(sch_1):page353_i98@pure_quanta.q_res(chips)',
 PATH='I98',
 DRAWING='@T6G_MB_LIB.T6G(SCH_1):PAGE462',
 WATTAGE='1/20W',
 TOLERANCE='5%',
 MATERIAL='CHIP',
 PHYS_PAGE='353',
 XY='(-2725,2300)',
 ROT='0',
 VER='1',
 PACK_TYPE='0201LF',
 LOCATION='R1433',
 CDS_LIB='pure_quanta',
 CDS_PART_NAME='Q_RES_0201LF-4.7K,5%,1/20W,CHIP,CS24701JE04',
 PART_NUMBER='CS24701JE04',
 VALUE='4.7K',
 PRIM_FILE='./archive_libs/logical/q_res/chips/chips.prt';

PART_NAME
 R1434 'Q_RES_0201LF-1K,1%,1/20W,EMPTY,CS21001FE07':;

SECTION_NUMBER 1
 '@T6G_MB_LIB.T6G(SCH_1):PAGE462_I115@PURE_QUANTA.Q_RES(CHIPS)':
 C_PATH='@t6g_mb_lib.t6g(sch_1):page462_i115@pure_quanta.q_res(chips)',
 P_PATH='@t6g_mb_lib.t6g(sch_1):page353_i115@pure_quanta.q_res(chips)',
 PATH='I115',
 DRAWING='@T6G_MB_LIB.T6G(SCH_1):PAGE462',
 WATTAGE='1/20W',
 TOLERANCE='1%',
 MATERIAL='EMPTY',
 PHYS_PAGE='353',
 XY='(-1525,3725)',
 ROT='0',
 VER='2',
 PACK_TYPE='0201LF',
 LOCATION='R1434',
 CDS_LIB='pure_quanta',
 CDS_PART_NAME='Q_RES_0201LF-1K,1%,1/20W,EMPTY,CS21001FE07',
 PART_NUMBER='CS21001FE07',
 VALUE='1K',
 PRIM_FILE='./archive_libs/logical/q_res/chips/chips.prt';

PART_NAME
 R1435 'Q_RES_0201LF-10K,1%,1/20W,CHIP,CS31001FE17':;

SECTION_NUMBER 1
 '@T6G_MB_LIB.T6G(SCH_1):PAGE462_I114@PURE_QUANTA.Q_RES(CHIPS)':
 C_PATH='@t6g_mb_lib.t6g(sch_1):page462_i114@pure_quanta.q_res(chips)',
 P_PATH='@t6g_mb_lib.t6g(sch_1):page353_i114@pure_quanta.q_res(chips)',
 PATH='I114',
 DRAWING='@T6G_MB_LIB.T6G(SCH_1):PAGE462',
 WATTAGE='1/20W',
 TOLERANCE='1%',
 MATERIAL='CHIP',
 PHYS_PAGE='353',
 XY='(-1525,3200)',
 ROT='0',
 VER='2',
 PACK_TYPE='0201LF',
 LOCATION='R1435',
 CDS_LIB='pure_quanta',
 CDS_PART_NAME='Q_RES_0201LF-10K,1%,1/20W,CHIP,CS31001FE17',
 PART_NUMBER='CS31001FE17',
 VALUE='10K',
 PRIM_FILE='./archive_libs/logical/q_res/chips/chips.prt';

PART_NAME
 R1436 'Q_RES_0201LF-1K,1%,1/20W,CHIP,CS21001FE07':;

SECTION_NUMBER 1
 '@T6G_MB_LIB.T6G(SCH_1):PAGE377_I173@PURE_QUANTA.Q_RES(CHIPS)':
 C_PATH='@t6g_mb_lib.t6g(sch_1):page377_i173@pure_quanta.q_res(chips)',
 P_PATH='@t6g_mb_lib.t6g(sch_1):page185_i173@pure_quanta.q_res(chips)',
 PATH='I173',
 DRAWING='@T6G_MB_LIB.T6G(SCH_1):PAGE377',
 WATTAGE='1/20W',
 TOLERANCE='1%',
 MATERIAL='CHIP',
 PHYS_PAGE='185',
 XY='(-2575,3650)',
 ROT='0',
 VER='1',
 PACK_TYPE='0201LF',
 LOCATION='R1436',
 CDS_LIB='pure_quanta',
 CDS_PART_NAME='Q_RES_0201LF-1K,1%,1/20W,CHIP,CS21001FE07',
 PART_NUMBER='CS21001FE07',
 VALUE='1K',
 PRIM_FILE='./archive_libs/logical/q_res/chips/chips.prt';

PART_NAME
 R1437 'Q_RES_0201LF-1K,1%,1/20W,CHIP,CS21001FE07':;

SECTION_NUMBER 1
 '@T6G_MB_LIB.T6G(SCH_1):PAGE377_I172@PURE_QUANTA.Q_RES(CHIPS)':
 C_PATH='@t6g_mb_lib.t6g(sch_1):page377_i172@pure_quanta.q_res(chips)',
 P_PATH='@t6g_mb_lib.t6g(sch_1):page185_i172@pure_quanta.q_res(chips)',
 PATH='I172',
 DRAWING='@T6G_MB_LIB.T6G(SCH_1):PAGE377',
 WATTAGE='1/20W',
 TOLERANCE='1%',
 MATERIAL='CHIP',
 PHYS_PAGE='185',
 XY='(-2575,3600)',
 ROT='0',
 VER='1',
 PACK_TYPE='0201LF',
 LOCATION='R1437',
 CDS_LIB='pure_quanta',
 CDS_PART_NAME='Q_RES_0201LF-1K,1%,1/20W,CHIP,CS21001FE07',
 PART_NUMBER='CS21001FE07',
 VALUE='1K',
 PRIM_FILE='./archive_libs/logical/q_res/chips/chips.prt';

PART_NAME
 R1438 'Q_RES_0201LF-4.7K,5%,1/20W,EMPTY,CS24701JE04':;

SECTION_NUMBER 1
 '@T6G_MB_LIB.T6G(SCH_1):PAGE385_I147@PURE_QUANTA.Q_RES(CHIPS)':
 C_PATH='@t6g_mb_lib.t6g(sch_1):page385_i147@pure_quanta.q_res(chips)',
 P_PATH='@t6g_mb_lib.t6g(sch_1):page276_i147@pure_quanta.q_res(chips)',
 PATH='I147',
 DRAWING='@T6G_MB_LIB.T6G(SCH_1):PAGE385',
 WATTAGE='1/20W',
 TOLERANCE='5%',
 MATERIAL='EMPTY',
 PHYS_PAGE='276',
 XY='(-1475,1450)',
 ROT='0',
 VER='2',
 PACK_TYPE='0201LF',
 LOCATION='R1438',
 CDS_LIB='pure_quanta',
 CDS_PART_NAME='Q_RES_0201LF-4.7K,5%,1/20W,EMPTY,CS24701JE04',
 PART_NUMBER='CS24701JE04',
 VALUE='4.7K',
 PRIM_FILE='./archive_libs/logical/q_res/chips/chips.prt';

PART_NAME
 R1439 'Q_RES_0201LF-4.7K,5%,1/20W,EMPTY,CS24701JE04':;

SECTION_NUMBER 1
 '@T6G_MB_LIB.T6G(SCH_1):PAGE385_I146@PURE_QUANTA.Q_RES(CHIPS)':
 C_PATH='@t6g_mb_lib.t6g(sch_1):page385_i146@pure_quanta.q_res(chips)',
 P_PATH='@t6g_mb_lib.t6g(sch_1):page276_i146@pure_quanta.q_res(chips)',
 PATH='I146',
 DRAWING='@T6G_MB_LIB.T6G(SCH_1):PAGE385',
 WATTAGE='1/20W',
 TOLERANCE='5%',
 MATERIAL='EMPTY',
 PHYS_PAGE='276',
 XY='(-1200,1450)',
 ROT='0',
 VER='2',
 PACK_TYPE='0201LF',
 LOCATION='R1439',
 CDS_LIB='pure_quanta',
 CDS_PART_NAME='Q_RES_0201LF-4.7K,5%,1/20W,EMPTY,CS24701JE04',
 PART_NUMBER='CS24701JE04',
 VALUE='4.7K',
 PRIM_FILE='./archive_libs/logical/q_res/chips/chips.prt';

PART_NAME
 R1440 'Q_RES_0402LF-100K,1%,1/16W,CHIP,CS41002FB09':;

SECTION_NUMBER 1
 '@T6G_MB_LIB.T6G(SCH_1):PAGE264_I25@PURE_QUANTA.Q_RES(CHIPS)':
 C_PATH='@t6g_mb_lib.t6g(sch_1):page264_i25@pure_quanta.q_res(chips)',
 P_PATH='@t6g_mb_lib.t6g(sch_1):page259_i25@pure_quanta.q_res(chips)',
 PATH='I25',
 DRAWING='@T6G_MB_LIB.T6G(SCH_1):PAGE264',
 BOM_COST='VR_SYSTEM',
 WATTAGE='1/16W',
 TOLERANCE='1%',
 MATERIAL='CHIP',
 PHYS_PAGE='259',
 XY='(-6175,4425)',
 ROT='0',
 VER='2',
 PACK_TYPE='0402LF',
 LOCATION='R1440',
 CDS_LIB='pure_quanta',
 CDS_PART_NAME='Q_RES_0402LF-100K,1%,1/16W,CHIP,CS41002FB09',
 PART_NUMBER='CS41002FB09',
 VALUE='100K',
 PRIM_FILE='./archive_libs/logical/q_res/chips/chips.prt';

PART_NAME
 R1441 'Q_RES_0402LF-16.9K,1%,1/16W,CHIP,CS31692FB03':;

SECTION_NUMBER 1
 '@T6G_MB_LIB.T6G(SCH_1):PAGE264_I24@PURE_QUANTA.Q_RES(CHIPS)':
 C_PATH='@t6g_mb_lib.t6g(sch_1):page264_i24@pure_quanta.q_res(chips)',
 P_PATH='@t6g_mb_lib.t6g(sch_1):page259_i24@pure_quanta.q_res(chips)',
 PATH='I24',
 DRAWING='@T6G_MB_LIB.T6G(SCH_1):PAGE264',
 BOM_COST='VR_SYSTEM',
 WATTAGE='1/16W',
 TOLERANCE='1%',
 MATERIAL='CHIP',
 PHYS_PAGE='259',
 XY='(-6175,3925)',
 ROT='0',
 VER='2',
 PACK_TYPE='0402LF',
 LOCATION='R1441',
 CDS_LIB='pure_quanta',
 CDS_PART_NAME='Q_RES_0402LF-16.9K,1%,1/16W,CHIP,CS31692FB03',
 PART_NUMBER='CS31692FB03',
 VALUE='16.9K',
 PRIM_FILE='./archive_libs/logical/q_res/chips/chips.prt';

PART_NAME
 R1442 'Q_RES_0402LF-100K,1%,1/16W,CHIP,CS41002FB09':;

SECTION_NUMBER 1
 '@T6G_MB_LIB.T6G(SCH_1):PAGE264_I30@PURE_QUANTA.Q_RES(CHIPS)':
 C_PATH='@t6g_mb_lib.t6g(sch_1):page264_i30@pure_quanta.q_res(chips)',
 P_PATH='@t6g_mb_lib.t6g(sch_1):page259_i30@pure_quanta.q_res(chips)',
 PATH='I30',
 DRAWING='@T6G_MB_LIB.T6G(SCH_1):PAGE264',
 BOM_COST='VR_SYSTEM',
 WATTAGE='1/16W',
 TOLERANCE='1%',
 MATERIAL='CHIP',
 PHYS_PAGE='259',
 XY='(-6275,5750)',
 ROT='0',
 VER='2',
 PACK_TYPE='0402LF',
 LOCATION='R1442',
 CDS_LIB='pure_quanta',
 CDS_PART_NAME='Q_RES_0402LF-100K,1%,1/16W,CHIP,CS41002FB09',
 PART_NUMBER='CS41002FB09',
 VALUE='100K',
 PRIM_FILE='./archive_libs/logical/q_res/chips/chips.prt';

PART_NAME
 R1443 'Q_RES_0402LF-16.9K,1%,1/16W,CHIP,CS31692FB03':;

SECTION_NUMBER 1
 '@T6G_MB_LIB.T6G(SCH_1):PAGE264_I27@PURE_QUANTA.Q_RES(CHIPS)':
 C_PATH='@t6g_mb_lib.t6g(sch_1):page264_i27@pure_quanta.q_res(chips)',
 P_PATH='@t6g_mb_lib.t6g(sch_1):page259_i27@pure_quanta.q_res(chips)',
 PATH='I27',
 DRAWING='@T6G_MB_LIB.T6G(SCH_1):PAGE264',
 BOM_COST='VR_SYSTEM',
 WATTAGE='1/16W',
 TOLERANCE='1%',
 MATERIAL='CHIP',
 PHYS_PAGE='259',
 XY='(-6275,5250)',
 ROT='0',
 VER='2',
 PACK_TYPE='0402LF',
 LOCATION='R1443',
 CDS_LIB='pure_quanta',
 CDS_PART_NAME='Q_RES_0402LF-16.9K,1%,1/16W,CHIP,CS31692FB03',
 PART_NUMBER='CS31692FB03',
 VALUE='16.9K',
 PRIM_FILE='./archive_libs/logical/q_res/chips/chips.prt';

PART_NAME
 R1444 'Q_RES_0402LF-130,1%,1/16W,CHIP,CS11302FB03':;

SECTION_NUMBER 1
 '@T6G_MB_LIB.T6G(SCH_1):PAGE142_I82@PURE_QUANTA.Q_RES(CHIPS)':
 C_PATH='@t6g_mb_lib.t6g(sch_1):page142_i82@pure_quanta.q_res(chips)',
 P_PATH='@t6g_mb_lib.t6g(sch_1):page165_i82@pure_quanta.q_res(chips)',
 PATH='I82',
 DRAWING='@T6G_MB_LIB.T6G(SCH_1):PAGE142',
 WATTAGE='1/16W',
 TOLERANCE='1%',
 MATERIAL='CHIP',
 PHYS_PAGE='165',
 XY='(-5550,1575)',
 ROT='0',
 VER='1',
 PACK_TYPE='0402LF',
 LOCATION='R1444',
 CDS_LIB='pure_quanta',
 CDS_PART_NAME='Q_RES_0402LF-130,1%,1/16W,CHIP,CS11302FB03',
 PART_NUMBER='CS11302FB03',
 VALUE='130',
 PRIM_FILE='./archive_libs/logical/q_res/chips/chips.prt';

PART_NAME
 R1445 'Q_RES_0201LF-1K,1%,1/20W,EMPTY,CS21001FE07':;

SECTION_NUMBER 1
 '@T6G_MB_LIB.T6G(SCH_1):PAGE385_I145@PURE_QUANTA.Q_RES(CHIPS)':
 C_PATH='@t6g_mb_lib.t6g(sch_1):page385_i145@pure_quanta.q_res(chips)',
 P_PATH='@t6g_mb_lib.t6g(sch_1):page276_i145@pure_quanta.q_res(chips)',
 PATH='I145',
 DRAWING='@T6G_MB_LIB.T6G(SCH_1):PAGE385',
 WATTAGE='1/20W',
 TOLERANCE='1%',
 MATERIAL='EMPTY',
 PHYS_PAGE='276',
 XY='(-925,1450)',
 ROT='0',
 VER='2',
 PACK_TYPE='0201LF',
 LOCATION='R1445',
 CDS_LIB='pure_quanta',
 CDS_PART_NAME='Q_RES_0201LF-1K,1%,1/20W,EMPTY,CS21001FE07',
 PART_NUMBER='CS21001FE07',
 VALUE='1K',
 PRIM_FILE='./archive_libs/logical/q_res/chips/chips.prt';

PART_NAME
 R1446 'Q_RES_0201LF-4.7K,5%,1/20W,EMPTY,CS24701JE04':;

SECTION_NUMBER 1
 '@T6G_MB_LIB.T6G(SCH_1):PAGE385_I143@PURE_QUANTA.Q_RES(CHIPS)':
 C_PATH='@t6g_mb_lib.t6g(sch_1):page385_i143@pure_quanta.q_res(chips)',
 P_PATH='@t6g_mb_lib.t6g(sch_1):page276_i143@pure_quanta.q_res(chips)',
 PATH='I143',
 DRAWING='@T6G_MB_LIB.T6G(SCH_1):PAGE385',
 WATTAGE='1/20W',
 TOLERANCE='5%',
 MATERIAL='EMPTY',
 PHYS_PAGE='276',
 XY='(-650,1475)',
 ROT='0',
 VER='2',
 PACK_TYPE='0201LF',
 LOCATION='R1446',
 CDS_LIB='pure_quanta',
 CDS_PART_NAME='Q_RES_0201LF-4.7K,5%,1/20W,EMPTY,CS24701JE04',
 PART_NUMBER='CS24701JE04',
 VALUE='4.7K',
 PRIM_FILE='./archive_libs/logical/q_res/chips/chips.prt';

PART_NAME
 R1447 'Q_RES_0402LF-0,5%,1/16W,CHIP,CS00002JB13':;

SECTION_NUMBER 1
 '@T6G_MB_LIB.T6G(SCH_1):PAGE349_I57@PURE_QUANTA.Q_RES(CHIPS)':
 C_PATH='@t6g_mb_lib.t6g(sch_1):page349_i57@pure_quanta.q_res(chips)',
 P_PATH='@t6g_mb_lib.t6g(sch_1):page151_i57@pure_quanta.q_res(chips)',
 PATH='I57',
 DRAWING='@T6G_MB_LIB.T6G(SCH_1):PAGE349',
 WATTAGE='1/16W',
 TOLERANCE='5%',
 MATERIAL='CHIP',
 PHYS_PAGE='151',
 XY='(500,4300)',
 ROT='2',
 VER='1',
 PACK_TYPE='0402LF',
 LOCATION='R1447',
 CDS_LIB='pure_quanta',
 CDS_PART_NAME='Q_RES_0402LF-0,5%,1/16W,CHIP,CS00002JB13',
 PART_NUMBER='CS00002JB13',
 VALUE='0',
 PRIM_FILE='./archive_libs/logical/q_res/chips/chips.prt';

PART_NAME
 R1448 'Q_RES_0201LF-1K,1%,1/20W,CHIP,CS21001FE07':;

SECTION_NUMBER 1
 '@T6G_MB_LIB.T6G(SCH_1):PAGE377_I174@PURE_QUANTA.Q_RES(CHIPS)':
 C_PATH='@t6g_mb_lib.t6g(sch_1):page377_i174@pure_quanta.q_res(chips)',
 P_PATH='@t6g_mb_lib.t6g(sch_1):page185_i174@pure_quanta.q_res(chips)',
 PATH='I174',
 DRAWING='@T6G_MB_LIB.T6G(SCH_1):PAGE377',
 WATTAGE='1/20W',
 TOLERANCE='1%',
 MATERIAL='CHIP',
 PHYS_PAGE='185',
 XY='(-2575,3550)',
 ROT='0',
 VER='1',
 PACK_TYPE='0201LF',
 LOCATION='R1448',
 CDS_LIB='pure_quanta',
 CDS_PART_NAME='Q_RES_0201LF-1K,1%,1/20W,CHIP,CS21001FE07',
 PART_NUMBER='CS21001FE07',
 VALUE='1K',
 PRIM_FILE='./archive_libs/logical/q_res/chips/chips.prt';

PART_NAME
 R1449 'Q_RES_0402LF-10K,5%,1/16W,CHIP,CS31002JB08':;

SECTION_NUMBER 1
 '@T6G_MB_LIB.T6G(SCH_1):PAGE264_I26@PURE_QUANTA.Q_RES(CHIPS)':
 C_PATH='@t6g_mb_lib.t6g(sch_1):page264_i26@pure_quanta.q_res(chips)',
 P_PATH='@t6g_mb_lib.t6g(sch_1):page259_i26@pure_quanta.q_res(chips)',
 PATH='I26',
 DRAWING='@T6G_MB_LIB.T6G(SCH_1):PAGE264',
 BOM_COST='VR_SYSTEM',
 WATTAGE='1/16W',
 TOLERANCE='5%',
 MATERIAL='CHIP',
 PHYS_PAGE='259',
 XY='(-5425,4700)',
 ROT='0',
 VER='2',
 PACK_TYPE='0402LF',
 LOCATION='R1449',
 CDS_LIB='pure_quanta',
 CDS_PART_NAME='Q_RES_0402LF-10K,5%,1/16W,CHIP,CS31002JB08',
 PART_NUMBER='CS31002JB08',
 VALUE='10K',
 PRIM_FILE='./archive_libs/logical/q_res/chips/chips.prt';

PART_NAME
 R1450 'Q_RES_0402LF-10K,5%,1/16W,CHIP,CS31002JB08':;

SECTION_NUMBER 1
 '@T6G_MB_LIB.T6G(SCH_1):PAGE264_I39@PURE_QUANTA.Q_RES(CHIPS)':
 C_PATH='@t6g_mb_lib.t6g(sch_1):page264_i39@pure_quanta.q_res(chips)',
 P_PATH='@t6g_mb_lib.t6g(sch_1):page259_i39@pure_quanta.q_res(chips)',
 PATH='I39',
 DRAWING='@T6G_MB_LIB.T6G(SCH_1):PAGE264',
 BOM_COST='VR_SYSTEM',
 WATTAGE='1/16W',
 TOLERANCE='5%',
 MATERIAL='CHIP',
 PHYS_PAGE='259',
 XY='(-5500,5975)',
 ROT='0',
 VER='2',
 PACK_TYPE='0402LF',
 LOCATION='R1450',
 CDS_LIB='pure_quanta',
 CDS_PART_NAME='Q_RES_0402LF-10K,5%,1/16W,CHIP,CS31002JB08',
 PART_NUMBER='CS31002JB08',
 VALUE='10K',
 PRIM_FILE='./archive_libs/logical/q_res/chips/chips.prt';

PART_NAME
 R1451 'Q_RES_0201LF-1K,1%,1/20W,CHIP,CS21001FE07':;

SECTION_NUMBER 1
 '@T6G_MB_LIB.T6G(SCH_1):PAGE377_I175@PURE_QUANTA.Q_RES(CHIPS)':
 C_PATH='@t6g_mb_lib.t6g(sch_1):page377_i175@pure_quanta.q_res(chips)',
 P_PATH='@t6g_mb_lib.t6g(sch_1):page185_i175@pure_quanta.q_res(chips)',
 PATH='I175',
 DRAWING='@T6G_MB_LIB.T6G(SCH_1):PAGE377',
 WATTAGE='1/20W',
 TOLERANCE='1%',
 MATERIAL='CHIP',
 PHYS_PAGE='185',
 XY='(-2575,3500)',
 ROT='0',
 VER='1',
 PACK_TYPE='0201LF',
 LOCATION='R1451',
 CDS_LIB='pure_quanta',
 CDS_PART_NAME='Q_RES_0201LF-1K,1%,1/20W,CHIP,CS21001FE07',
 PART_NUMBER='CS21001FE07',
 VALUE='1K',
 PRIM_FILE='./archive_libs/logical/q_res/chips/chips.prt';

PART_NAME
 R1452 'Q_RES_0402LF-10K,5%,1/16W,CHIP,CS31002JB08':;

SECTION_NUMBER 1
 '@T6G_MB_LIB.T6G(SCH_1):PAGE264_I43@PURE_QUANTA.Q_RES(CHIPS)':
 C_PATH='@t6g_mb_lib.t6g(sch_1):page264_i43@pure_quanta.q_res(chips)',
 P_PATH='@t6g_mb_lib.t6g(sch_1):page259_i43@pure_quanta.q_res(chips)',
 PATH='I43',
 DRAWING='@T6G_MB_LIB.T6G(SCH_1):PAGE264',
 BOM_COST='VR_SYSTEM',
 WATTAGE='1/16W',
 TOLERANCE='5%',
 MATERIAL='CHIP',
 PHYS_PAGE='259',
 XY='(-4325,4650)',
 ROT='0',
 VER='2',
 PACK_TYPE='0402LF',
 LOCATION='R1452',
 CDS_LIB='pure_quanta',
 CDS_PART_NAME='Q_RES_0402LF-10K,5%,1/16W,CHIP,CS31002JB08',
 PART_NUMBER='CS31002JB08',
 VALUE='10K',
 PRIM_FILE='./archive_libs/logical/q_res/chips/chips.prt';

PART_NAME
 R1453 'Q_RES_0402LF-0,5%,1/16W,CHIP,CS00002JB13':;

SECTION_NUMBER 1
 '@T6G_MB_LIB.T6G(SCH_1):PAGE349_I56@PURE_QUANTA.Q_RES(CHIPS)':
 C_PATH='@t6g_mb_lib.t6g(sch_1):page349_i56@pure_quanta.q_res(chips)',
 P_PATH='@t6g_mb_lib.t6g(sch_1):page151_i56@pure_quanta.q_res(chips)',
 PATH='I56',
 DRAWING='@T6G_MB_LIB.T6G(SCH_1):PAGE349',
 WATTAGE='1/16W',
 TOLERANCE='5%',
 MATERIAL='CHIP',
 PHYS_PAGE='151',
 XY='(500,4200)',
 ROT='2',
 VER='1',
 PACK_TYPE='0402LF',
 LOCATION='R1453',
 CDS_LIB='pure_quanta',
 CDS_PART_NAME='Q_RES_0402LF-0,5%,1/16W,CHIP,CS00002JB13',
 PART_NUMBER='CS00002JB13',
 VALUE='0',
 PRIM_FILE='./archive_libs/logical/q_res/chips/chips.prt';

PART_NAME
 R1454 'Q_RES_0201LF-4.7K,5%,1/20W,EMPTY,CS24701JE04':;

SECTION_NUMBER 1
 '@T6G_MB_LIB.T6G(SCH_1):PAGE392_I145@PURE_QUANTA.Q_RES(CHIPS)':
 C_PATH='@t6g_mb_lib.t6g(sch_1):page392_i145@pure_quanta.q_res(chips)',
 P_PATH='@t6g_mb_lib.t6g(sch_1):page331_i145@pure_quanta.q_res(chips)',
 PATH='I145',
 DRAWING='@T6G_MB_LIB.T6G(SCH_1):PAGE392',
 WATTAGE='1/20W',
 TOLERANCE='5%',
 MATERIAL='EMPTY',
 PHYS_PAGE='331',
 XY='(-1475,1300)',
 ROT='0',
 VER='2',
 PACK_TYPE='0201LF',
 LOCATION='R1454',
 CDS_LIB='pure_quanta',
 CDS_PART_NAME='Q_RES_0201LF-4.7K,5%,1/20W,EMPTY,CS24701JE04',
 PART_NUMBER='CS24701JE04',
 VALUE='4.7K',
 PRIM_FILE='./archive_libs/logical/q_res/chips/chips.prt';

PART_NAME
 R1455 'Q_RES_0201LF-4.7K,5%,1/20W,EMPTY,CS24701JE04':;

SECTION_NUMBER 1
 '@T6G_MB_LIB.T6G(SCH_1):PAGE392_I146@PURE_QUANTA.Q_RES(CHIPS)':
 C_PATH='@t6g_mb_lib.t6g(sch_1):page392_i146@pure_quanta.q_res(chips)',
 P_PATH='@t6g_mb_lib.t6g(sch_1):page331_i146@pure_quanta.q_res(chips)',
 PATH='I146',
 DRAWING='@T6G_MB_LIB.T6G(SCH_1):PAGE392',
 WATTAGE='1/20W',
 TOLERANCE='5%',
 MATERIAL='EMPTY',
 PHYS_PAGE='331',
 XY='(-1200,1300)',
 ROT='0',
 VER='2',
 PACK_TYPE='0201LF',
 LOCATION='R1455',
 CDS_LIB='pure_quanta',
 CDS_PART_NAME='Q_RES_0201LF-4.7K,5%,1/20W,EMPTY,CS24701JE04',
 PART_NUMBER='CS24701JE04',
 VALUE='4.7K',
 PRIM_FILE='./archive_libs/logical/q_res/chips/chips.prt';

PART_NAME
 R1456 'Q_RES_0201LF-1K,1%,1/20W,EMPTY,CS21001FE07':;

SECTION_NUMBER 1
 '@T6G_MB_LIB.T6G(SCH_1):PAGE392_I153@PURE_QUANTA.Q_RES(CHIPS)':
 C_PATH='@t6g_mb_lib.t6g(sch_1):page392_i153@pure_quanta.q_res(chips)',
 P_PATH='@t6g_mb_lib.t6g(sch_1):page331_i153@pure_quanta.q_res(chips)',
 PATH='I153',
 DRAWING='@T6G_MB_LIB.T6G(SCH_1):PAGE392',
 WATTAGE='1/20W',
 TOLERANCE='1%',
 MATERIAL='EMPTY',
 PHYS_PAGE='331',
 XY='(-925,1300)',
 ROT='0',
 VER='2',
 PACK_TYPE='0201LF',
 LOCATION='R1456',
 CDS_LIB='pure_quanta',
 CDS_PART_NAME='Q_RES_0201LF-1K,1%,1/20W,EMPTY,CS21001FE07',
 PART_NUMBER='CS21001FE07',
 VALUE='1K',
 PRIM_FILE='./archive_libs/logical/q_res/chips/chips.prt';

PART_NAME
 R1457 'Q_RES_0402LF-10K,5%,1/16W,CHIP,CS31002JB08':;

SECTION_NUMBER 1
 '@T6G_MB_LIB.T6G(SCH_1):PAGE264_I41@PURE_QUANTA.Q_RES(CHIPS)':
 C_PATH='@t6g_mb_lib.t6g(sch_1):page264_i41@pure_quanta.q_res(chips)',
 P_PATH='@t6g_mb_lib.t6g(sch_1):page259_i41@pure_quanta.q_res(chips)',
 PATH='I41',
 DRAWING='@T6G_MB_LIB.T6G(SCH_1):PAGE264',
 BOM_COST='VR_SYSTEM',
 WATTAGE='1/16W',
 TOLERANCE='5%',
 MATERIAL='CHIP',
 PHYS_PAGE='259',
 XY='(-4425,5950)',
 ROT='0',
 VER='2',
 PACK_TYPE='0402LF',
 LOCATION='R1457',
 CDS_LIB='pure_quanta',
 CDS_PART_NAME='Q_RES_0402LF-10K,5%,1/16W,CHIP,CS31002JB08',
 PART_NUMBER='CS31002JB08',
 VALUE='10K',
 PRIM_FILE='./archive_libs/logical/q_res/chips/chips.prt';

PART_NAME
 R1458 'Q_RES_0402LF-33,5%,1/16W,CHIP,CS03302JB10':;

SECTION_NUMBER 1
 '@T6G_MB_LIB.T6G(SCH_1):PAGE264_I6@PURE_QUANTA.Q_RES(CHIPS)':
 C_PATH='@t6g_mb_lib.t6g(sch_1):page264_i6@pure_quanta.q_res(chips)',
 P_PATH='@t6g_mb_lib.t6g(sch_1):page259_i6@pure_quanta.q_res(chips)',
 PATH='I6',
 DRAWING='@T6G_MB_LIB.T6G(SCH_1):PAGE264',
 BOM_COST='OCP3.0 ',
 WATTAGE='1/16W',
 TOLERANCE='5%',
 MATERIAL='CHIP',
 PHYS_PAGE='259',
 XY='(-5475,2175)',
 ROT='0',
 VER='1',
 PACK_TYPE='0402LF',
 LOCATION='R1458',
 CDS_LIB='pure_quanta',
 CDS_PART_NAME='Q_RES_0402LF-33,5%,1/16W,CHIP,CS03302JB10',
 PART_NUMBER='CS03302JB10',
 VALUE='33',
 PRIM_FILE='./archive_libs/logical/q_res/chips/chips.prt';

PART_NAME
 R1459 'Q_RES_0402LF-33,5%,1/16W,CHIP,CS03302JB10':;

SECTION_NUMBER 1
 '@T6G_MB_LIB.T6G(SCH_1):PAGE264_I5@PURE_QUANTA.Q_RES(CHIPS)':
 C_PATH='@t6g_mb_lib.t6g(sch_1):page264_i5@pure_quanta.q_res(chips)',
 P_PATH='@t6g_mb_lib.t6g(sch_1):page259_i5@pure_quanta.q_res(chips)',
 PATH='I5',
 DRAWING='@T6G_MB_LIB.T6G(SCH_1):PAGE264',
 BOM_COST='OCP3.0 ',
 WATTAGE='1/16W',
 TOLERANCE='5%',
 MATERIAL='CHIP',
 PHYS_PAGE='259',
 XY='(-5475,2075)',
 ROT='0',
 VER='1',
 PACK_TYPE='0402LF',
 LOCATION='R1459',
 CDS_LIB='pure_quanta',
 CDS_PART_NAME='Q_RES_0402LF-33,5%,1/16W,CHIP,CS03302JB10',
 PART_NUMBER='CS03302JB10',
 VALUE='33',
 PRIM_FILE='./archive_libs/logical/q_res/chips/chips.prt';

PART_NAME
 R1460 'Q_RES_0402LF-2.2K,5%,1/16W,EMPTY,CS22202JB07':;

SECTION_NUMBER 1
 '@T6G_MB_LIB.T6G(SCH_1):PAGE349_I127@PURE_QUANTA.Q_RES(CHIPS)':
 C_PATH='@t6g_mb_lib.t6g(sch_1):page349_i127@pure_quanta.q_res(chips)',
 P_PATH='@t6g_mb_lib.t6g(sch_1):page151_i127@pure_quanta.q_res(chips)',
 PATH='I127',
 DRAWING='@T6G_MB_LIB.T6G(SCH_1):PAGE349',
 WATTAGE='1/16W',
 TOLERANCE='5%',
 MATERIAL='EMPTY',
 PHYS_PAGE='151',
 XY='(4275,3725)',
 ROT='0',
 VER='1',
 PACK_TYPE='0402LF',
 LOCATION='R1460',
 CDS_LIB='pure_quanta',
 CDS_PART_NAME='Q_RES_0402LF-2.2K,5%,1/16W,EMPTY,CS22202JB07',
 PART_NUMBER='CS22202JB07',
 VALUE='2.2K',
 PRIM_FILE='./archive_libs/logical/q_res/chips/chips.prt';

PART_NAME
 R1461 'Q_RES_0201LF-4.7K,5%,1/20W,EMPTY,CS24701JE04':;

SECTION_NUMBER 1
 '@T6G_MB_LIB.T6G(SCH_1):PAGE392_I151@PURE_QUANTA.Q_RES(CHIPS)':
 C_PATH='@t6g_mb_lib.t6g(sch_1):page392_i151@pure_quanta.q_res(chips)',
 P_PATH='@t6g_mb_lib.t6g(sch_1):page331_i151@pure_quanta.q_res(chips)',
 PATH='I151',
 DRAWING='@T6G_MB_LIB.T6G(SCH_1):PAGE392',
 WATTAGE='1/20W',
 TOLERANCE='5%',
 MATERIAL='EMPTY',
 PHYS_PAGE='331',
 XY='(-650,1325)',
 ROT='0',
 VER='2',
 PACK_TYPE='0201LF',
 LOCATION='R1461',
 CDS_LIB='pure_quanta',
 CDS_PART_NAME='Q_RES_0201LF-4.7K,5%,1/20W,EMPTY,CS24701JE04',
 PART_NUMBER='CS24701JE04',
 VALUE='4.7K',
 PRIM_FILE='./archive_libs/logical/q_res/chips/chips.prt';

PART_NAME
 R1462 'Q_RES_0201LF-1K,1%,1/20W,CHIP,CS21001FE07':;

SECTION_NUMBER 1
 '@T6G_MB_LIB.T6G(SCH_1):PAGE377_I176@PURE_QUANTA.Q_RES(CHIPS)':
 C_PATH='@t6g_mb_lib.t6g(sch_1):page377_i176@pure_quanta.q_res(chips)',
 P_PATH='@t6g_mb_lib.t6g(sch_1):page185_i176@pure_quanta.q_res(chips)',
 PATH='I176',
 DRAWING='@T6G_MB_LIB.T6G(SCH_1):PAGE377',
 WATTAGE='1/20W',
 TOLERANCE='1%',
 MATERIAL='CHIP',
 PHYS_PAGE='185',
 XY='(-2575,3450)',
 ROT='0',
 VER='1',
 PACK_TYPE='0201LF',
 LOCATION='R1462',
 CDS_LIB='pure_quanta',
 CDS_PART_NAME='Q_RES_0201LF-1K,1%,1/20W,CHIP,CS21001FE07',
 PART_NUMBER='CS21001FE07',
 VALUE='1K',
 PRIM_FILE='./archive_libs/logical/q_res/chips/chips.prt';

PART_NAME
 R1463 'Q_RES_0201LF-1K,1%,1/20W,CHIP,CS21001FE07':;

SECTION_NUMBER 1
 '@T6G_MB_LIB.T6G(SCH_1):PAGE377_I177@PURE_QUANTA.Q_RES(CHIPS)':
 C_PATH='@t6g_mb_lib.t6g(sch_1):page377_i177@pure_quanta.q_res(chips)',
 P_PATH='@t6g_mb_lib.t6g(sch_1):page185_i177@pure_quanta.q_res(chips)',
 PATH='I177',
 DRAWING='@T6G_MB_LIB.T6G(SCH_1):PAGE377',
 WATTAGE='1/20W',
 TOLERANCE='1%',
 MATERIAL='CHIP',
 PHYS_PAGE='185',
 XY='(-2575,3400)',
 ROT='0',
 VER='1',
 PACK_TYPE='0201LF',
 LOCATION='R1463',
 CDS_LIB='pure_quanta',
 CDS_PART_NAME='Q_RES_0201LF-1K,1%,1/20W,CHIP,CS21001FE07',
 PART_NUMBER='CS21001FE07',
 VALUE='1K',
 PRIM_FILE='./archive_libs/logical/q_res/chips/chips.prt';

PART_NAME
 R1464 'Q_RES_0201LF-4.7K,5%,1/20W,EMPTY,CS24701JE04':;

SECTION_NUMBER 1
 '@T6G_MB_LIB.T6G(SCH_1):PAGE401_I149@PURE_QUANTA.Q_RES(CHIPS)':
 C_PATH='@t6g_mb_lib.t6g(sch_1):page401_i149@pure_quanta.q_res(chips)',
 P_PATH='@t6g_mb_lib.t6g(sch_1):page320_i149@pure_quanta.q_res(chips)',
 PATH='I149',
 DRAWING='@T6G_MB_LIB.T6G(SCH_1):PAGE401',
 WATTAGE='1/20W',
 TOLERANCE='5%',
 MATERIAL='EMPTY',
 PHYS_PAGE='320',
 XY='(-1475,1375)',
 ROT='0',
 VER='2',
 PACK_TYPE='0201LF',
 LOCATION='R1464',
 CDS_LIB='pure_quanta',
 CDS_PART_NAME='Q_RES_0201LF-4.7K,5%,1/20W,EMPTY,CS24701JE04',
 PART_NUMBER='CS24701JE04',
 VALUE='4.7K',
 PRIM_FILE='./archive_libs/logical/q_res/chips/chips.prt';

PART_NAME
 R1465 'Q_RES_0201LF-4.7K,5%,1/20W,EMPTY,CS24701JE04':;

SECTION_NUMBER 1
 '@T6G_MB_LIB.T6G(SCH_1):PAGE401_I145@PURE_QUANTA.Q_RES(CHIPS)':
 C_PATH='@t6g_mb_lib.t6g(sch_1):page401_i145@pure_quanta.q_res(chips)',
 P_PATH='@t6g_mb_lib.t6g(sch_1):page320_i145@pure_quanta.q_res(chips)',
 PATH='I145',
 DRAWING='@T6G_MB_LIB.T6G(SCH_1):PAGE401',
 WATTAGE='1/20W',
 TOLERANCE='5%',
 MATERIAL='EMPTY',
 PHYS_PAGE='320',
 XY='(-1200,1375)',
 ROT='0',
 VER='2',
 PACK_TYPE='0201LF',
 LOCATION='R1465',
 CDS_LIB='pure_quanta',
 CDS_PART_NAME='Q_RES_0201LF-4.7K,5%,1/20W,EMPTY,CS24701JE04',
 PART_NUMBER='CS24701JE04',
 VALUE='4.7K',
 PRIM_FILE='./archive_libs/logical/q_res/chips/chips.prt';

PART_NAME
 R1466 'Q_RES_0201LF-1K,1%,1/20W,EMPTY,CS21001FE07':;

SECTION_NUMBER 1
 '@T6G_MB_LIB.T6G(SCH_1):PAGE401_I146@PURE_QUANTA.Q_RES(CHIPS)':
 C_PATH='@t6g_mb_lib.t6g(sch_1):page401_i146@pure_quanta.q_res(chips)',
 P_PATH='@t6g_mb_lib.t6g(sch_1):page320_i146@pure_quanta.q_res(chips)',
 PATH='I146',
 DRAWING='@T6G_MB_LIB.T6G(SCH_1):PAGE401',
 WATTAGE='1/20W',
 TOLERANCE='1%',
 MATERIAL='EMPTY',
 PHYS_PAGE='320',
 XY='(-925,1375)',
 ROT='0',
 VER='2',
 PACK_TYPE='0201LF',
 LOCATION='R1466',
 CDS_LIB='pure_quanta',
 CDS_PART_NAME='Q_RES_0201LF-1K,1%,1/20W,EMPTY,CS21001FE07',
 PART_NUMBER='CS21001FE07',
 VALUE='1K',
 PRIM_FILE='./archive_libs/logical/q_res/chips/chips.prt';

PART_NAME
 R1467 'Q_RES_0201LF-4.7K,5%,1/20W,EMPTY,CS24701JE04':;

SECTION_NUMBER 1
 '@T6G_MB_LIB.T6G(SCH_1):PAGE401_I147@PURE_QUANTA.Q_RES(CHIPS)':
 C_PATH='@t6g_mb_lib.t6g(sch_1):page401_i147@pure_quanta.q_res(chips)',
 P_PATH='@t6g_mb_lib.t6g(sch_1):page320_i147@pure_quanta.q_res(chips)',
 PATH='I147',
 DRAWING='@T6G_MB_LIB.T6G(SCH_1):PAGE401',
 WATTAGE='1/20W',
 TOLERANCE='5%',
 MATERIAL='EMPTY',
 PHYS_PAGE='320',
 XY='(-650,1400)',
 ROT='0',
 VER='2',
 PACK_TYPE='0201LF',
 LOCATION='R1467',
 CDS_LIB='pure_quanta',
 CDS_PART_NAME='Q_RES_0201LF-4.7K,5%,1/20W,EMPTY,CS24701JE04',
 PART_NUMBER='CS24701JE04',
 VALUE='4.7K',
 PRIM_FILE='./archive_libs/logical/q_res/chips/chips.prt';

PART_NAME
 R1468 'Q_RES_0201LF-1K,1%,1/20W,CHIP,CS21001FE07':;

SECTION_NUMBER 1
 '@T6G_MB_LIB.T6G(SCH_1):PAGE377_I178@PURE_QUANTA.Q_RES(CHIPS)':
 C_PATH='@t6g_mb_lib.t6g(sch_1):page377_i178@pure_quanta.q_res(chips)',
 P_PATH='@t6g_mb_lib.t6g(sch_1):page185_i178@pure_quanta.q_res(chips)',
 PATH='I178',
 DRAWING='@T6G_MB_LIB.T6G(SCH_1):PAGE377',
 WATTAGE='1/20W',
 TOLERANCE='1%',
 MATERIAL='CHIP',
 PHYS_PAGE='185',
 XY='(-2575,3350)',
 ROT='0',
 VER='1',
 PACK_TYPE='0201LF',
 LOCATION='R1468',
 CDS_LIB='pure_quanta',
 CDS_PART_NAME='Q_RES_0201LF-1K,1%,1/20W,CHIP,CS21001FE07',
 PART_NUMBER='CS21001FE07',
 VALUE='1K',
 PRIM_FILE='./archive_libs/logical/q_res/chips/chips.prt';

PART_NAME
 R1469 'Q_RES_0201LF-1K,1%,1/20W,CHIP,CS21001FE07':;

SECTION_NUMBER 1
 '@T6G_MB_LIB.T6G(SCH_1):PAGE377_I179@PURE_QUANTA.Q_RES(CHIPS)':
 C_PATH='@t6g_mb_lib.t6g(sch_1):page377_i179@pure_quanta.q_res(chips)',
 P_PATH='@t6g_mb_lib.t6g(sch_1):page185_i179@pure_quanta.q_res(chips)',
 PATH='I179',
 DRAWING='@T6G_MB_LIB.T6G(SCH_1):PAGE377',
 WATTAGE='1/20W',
 TOLERANCE='1%',
 MATERIAL='CHIP',
 PHYS_PAGE='185',
 XY='(-2575,3300)',
 ROT='0',
 VER='1',
 PACK_TYPE='0201LF',
 LOCATION='R1469',
 CDS_LIB='pure_quanta',
 CDS_PART_NAME='Q_RES_0201LF-1K,1%,1/20W,CHIP,CS21001FE07',
 PART_NUMBER='CS21001FE07',
 VALUE='1K',
 PRIM_FILE='./archive_libs/logical/q_res/chips/chips.prt';

PART_NAME
 R1470 'Q_RES_0201LF-4.7K,5%,1/20W,EMPTY,CS24701JE04':;

SECTION_NUMBER 1
 '@T6G_MB_LIB.T6G(SCH_1):PAGE408_I115@PURE_QUANTA.Q_RES(CHIPS)':
 C_PATH='@t6g_mb_lib.t6g(sch_1):page408_i115@pure_quanta.q_res(chips)',
 P_PATH='@t6g_mb_lib.t6g(sch_1):page287_i115@pure_quanta.q_res(chips)',
 PATH='I115',
 DRAWING='@T6G_MB_LIB.T6G(SCH_1):PAGE408',
 WATTAGE='1/20W',
 TOLERANCE='5%',
 MATERIAL='EMPTY',
 PHYS_PAGE='287',
 XY='(-1650,1350)',
 ROT='0',
 VER='2',
 PACK_TYPE='0201LF',
 LOCATION='R1470',
 CDS_LIB='pure_quanta',
 CDS_PART_NAME='Q_RES_0201LF-4.7K,5%,1/20W,EMPTY,CS24701JE04',
 PART_NUMBER='CS24701JE04',
 VALUE='4.7K',
 PRIM_FILE='./archive_libs/logical/q_res/chips/chips.prt';

PART_NAME
 R1471 'Q_RES_0201LF-4.7K,5%,1/20W,EMPTY,CS24701JE04':;

SECTION_NUMBER 1
 '@T6G_MB_LIB.T6G(SCH_1):PAGE408_I116@PURE_QUANTA.Q_RES(CHIPS)':
 C_PATH='@t6g_mb_lib.t6g(sch_1):page408_i116@pure_quanta.q_res(chips)',
 P_PATH='@t6g_mb_lib.t6g(sch_1):page287_i116@pure_quanta.q_res(chips)',
 PATH='I116',
 DRAWING='@T6G_MB_LIB.T6G(SCH_1):PAGE408',
 WATTAGE='1/20W',
 TOLERANCE='5%',
 MATERIAL='EMPTY',
 PHYS_PAGE='287',
 XY='(-1375,1350)',
 ROT='0',
 VER='2',
 PACK_TYPE='0201LF',
 LOCATION='R1471',
 CDS_LIB='pure_quanta',
 CDS_PART_NAME='Q_RES_0201LF-4.7K,5%,1/20W,EMPTY,CS24701JE04',
 PART_NUMBER='CS24701JE04',
 VALUE='4.7K',
 PRIM_FILE='./archive_libs/logical/q_res/chips/chips.prt';

PART_NAME
 R1472 'Q_RES_0201LF-1K,1%,1/20W,EMPTY,CS21001FE07':;

SECTION_NUMBER 1
 '@T6G_MB_LIB.T6G(SCH_1):PAGE408_I121@PURE_QUANTA.Q_RES(CHIPS)':
 C_PATH='@t6g_mb_lib.t6g(sch_1):page408_i121@pure_quanta.q_res(chips)',
 P_PATH='@t6g_mb_lib.t6g(sch_1):page287_i121@pure_quanta.q_res(chips)',
 PATH='I121',
 DRAWING='@T6G_MB_LIB.T6G(SCH_1):PAGE408',
 WATTAGE='1/20W',
 TOLERANCE='1%',
 MATERIAL='EMPTY',
 PHYS_PAGE='287',
 XY='(-1100,1350)',
 ROT='0',
 VER='2',
 PACK_TYPE='0201LF',
 LOCATION='R1472',
 CDS_LIB='pure_quanta',
 CDS_PART_NAME='Q_RES_0201LF-1K,1%,1/20W,EMPTY,CS21001FE07',
 PART_NUMBER='CS21001FE07',
 VALUE='1K',
 PRIM_FILE='./archive_libs/logical/q_res/chips/chips.prt';

PART_NAME
 R1473 'Q_RES_0201LF-4.7K,5%,1/20W,EMPTY,CS24701JE04':;

SECTION_NUMBER 1
 '@T6G_MB_LIB.T6G(SCH_1):PAGE408_I122@PURE_QUANTA.Q_RES(CHIPS)':
 C_PATH='@t6g_mb_lib.t6g(sch_1):page408_i122@pure_quanta.q_res(chips)',
 P_PATH='@t6g_mb_lib.t6g(sch_1):page287_i122@pure_quanta.q_res(chips)',
 PATH='I122',
 DRAWING='@T6G_MB_LIB.T6G(SCH_1):PAGE408',
 WATTAGE='1/20W',
 TOLERANCE='5%',
 MATERIAL='EMPTY',
 PHYS_PAGE='287',
 XY='(-825,1375)',
 ROT='0',
 VER='2',
 PACK_TYPE='0201LF',
 LOCATION='R1473',
 CDS_LIB='pure_quanta',
 CDS_PART_NAME='Q_RES_0201LF-4.7K,5%,1/20W,EMPTY,CS24701JE04',
 PART_NUMBER='CS24701JE04',
 VALUE='4.7K',
 PRIM_FILE='./archive_libs/logical/q_res/chips/chips.prt';

PART_NAME
 R1474 'Q_RES_0402LF-10K,1%,1/16W,EMPTY,CS31002FB08':;

SECTION_NUMBER 1
 '@T6G_MB_LIB.T6G(SCH_1):PAGE146_I14@PURE_QUANTA.Q_RES(CHIPS)':
 C_PATH='@t6g_mb_lib.t6g(sch_1):page146_i14@pure_quanta.q_res(chips)',
 P_PATH='@t6g_mb_lib.t6g(sch_1):page169_i14@pure_quanta.q_res(chips)',
 PATH='I14',
 DRAWING='@T6G_MB_LIB.T6G(SCH_1):PAGE146',
 WATTAGE='1/16W',
 TOLERANCE='1%',
 MATERIAL='EMPTY',
 PHYS_PAGE='169',
 XY='(-5200,3950)',
 ROT='0',
 VER='2',
 PACK_TYPE='0402LF',
 LOCATION='R1474',
 CDS_LIB='pure_quanta',
 CDS_PART_NAME='Q_RES_0402LF-10K,1%,1/16W,EMPTY,CS31002FB08',
 PART_NUMBER='CS31002FB08',
 VALUE='10K',
 PRIM_FILE='./archive_libs/logical/q_res/chips/chips.prt';

PART_NAME
 R1475 'Q_RES_0402LF-10K,1%,1/16W,EMPTY,CS31002FB08':;

SECTION_NUMBER 1
 '@T6G_MB_LIB.T6G(SCH_1):PAGE146_I28@PURE_QUANTA.Q_RES(CHIPS)':
 C_PATH='@t6g_mb_lib.t6g(sch_1):page146_i28@pure_quanta.q_res(chips)',
 P_PATH='@t6g_mb_lib.t6g(sch_1):page169_i28@pure_quanta.q_res(chips)',
 PATH='I28',
 DRAWING='@T6G_MB_LIB.T6G(SCH_1):PAGE146',
 WATTAGE='1/16W',
 TOLERANCE='1%',
 MATERIAL='EMPTY',
 PHYS_PAGE='169',
 XY='(-5075,1075)',
 ROT='0',
 VER='2',
 PACK_TYPE='0402LF',
 LOCATION='R1475',
 CDS_LIB='pure_quanta',
 CDS_PART_NAME='Q_RES_0402LF-10K,1%,1/16W,EMPTY,CS31002FB08',
 PART_NUMBER='CS31002FB08',
 VALUE='10K',
 PRIM_FILE='./archive_libs/logical/q_res/chips/chips.prt';

PART_NAME
 R1476 'Q_RES_0201LF-4.7K,5%,1/20W,EMPTY,CS24701JE04':;

SECTION_NUMBER 1
 '@T6G_MB_LIB.T6G(SCH_1):PAGE419_I116@PURE_QUANTA.Q_RES(CHIPS)':
 C_PATH='@t6g_mb_lib.t6g(sch_1):page419_i116@pure_quanta.q_res(chips)',
 P_PATH='@t6g_mb_lib.t6g(sch_1):page298_i116@pure_quanta.q_res(chips)',
 PATH='I116',
 DRAWING='@T6G_MB_LIB.T6G(SCH_1):PAGE419',
 WATTAGE='1/20W',
 TOLERANCE='5%',
 MATERIAL='EMPTY',
 PHYS_PAGE='298',
 XY='(-1450,1300)',
 ROT='0',
 VER='2',
 PACK_TYPE='0201LF',
 LOCATION='R1476',
 CDS_LIB='pure_quanta',
 CDS_PART_NAME='Q_RES_0201LF-4.7K,5%,1/20W,EMPTY,CS24701JE04',
 PART_NUMBER='CS24701JE04',
 VALUE='4.7K',
 PRIM_FILE='./archive_libs/logical/q_res/chips/chips.prt';

PART_NAME
 R1477 'Q_RES_0201LF-4.7K,5%,1/20W,EMPTY,CS24701JE04':;

SECTION_NUMBER 1
 '@T6G_MB_LIB.T6G(SCH_1):PAGE419_I117@PURE_QUANTA.Q_RES(CHIPS)':
 C_PATH='@t6g_mb_lib.t6g(sch_1):page419_i117@pure_quanta.q_res(chips)',
 P_PATH='@t6g_mb_lib.t6g(sch_1):page298_i117@pure_quanta.q_res(chips)',
 PATH='I117',
 DRAWING='@T6G_MB_LIB.T6G(SCH_1):PAGE419',
 WATTAGE='1/20W',
 TOLERANCE='5%',
 MATERIAL='EMPTY',
 PHYS_PAGE='298',
 XY='(-1175,1300)',
 ROT='0',
 VER='2',
 PACK_TYPE='0201LF',
 LOCATION='R1477',
 CDS_LIB='pure_quanta',
 CDS_PART_NAME='Q_RES_0201LF-4.7K,5%,1/20W,EMPTY,CS24701JE04',
 PART_NUMBER='CS24701JE04',
 VALUE='4.7K',
 PRIM_FILE='./archive_libs/logical/q_res/chips/chips.prt';

PART_NAME
 R1478 'Q_RES_0201LF-1K,1%,1/20W,EMPTY,CS21001FE07':;

SECTION_NUMBER 1
 '@T6G_MB_LIB.T6G(SCH_1):PAGE419_I118@PURE_QUANTA.Q_RES(CHIPS)':
 C_PATH='@t6g_mb_lib.t6g(sch_1):page419_i118@pure_quanta.q_res(chips)',
 P_PATH='@t6g_mb_lib.t6g(sch_1):page298_i118@pure_quanta.q_res(chips)',
 PATH='I118',
 DRAWING='@T6G_MB_LIB.T6G(SCH_1):PAGE419',
 WATTAGE='1/20W',
 TOLERANCE='1%',
 MATERIAL='EMPTY',
 PHYS_PAGE='298',
 XY='(-900,1300)',
 ROT='0',
 VER='2',
 PACK_TYPE='0201LF',
 LOCATION='R1478',
 CDS_LIB='pure_quanta',
 CDS_PART_NAME='Q_RES_0201LF-1K,1%,1/20W,EMPTY,CS21001FE07',
 PART_NUMBER='CS21001FE07',
 VALUE='1K',
 PRIM_FILE='./archive_libs/logical/q_res/chips/chips.prt';

PART_NAME
 R1479 'Q_RES_0201LF-4.7K,5%,1/20W,EMPTY,CS24701JE04':;

SECTION_NUMBER 1
 '@T6G_MB_LIB.T6G(SCH_1):PAGE419_I121@PURE_QUANTA.Q_RES(CHIPS)':
 C_PATH='@t6g_mb_lib.t6g(sch_1):page419_i121@pure_quanta.q_res(chips)',
 P_PATH='@t6g_mb_lib.t6g(sch_1):page298_i121@pure_quanta.q_res(chips)',
 PATH='I121',
 DRAWING='@T6G_MB_LIB.T6G(SCH_1):PAGE419',
 WATTAGE='1/20W',
 TOLERANCE='5%',
 MATERIAL='EMPTY',
 PHYS_PAGE='298',
 XY='(-625,1325)',
 ROT='0',
 VER='2',
 PACK_TYPE='0201LF',
 LOCATION='R1479',
 CDS_LIB='pure_quanta',
 CDS_PART_NAME='Q_RES_0201LF-4.7K,5%,1/20W,EMPTY,CS24701JE04',
 PART_NUMBER='CS24701JE04',
 VALUE='4.7K',
 PRIM_FILE='./archive_libs/logical/q_res/chips/chips.prt';

PART_NAME
 R1480 'Q_RES_2512LF-10,1%,2W,EMPTY,CS0100AFR00':;

SECTION_NUMBER 1
 '@T6G_MB_LIB.T6G(SCH_1):PAGE146_I19@PURE_QUANTA.Q_RES(CHIPS)':
 C_PATH='@t6g_mb_lib.t6g(sch_1):page146_i19@pure_quanta.q_res(chips)',
 P_PATH='@t6g_mb_lib.t6g(sch_1):page169_i19@pure_quanta.q_res(chips)',
 PATH='I19',
 DRAWING='@T6G_MB_LIB.T6G(SCH_1):PAGE146',
 WATTAGE='2W',
 TOLERANCE='1%',
 MATERIAL='EMPTY',
 PHYS_PAGE='169',
 XY='(-4150,5350)',
 ROT='0',
 VER='2',
 PACK_TYPE='2512LF',
 LOCATION='R1480',
 CDS_LIB='pure_quanta',
 CDS_PART_NAME='Q_RES_2512LF-10,1%,2W,EMPTY,CS0100AFR00',
 PART_NUMBER='CS0100AFR00',
 VALUE='10',
 PRIM_FILE='./archive_libs/logical/q_res/chips/chips.prt';

PART_NAME
 R1481 'Q_RES_2512LF-10,1%,2W,EMPTY,CS0100AFR00':;

SECTION_NUMBER 1
 '@T6G_MB_LIB.T6G(SCH_1):PAGE146_I21@PURE_QUANTA.Q_RES(CHIPS)':
 C_PATH='@t6g_mb_lib.t6g(sch_1):page146_i21@pure_quanta.q_res(chips)',
 P_PATH='@t6g_mb_lib.t6g(sch_1):page169_i21@pure_quanta.q_res(chips)',
 PATH='I21',
 DRAWING='@T6G_MB_LIB.T6G(SCH_1):PAGE146',
 WATTAGE='2W',
 TOLERANCE='1%',
 MATERIAL='EMPTY',
 PHYS_PAGE='169',
 XY='(-4025,2475)',
 ROT='0',
 VER='2',
 PACK_TYPE='2512LF',
 LOCATION='R1481',
 CDS_LIB='pure_quanta',
 CDS_PART_NAME='Q_RES_2512LF-10,1%,2W,EMPTY,CS0100AFR00',
 PART_NUMBER='CS0100AFR00',
 VALUE='10',
 PRIM_FILE='./archive_libs/logical/q_res/chips/chips.prt';

PART_NAME
 R1482 'Q_RES_0201LF-4.7K,5%,1/20W,EMPTY,CS24701JE04':;

SECTION_NUMBER 1
 '@T6G_MB_LIB.T6G(SCH_1):PAGE430_I112@PURE_QUANTA.Q_RES(CHIPS)':
 C_PATH='@t6g_mb_lib.t6g(sch_1):page430_i112@pure_quanta.q_res(chips)',
 P_PATH='@t6g_mb_lib.t6g(sch_1):page309_i112@pure_quanta.q_res(chips)',
 PATH='I112',
 DRAWING='@T6G_MB_LIB.T6G(SCH_1):PAGE430',
 WATTAGE='1/20W',
 TOLERANCE='5%',
 MATERIAL='EMPTY',
 PHYS_PAGE='309',
 XY='(-1250,1375)',
 ROT='0',
 VER='2',
 PACK_TYPE='0201LF',
 LOCATION='R1482',
 CDS_LIB='pure_quanta',
 CDS_PART_NAME='Q_RES_0201LF-4.7K,5%,1/20W,EMPTY,CS24701JE04',
 PART_NUMBER='CS24701JE04',
 VALUE='4.7K',
 PRIM_FILE='./archive_libs/logical/q_res/chips/chips.prt';

PART_NAME
 R1483 'Q_RES_0201LF-4.7K,5%,1/20W,EMPTY,CS24701JE04':;

SECTION_NUMBER 1
 '@T6G_MB_LIB.T6G(SCH_1):PAGE430_I113@PURE_QUANTA.Q_RES(CHIPS)':
 C_PATH='@t6g_mb_lib.t6g(sch_1):page430_i113@pure_quanta.q_res(chips)',
 P_PATH='@t6g_mb_lib.t6g(sch_1):page309_i113@pure_quanta.q_res(chips)',
 PATH='I113',
 DRAWING='@T6G_MB_LIB.T6G(SCH_1):PAGE430',
 WATTAGE='1/20W',
 TOLERANCE='5%',
 MATERIAL='EMPTY',
 PHYS_PAGE='309',
 XY='(-975,1375)',
 ROT='0',
 VER='2',
 PACK_TYPE='0201LF',
 LOCATION='R1483',
 CDS_LIB='pure_quanta',
 CDS_PART_NAME='Q_RES_0201LF-4.7K,5%,1/20W,EMPTY,CS24701JE04',
 PART_NUMBER='CS24701JE04',
 VALUE='4.7K',
 PRIM_FILE='./archive_libs/logical/q_res/chips/chips.prt';

PART_NAME
 R1484 'Q_RES_0201LF-1K,1%,1/20W,EMPTY,CS21001FE07':;

SECTION_NUMBER 1
 '@T6G_MB_LIB.T6G(SCH_1):PAGE430_I118@PURE_QUANTA.Q_RES(CHIPS)':
 C_PATH='@t6g_mb_lib.t6g(sch_1):page430_i118@pure_quanta.q_res(chips)',
 P_PATH='@t6g_mb_lib.t6g(sch_1):page309_i118@pure_quanta.q_res(chips)',
 PATH='I118',
 DRAWING='@T6G_MB_LIB.T6G(SCH_1):PAGE430',
 WATTAGE='1/20W',
 TOLERANCE='1%',
 MATERIAL='EMPTY',
 PHYS_PAGE='309',
 XY='(-700,1375)',
 ROT='0',
 VER='2',
 PACK_TYPE='0201LF',
 LOCATION='R1484',
 CDS_LIB='pure_quanta',
 CDS_PART_NAME='Q_RES_0201LF-1K,1%,1/20W,EMPTY,CS21001FE07',
 PART_NUMBER='CS21001FE07',
 VALUE='1K',
 PRIM_FILE='./archive_libs/logical/q_res/chips/chips.prt';

PART_NAME
 R1485 'Q_RES_0201LF-4.7K,5%,1/20W,EMPTY,CS24701JE04':;

SECTION_NUMBER 1
 '@T6G_MB_LIB.T6G(SCH_1):PAGE430_I119@PURE_QUANTA.Q_RES(CHIPS)':
 C_PATH='@t6g_mb_lib.t6g(sch_1):page430_i119@pure_quanta.q_res(chips)',
 P_PATH='@t6g_mb_lib.t6g(sch_1):page309_i119@pure_quanta.q_res(chips)',
 PATH='I119',
 DRAWING='@T6G_MB_LIB.T6G(SCH_1):PAGE430',
 WATTAGE='1/20W',
 TOLERANCE='5%',
 MATERIAL='EMPTY',
 PHYS_PAGE='309',
 XY='(-425,1400)',
 ROT='0',
 VER='2',
 PACK_TYPE='0201LF',
 LOCATION='R1485',
 CDS_LIB='pure_quanta',
 CDS_PART_NAME='Q_RES_0201LF-4.7K,5%,1/20W,EMPTY,CS24701JE04',
 PART_NUMBER='CS24701JE04',
 VALUE='4.7K',
 PRIM_FILE='./archive_libs/logical/q_res/chips/chips.prt';

PART_NAME
 R1486 'Q_RES_0402LF-0,5%,1/16W,CHIP,CS00002JB13':
 ROOM='NIC_P3V3_BOM1';

SECTION_NUMBER 1
 '@T6G_MB_LIB.T6G(SCH_1):PAGE338_I135@PURE_QUANTA.Q_RES(CHIPS)':
 C_PATH='@t6g_mb_lib.t6g(sch_1):page338_i135@pure_quanta.q_res(chips)',
 P_PATH='@t6g_mb_lib.t6g(sch_1):page134_i135@pure_quanta.q_res(chips)',
 PATH='I135',
 DRAWING='@T6G_MB_LIB.T6G(SCH_1):PAGE338',
 WATTAGE='1/16W',
 TOLERANCE='5%',
 MATERIAL='CHIP',
 PHYS_PAGE='134',
 XY='(3275,12650)',
 ROT='0',
 VER='1',
 PACK_TYPE='0402LF',
 LOCATION='R1486',
 CDS_LIB='pure_quanta',
 CDS_PART_NAME='Q_RES_0402LF-0,5%,1/16W,CHIP,CS00002JB13',
 ROOM='NIC_P3V3_BOM1',
 PART_NUMBER='CS00002JB13',
 VALUE='0',
 PRIM_FILE='./archive_libs/logical/q_res/chips/chips.prt';

PART_NAME
 R1487 'Q_RES_0402LF-0,5%,1/16W,CHIP,CS00002JB13':
 ROOM='NIC_P3V3_BOM2';

SECTION_NUMBER 1
 '@T6G_MB_LIB.T6G(SCH_1):PAGE339_I134@PURE_QUANTA.Q_RES(CHIPS)':
 C_PATH='@t6g_mb_lib.t6g(sch_1):page339_i134@pure_quanta.q_res(chips)',
 P_PATH='@t6g_mb_lib.t6g(sch_1):page135_i134@pure_quanta.q_res(chips)',
 PATH='I134',
 DRAWING='@T6G_MB_LIB.T6G(SCH_1):PAGE339',
 WATTAGE='1/16W',
 TOLERANCE='5%',
 MATERIAL='CHIP',
 PHYS_PAGE='135',
 XY='(-4000,13325)',
 ROT='0',
 VER='1',
 PACK_TYPE='0402LF',
 LOCATION='R1487',
 CDS_LIB='pure_quanta',
 CDS_PART_NAME='Q_RES_0402LF-0,5%,1/16W,CHIP,CS00002JB13',
 ROOM='NIC_P3V3_BOM2',
 PART_NUMBER='CS00002JB13',
 VALUE='0',
 PRIM_FILE='./archive_libs/logical/q_res/chips/chips.prt';

PART_NAME
 R1488 'Q_RES_0201LF-4.7K,5%,1/20W,EMPTY,CS24701JE04':;

SECTION_NUMBER 1
 '@T6G_MB_LIB.T6G(SCH_1):PAGE451_I132@PURE_QUANTA.Q_RES(CHIPS)':
 C_PATH='@t6g_mb_lib.t6g(sch_1):page451_i132@pure_quanta.q_res(chips)',
 P_PATH='@t6g_mb_lib.t6g(sch_1):page342_i132@pure_quanta.q_res(chips)',
 PATH='I132',
 DRAWING='@T6G_MB_LIB.T6G(SCH_1):PAGE451',
 WATTAGE='1/20W',
 TOLERANCE='5%',
 MATERIAL='EMPTY',
 PHYS_PAGE='342',
 XY='(-1425,1350)',
 ROT='0',
 VER='2',
 PACK_TYPE='0201LF',
 LOCATION='R1488',
 CDS_LIB='pure_quanta',
 CDS_PART_NAME='Q_RES_0201LF-4.7K,5%,1/20W,EMPTY,CS24701JE04',
 PART_NUMBER='CS24701JE04',
 VALUE='4.7K',
 PRIM_FILE='./archive_libs/logical/q_res/chips/chips.prt';

PART_NAME
 R1489 'Q_RES_0201LF-4.7K,5%,1/20W,EMPTY,CS24701JE04':;

SECTION_NUMBER 1
 '@T6G_MB_LIB.T6G(SCH_1):PAGE451_I140@PURE_QUANTA.Q_RES(CHIPS)':
 C_PATH='@t6g_mb_lib.t6g(sch_1):page451_i140@pure_quanta.q_res(chips)',
 P_PATH='@t6g_mb_lib.t6g(sch_1):page342_i140@pure_quanta.q_res(chips)',
 PATH='I140',
 DRAWING='@T6G_MB_LIB.T6G(SCH_1):PAGE451',
 WATTAGE='1/20W',
 TOLERANCE='5%',
 MATERIAL='EMPTY',
 PHYS_PAGE='342',
 XY='(-1150,1350)',
 ROT='0',
 VER='2',
 PACK_TYPE='0201LF',
 LOCATION='R1489',
 CDS_LIB='pure_quanta',
 CDS_PART_NAME='Q_RES_0201LF-4.7K,5%,1/20W,EMPTY,CS24701JE04',
 PART_NUMBER='CS24701JE04',
 VALUE='4.7K',
 PRIM_FILE='./archive_libs/logical/q_res/chips/chips.prt';

PART_NAME
 R1490 'Q_RES_0201LF-1K,1%,1/20W,EMPTY,CS21001FE07':;

SECTION_NUMBER 1
 '@T6G_MB_LIB.T6G(SCH_1):PAGE451_I139@PURE_QUANTA.Q_RES(CHIPS)':
 C_PATH='@t6g_mb_lib.t6g(sch_1):page451_i139@pure_quanta.q_res(chips)',
 P_PATH='@t6g_mb_lib.t6g(sch_1):page342_i139@pure_quanta.q_res(chips)',
 PATH='I139',
 DRAWING='@T6G_MB_LIB.T6G(SCH_1):PAGE451',
 WATTAGE='1/20W',
 TOLERANCE='1%',
 MATERIAL='EMPTY',
 PHYS_PAGE='342',
 XY='(-875,1350)',
 ROT='0',
 VER='2',
 PACK_TYPE='0201LF',
 LOCATION='R1490',
 CDS_LIB='pure_quanta',
 CDS_PART_NAME='Q_RES_0201LF-1K,1%,1/20W,EMPTY,CS21001FE07',
 PART_NUMBER='CS21001FE07',
 VALUE='1K',
 PRIM_FILE='./archive_libs/logical/q_res/chips/chips.prt';

PART_NAME
 R1491 'Q_RES_0402LF-10K,5%,1/16W,EMPTY,CS31002JB08':;

SECTION_NUMBER 1
 '@T6G_MB_LIB.T6G(SCH_1):PAGE273_I141@PURE_QUANTA.Q_RES(CHIPS)':
 C_PATH='@t6g_mb_lib.t6g(sch_1):page273_i141@pure_quanta.q_res(chips)',
 P_PATH='@t6g_mb_lib.t6g(sch_1):page188_i141@pure_quanta.q_res(chips)',
 PATH='I141',
 DRAWING='@T6G_MB_LIB.T6G(SCH_1):PAGE273',
 SEC_TYPE='0402LF',
 WATTAGE='1/16W',
 TOLERANCE='5%',
 MATERIAL='EMPTY',
 PHYS_PAGE='188',
 XY='(-6200,2550)',
 ROT='0',
 VER='2',
 PACK_TYPE='0402LF',
 LOCATION='R1491',
 SEC='1',
 CDS_LIB='pure_quanta',
 CDS_PART_NAME='Q_RES_0402LF-10K,5%,1/16W,EMPTY,CS31002JB08',
 PART_NUMBER='CS31002JB08',
 VALUE='10K',
 PRIM_FILE='./archive_libs/logical/q_res/chips/chips.prt';

PART_NAME
 R1492 'Q_RES_0402LF-10K,5%,1/16W,CHIP,CS31002JB08':;

SECTION_NUMBER 1
 '@T6G_MB_LIB.T6G(SCH_1):PAGE273_I120@PURE_QUANTA.Q_RES(CHIPS)':
 C_PATH='@t6g_mb_lib.t6g(sch_1):page273_i120@pure_quanta.q_res(chips)',
 P_PATH='@t6g_mb_lib.t6g(sch_1):page188_i120@pure_quanta.q_res(chips)',
 PATH='I120',
 DRAWING='@T6G_MB_LIB.T6G(SCH_1):PAGE273',
 BOM_COST='VR_SYSTEM',
 WATTAGE='1/16W',
 TOLERANCE='5%',
 MATERIAL='CHIP',
 PHYS_PAGE='188',
 XY='(-5500,2725)',
 ROT='0',
 VER='2',
 PACK_TYPE='0402LF',
 LOCATION='R1492',
 CDS_LIB='pure_quanta',
 CDS_PART_NAME='Q_RES_0402LF-10K,5%,1/16W,CHIP,CS31002JB08',
 PART_NUMBER='CS31002JB08',
 VALUE='10K',
 PRIM_FILE='./archive_libs/logical/q_res/chips/chips.prt';

PART_NAME
 R1493 'Q_RES_0402LF-10K,5%,1/16W,CHIP,CS31002JB08':;

SECTION_NUMBER 1
 '@T6G_MB_LIB.T6G(SCH_1):PAGE273_I125@PURE_QUANTA.Q_RES(CHIPS)':
 C_PATH='@t6g_mb_lib.t6g(sch_1):page273_i125@pure_quanta.q_res(chips)',
 P_PATH='@t6g_mb_lib.t6g(sch_1):page188_i125@pure_quanta.q_res(chips)',
 PATH='I125',
 DRAWING='@T6G_MB_LIB.T6G(SCH_1):PAGE273',
 BOM_COST='VR_SYSTEM',
 WATTAGE='1/16W',
 TOLERANCE='5%',
 MATERIAL='CHIP',
 PHYS_PAGE='188',
 XY='(-4600,2850)',
 ROT='0',
 VER='2',
 PACK_TYPE='0402LF',
 LOCATION='R1493',
 CDS_LIB='pure_quanta',
 CDS_PART_NAME='Q_RES_0402LF-10K,5%,1/16W,CHIP,CS31002JB08',
 PART_NUMBER='CS31002JB08',
 VALUE='10K',
 PRIM_FILE='./archive_libs/logical/q_res/chips/chips.prt';

PART_NAME
 R1494 'Q_RES_0402LF-33,5%,1/16W,CHIP,CS03302JB10':;

SECTION_NUMBER 1
 '@T6G_MB_LIB.T6G(SCH_1):PAGE349_I9@PURE_QUANTA.Q_RES(CHIPS)':
 C_PATH='@t6g_mb_lib.t6g(sch_1):page349_i9@pure_quanta.q_res(chips)',
 P_PATH='@t6g_mb_lib.t6g(sch_1):page151_i9@pure_quanta.q_res(chips)',
 PATH='I9',
 DRAWING='@T6G_MB_LIB.T6G(SCH_1):PAGE349',
 WATTAGE='1/16W',
 TOLERANCE='5%',
 MATERIAL='CHIP',
 PHYS_PAGE='151',
 XY='(-525,2000)',
 ROT='0',
 VER='1',
 PACK_TYPE='0402LF',
 LOCATION='R1494',
 CDS_LIB='pure_quanta',
 CDS_PART_NAME='Q_RES_0402LF-33,5%,1/16W,CHIP,CS03302JB10',
 PART_NUMBER='CS03302JB10',
 VALUE='33',
 PRIM_FILE='./archive_libs/logical/q_res/chips/chips.prt';

PART_NAME
 R1495 'Q_RES_0402LF-33,5%,1/16W,CHIP,CS03302JB10':;

SECTION_NUMBER 1
 '@T6G_MB_LIB.T6G(SCH_1):PAGE349_I49@PURE_QUANTA.Q_RES(CHIPS)':
 C_PATH='@t6g_mb_lib.t6g(sch_1):page349_i49@pure_quanta.q_res(chips)',
 P_PATH='@t6g_mb_lib.t6g(sch_1):page151_i49@pure_quanta.q_res(chips)',
 PATH='I49',
 DRAWING='@T6G_MB_LIB.T6G(SCH_1):PAGE349',
 WATTAGE='1/16W',
 TOLERANCE='5%',
 MATERIAL='CHIP',
 PHYS_PAGE='151',
 XY='(500,1850)',
 ROT='0',
 VER='1',
 PACK_TYPE='0402LF',
 LOCATION='R1495',
 CDS_LIB='pure_quanta',
 CDS_PART_NAME='Q_RES_0402LF-33,5%,1/16W,CHIP,CS03302JB10',
 PART_NUMBER='CS03302JB10',
 VALUE='33',
 PRIM_FILE='./archive_libs/logical/q_res/chips/chips.prt';

PART_NAME
 R1496 'Q_RES_0402LF-33,5%,1/16W,CHIP,CS03302JB10':;

SECTION_NUMBER 1
 '@T6G_MB_LIB.T6G(SCH_1):PAGE349_I48@PURE_QUANTA.Q_RES(CHIPS)':
 C_PATH='@t6g_mb_lib.t6g(sch_1):page349_i48@pure_quanta.q_res(chips)',
 P_PATH='@t6g_mb_lib.t6g(sch_1):page151_i48@pure_quanta.q_res(chips)',
 PATH='I48',
 DRAWING='@T6G_MB_LIB.T6G(SCH_1):PAGE349',
 WATTAGE='1/16W',
 TOLERANCE='5%',
 MATERIAL='CHIP',
 PHYS_PAGE='151',
 XY='(500,1750)',
 ROT='0',
 VER='1',
 PACK_TYPE='0402LF',
 LOCATION='R1496',
 CDS_LIB='pure_quanta',
 CDS_PART_NAME='Q_RES_0402LF-33,5%,1/16W,CHIP,CS03302JB10',
 PART_NUMBER='CS03302JB10',
 VALUE='33',
 PRIM_FILE='./archive_libs/logical/q_res/chips/chips.prt';

PART_NAME
 R1497 'Q_RES_0402LF-33,5%,1/16W,CHIP,CS03302JB10':;

SECTION_NUMBER 1
 '@T6G_MB_LIB.T6G(SCH_1):PAGE349_I176@PURE_QUANTA.Q_RES(CHIPS)':
 C_PATH='@t6g_mb_lib.t6g(sch_1):page349_i176@pure_quanta.q_res(chips)',
 P_PATH='@t6g_mb_lib.t6g(sch_1):page151_i176@pure_quanta.q_res(chips)',
 PATH='I176',
 DRAWING='@T6G_MB_LIB.T6G(SCH_1):PAGE349',
 WATTAGE='1/16W',
 TOLERANCE='5%',
 MATERIAL='CHIP',
 PHYS_PAGE='151',
 XY='(-1650,1700)',
 ROT='0',
 VER='1',
 PACK_TYPE='0402LF',
 LOCATION='R1497',
 CDS_LIB='pure_quanta',
 CDS_PART_NAME='Q_RES_0402LF-33,5%,1/16W,CHIP,CS03302JB10',
 PART_NUMBER='CS03302JB10',
 VALUE='33',
 PRIM_FILE='./archive_libs/logical/q_res/chips/chips.prt';

PART_NAME
 R1498 'Q_RES_0402LF-33,5%,1/16W,CHIP,CS03302JB10':;

SECTION_NUMBER 1
 '@T6G_MB_LIB.T6G(SCH_1):PAGE349_I183@PURE_QUANTA.Q_RES(CHIPS)':
 C_PATH='@t6g_mb_lib.t6g(sch_1):page349_i183@pure_quanta.q_res(chips)',
 P_PATH='@t6g_mb_lib.t6g(sch_1):page151_i183@pure_quanta.q_res(chips)',
 PATH='I183',
 DRAWING='@T6G_MB_LIB.T6G(SCH_1):PAGE349',
 WATTAGE='1/16W',
 TOLERANCE='5%',
 MATERIAL='CHIP',
 PHYS_PAGE='151',
 XY='(-1650,1600)',
 ROT='0',
 VER='1',
 PACK_TYPE='0402LF',
 LOCATION='R1498',
 CDS_LIB='pure_quanta',
 CDS_PART_NAME='Q_RES_0402LF-33,5%,1/16W,CHIP,CS03302JB10',
 PART_NUMBER='CS03302JB10',
 VALUE='33',
 PRIM_FILE='./archive_libs/logical/q_res/chips/chips.prt';

PART_NAME
 R1499 'Q_RES_0201LF-4.7K,5%,1/20W,EMPTY,CS24701JE04':;

SECTION_NUMBER 1
 '@T6G_MB_LIB.T6G(SCH_1):PAGE451_I137@PURE_QUANTA.Q_RES(CHIPS)':
 C_PATH='@t6g_mb_lib.t6g(sch_1):page451_i137@pure_quanta.q_res(chips)',
 P_PATH='@t6g_mb_lib.t6g(sch_1):page342_i137@pure_quanta.q_res(chips)',
 PATH='I137',
 DRAWING='@T6G_MB_LIB.T6G(SCH_1):PAGE451',
 WATTAGE='1/20W',
 TOLERANCE='5%',
 MATERIAL='EMPTY',
 PHYS_PAGE='342',
 XY='(-600,1375)',
 ROT='0',
 VER='2',
 PACK_TYPE='0201LF',
 LOCATION='R1499',
 CDS_LIB='pure_quanta',
 CDS_PART_NAME='Q_RES_0201LF-4.7K,5%,1/20W,EMPTY,CS24701JE04',
 PART_NUMBER='CS24701JE04',
 VALUE='4.7K',
 PRIM_FILE='./archive_libs/logical/q_res/chips/chips.prt';

PART_NAME
 R1500 'Q_RES_0402LF-0,5%,1/16W,CHIP,CS00002JB13':;

SECTION_NUMBER 1
 '@T6G_MB_LIB.T6G(SCH_1):PAGE248_I43@PURE_QUANTA.Q_RES(CHIPS)':
 C_PATH='@t6g_mb_lib.t6g(sch_1):page248_i43@pure_quanta.q_res(chips)',
 P_PATH='@t6g_mb_lib.t6g(sch_1):page247_i43@pure_quanta.q_res(chips)',
 PATH='I43',
 DRAWING='@T6G_MB_LIB.T6G(SCH_1):PAGE248',
 WATTAGE='1/16W',
 TOLERANCE='5%',
 MATERIAL='CHIP',
 PHYS_PAGE='247',
 XY='(-3450,4475)',
 ROT='0',
 VER='1',
 PACK_TYPE='0402LF',
 LOCATION='R1500',
 CDS_LIB='pure_quanta',
 CDS_PART_NAME='Q_RES_0402LF-0,5%,1/16W,CHIP,CS00002JB13',
 PART_NUMBER='CS00002JB13',
 VALUE='0',
 PRIM_FILE='./archive_libs/logical/q_res/chips/chips.prt';

PART_NAME
 R1501 'Q_RES_0402LF-10K,5%,1/16W,EMPTY,CS31002JB08':;

SECTION_NUMBER 1
 '@T6G_MB_LIB.T6G(SCH_1):PAGE75_I90@PURE_QUANTA.Q_RES(CHIPS)':
 C_PATH='@t6g_mb_lib.t6g(sch_1):page75_i90@pure_quanta.q_res(chips)',
 P_PATH='@t6g_mb_lib.t6g(sch_1):page76_i90@pure_quanta.q_res(chips)',
 PATH='I90',
 DRAWING='@T6G_MB_LIB.T6G(SCH_1):PAGE75',
 WATTAGE='1/16W',
 TOLERANCE='5%',
 MATERIAL='EMPTY',
 PHYS_PAGE='76',
 XY='(-3950,5000)',
 ROT='0',
 VER='1',
 PACK_TYPE='0402LF',
 LOCATION='R1501',
 CDS_LIB='pure_quanta',
 CDS_PART_NAME='Q_RES_0402LF-10K,5%,1/16W,EMPTY,CS31002JB08',
 PART_NUMBER='CS31002JB08',
 VALUE='10K',
 PRIM_FILE='./archive_libs/logical/q_res/chips/chips.prt';

PART_NAME
 R1502 'Q_RES_0402LF-10K,5%,1/16W,CHIP,CS31002JB08':;

SECTION_NUMBER 1
 '@T6G_MB_LIB.T6G(SCH_1):PAGE75_I94@PURE_QUANTA.Q_RES(CHIPS)':
 C_PATH='@t6g_mb_lib.t6g(sch_1):page75_i94@pure_quanta.q_res(chips)',
 P_PATH='@t6g_mb_lib.t6g(sch_1):page76_i94@pure_quanta.q_res(chips)',
 PATH='I94',
 DRAWING='@T6G_MB_LIB.T6G(SCH_1):PAGE75',
 WATTAGE='1/16W',
 TOLERANCE='5%',
 MATERIAL='CHIP',
 PHYS_PAGE='76',
 XY='(-3950,4100)',
 ROT='0',
 VER='1',
 PACK_TYPE='0402LF',
 LOCATION='R1502',
 CDS_LIB='pure_quanta',
 CDS_PART_NAME='Q_RES_0402LF-10K,5%,1/16W,CHIP,CS31002JB08',
 PART_NUMBER='CS31002JB08',
 VALUE='10K',
 PRIM_FILE='./archive_libs/logical/q_res/chips/chips.prt';

PART_NAME
 R1503 'Q_RES_0402LF-30K,1%,1/16W,CHIP,CS33002FB02':;

SECTION_NUMBER 1
 '@T6G_MB_LIB.T6G(SCH_1):PAGE29_I396@PURE_QUANTA.Q_RES(CHIPS)':
 C_PATH='@t6g_mb_lib.t6g(sch_1):page29_i396@pure_quanta.q_res(chips)',
 P_PATH='@t6g_mb_lib.t6g(sch_1):page29_i396@pure_quanta.q_res(chips)',
 PATH='I396',
 DRAWING='@T6G_MB_LIB.T6G(SCH_1):PAGE29',
 WATTAGE='1/16W',
 TOLERANCE='1%',
 MATERIAL='CHIP',
 PHYS_PAGE='29',
 XY='(-7750,2375)',
 ROT='0',
 VER='1',
 PACK_TYPE='0402LF',
 LOCATION='R1503',
 CDS_LIB='pure_quanta',
 CDS_PART_NAME='Q_RES_0402LF-30K,1%,1/16W,CHIP,CS33002FB02',
 PART_NUMBER='CS33002FB02',
 VALUE='30K',
 PRIM_FILE='./archive_libs/logical/q_res/chips/chips.prt';

PART_NAME
 R1504 'Q_RES_0402LF-30K,1%,1/16W,CHIP,CS33002FB02':;

SECTION_NUMBER 1
 '@T6G_MB_LIB.T6G(SCH_1):PAGE29_I397@PURE_QUANTA.Q_RES(CHIPS)':
 C_PATH='@t6g_mb_lib.t6g(sch_1):page29_i397@pure_quanta.q_res(chips)',
 P_PATH='@t6g_mb_lib.t6g(sch_1):page29_i397@pure_quanta.q_res(chips)',
 PATH='I397',
 DRAWING='@T6G_MB_LIB.T6G(SCH_1):PAGE29',
 WATTAGE='1/16W',
 TOLERANCE='1%',
 MATERIAL='CHIP',
 PHYS_PAGE='29',
 XY='(-7750,2325)',
 ROT='0',
 VER='1',
 PACK_TYPE='0402LF',
 LOCATION='R1504',
 CDS_LIB='pure_quanta',
 CDS_PART_NAME='Q_RES_0402LF-30K,1%,1/16W,CHIP,CS33002FB02',
 PART_NUMBER='CS33002FB02',
 VALUE='30K',
 PRIM_FILE='./archive_libs/logical/q_res/chips/chips.prt';

PART_NAME
 R1505 'Q_RES_0402LF-30K,1%,1/16W,CHIP,CS33002FB02':;

SECTION_NUMBER 1
 '@T6G_MB_LIB.T6G(SCH_1):PAGE29_I398@PURE_QUANTA.Q_RES(CHIPS)':
 C_PATH='@t6g_mb_lib.t6g(sch_1):page29_i398@pure_quanta.q_res(chips)',
 P_PATH='@t6g_mb_lib.t6g(sch_1):page29_i398@pure_quanta.q_res(chips)',
 PATH='I398',
 DRAWING='@T6G_MB_LIB.T6G(SCH_1):PAGE29',
 WATTAGE='1/16W',
 TOLERANCE='1%',
 MATERIAL='CHIP',
 PHYS_PAGE='29',
 XY='(-7750,2275)',
 ROT='0',
 VER='1',
 PACK_TYPE='0402LF',
 LOCATION='R1505',
 CDS_LIB='pure_quanta',
 CDS_PART_NAME='Q_RES_0402LF-30K,1%,1/16W,CHIP,CS33002FB02',
 PART_NUMBER='CS33002FB02',
 VALUE='30K',
 PRIM_FILE='./archive_libs/logical/q_res/chips/chips.prt';

PART_NAME
 R1506 'Q_RES_0402LF-30K,1%,1/16W,CHIP,CS33002FB02':;

SECTION_NUMBER 1
 '@T6G_MB_LIB.T6G(SCH_1):PAGE29_I399@PURE_QUANTA.Q_RES(CHIPS)':
 C_PATH='@t6g_mb_lib.t6g(sch_1):page29_i399@pure_quanta.q_res(chips)',
 P_PATH='@t6g_mb_lib.t6g(sch_1):page29_i399@pure_quanta.q_res(chips)',
 PATH='I399',
 DRAWING='@T6G_MB_LIB.T6G(SCH_1):PAGE29',
 WATTAGE='1/16W',
 TOLERANCE='1%',
 MATERIAL='CHIP',
 PHYS_PAGE='29',
 XY='(-7750,2225)',
 ROT='0',
 VER='1',
 PACK_TYPE='0402LF',
 LOCATION='R1506',
 CDS_LIB='pure_quanta',
 CDS_PART_NAME='Q_RES_0402LF-30K,1%,1/16W,CHIP,CS33002FB02',
 PART_NUMBER='CS33002FB02',
 VALUE='30K',
 PRIM_FILE='./archive_libs/logical/q_res/chips/chips.prt';

PART_NAME
 R1507 'Q_RES_0402LF-1K,1%,1/16W,CHIP,CS21002FB06':;

SECTION_NUMBER 1
 '@T6G_MB_LIB.T6G(SCH_1):PAGE142_I87@PURE_QUANTA.Q_RES(CHIPS)':
 C_PATH='@t6g_mb_lib.t6g(sch_1):page142_i87@pure_quanta.q_res(chips)',
 P_PATH='@t6g_mb_lib.t6g(sch_1):page165_i87@pure_quanta.q_res(chips)',
 PATH='I87',
 DRAWING='@T6G_MB_LIB.T6G(SCH_1):PAGE142',
 WATTAGE='1/16W',
 TOLERANCE='1%',
 MATERIAL='CHIP',
 PHYS_PAGE='165',
 XY='(-2550,1500)',
 ROT='0',
 VER='2',
 PACK_TYPE='0402LF',
 LOCATION='R1507',
 CDS_LIB='pure_quanta',
 CDS_PART_NAME='Q_RES_0402LF-1K,1%,1/16W,CHIP,CS21002FB06',
 PART_NUMBER='CS21002FB06',
 VALUE='1K',
 PRIM_FILE='./archive_libs/logical/q_res/chips/chips.prt';

PART_NAME
 R1508 'Q_RES_0402LF-100,1%,1/16W,CHIP,CS11002FB07':;

SECTION_NUMBER 1
 '@T6G_MB_LIB.T6G(SCH_1):PAGE144_I6@PURE_QUANTA.Q_RES(CHIPS)':
 C_PATH='@t6g_mb_lib.t6g(sch_1):page144_i6@pure_quanta.q_res(chips)',
 P_PATH='@t6g_mb_lib.t6g(sch_1):page167_i6@pure_quanta.q_res(chips)',
 PATH='I6',
 DRAWING='@T6G_MB_LIB.T6G(SCH_1):PAGE144',
 WATTAGE='1/16W',
 TOLERANCE='1%',
 MATERIAL='CHIP',
 PHYS_PAGE='167',
 XY='(-8900,1050)',
 ROT='0',
 VER='1',
 PACK_TYPE='0402LF',
 LOCATION='R1508',
 CDS_LIB='pure_quanta',
 CDS_PART_NAME='Q_RES_0402LF-100,1%,1/16W,CHIP,CS11002FB07',
 PART_NUMBER='CS11002FB07',
 VALUE='100',
 PRIM_FILE='./archive_libs/logical/q_res/chips/chips.prt';

PART_NAME
 R1509 'Q_RES_0402LF-0,5%,1/16W,CHIP,CS00002JB13':;

SECTION_NUMBER 1
 '@T6G_MB_LIB.T6G(SCH_1):PAGE340_I96@PURE_QUANTA.Q_RES(CHIPS)':
 C_PATH='@t6g_mb_lib.t6g(sch_1):page340_i96@pure_quanta.q_res(chips)',
 P_PATH='@t6g_mb_lib.t6g(sch_1):page136_i96@pure_quanta.q_res(chips)',
 PATH='I96',
 DRAWING='@T6G_MB_LIB.T6G(SCH_1):PAGE340',
 WATTAGE='1/16W',
 TOLERANCE='5%',
 MATERIAL='CHIP',
 PHYS_PAGE='136',
 XY='(-3975,5925)',
 ROT='0',
 VER='1',
 PACK_TYPE='0402LF',
 LOCATION='R1509',
 CDS_LIB='pure_quanta',
 CDS_PART_NAME='Q_RES_0402LF-0,5%,1/16W,CHIP,CS00002JB13',
 PART_NUMBER='CS00002JB13',
 VALUE='0',
 PRIM_FILE='./archive_libs/logical/q_res/chips/chips.prt';

PART_NAME
 R1510 'Q_RES_0201LF-4.7K,5%,1/20W,EMPTY,CS24701JE04':;

SECTION_NUMBER 1
 '@T6G_MB_LIB.T6G(SCH_1):PAGE462_I139@PURE_QUANTA.Q_RES(CHIPS)':
 C_PATH='@t6g_mb_lib.t6g(sch_1):page462_i139@pure_quanta.q_res(chips)',
 P_PATH='@t6g_mb_lib.t6g(sch_1):page353_i139@pure_quanta.q_res(chips)',
 PATH='I139',
 DRAWING='@T6G_MB_LIB.T6G(SCH_1):PAGE462',
 WATTAGE='1/20W',
 TOLERANCE='5%',
 MATERIAL='EMPTY',
 PHYS_PAGE='353',
 XY='(-1400,1350)',
 ROT='0',
 VER='2',
 PACK_TYPE='0201LF',
 LOCATION='R1510',
 CDS_LIB='pure_quanta',
 CDS_PART_NAME='Q_RES_0201LF-4.7K,5%,1/20W,EMPTY,CS24701JE04',
 PART_NUMBER='CS24701JE04',
 VALUE='4.7K',
 PRIM_FILE='./archive_libs/logical/q_res/chips/chips.prt';

PART_NAME
 R1511 'Q_RES_0201LF-4.7K,5%,1/20W,EMPTY,CS24701JE04':;

SECTION_NUMBER 1
 '@T6G_MB_LIB.T6G(SCH_1):PAGE462_I132@PURE_QUANTA.Q_RES(CHIPS)':
 C_PATH='@t6g_mb_lib.t6g(sch_1):page462_i132@pure_quanta.q_res(chips)',
 P_PATH='@t6g_mb_lib.t6g(sch_1):page353_i132@pure_quanta.q_res(chips)',
 PATH='I132',
 DRAWING='@T6G_MB_LIB.T6G(SCH_1):PAGE462',
 WATTAGE='1/20W',
 TOLERANCE='5%',
 MATERIAL='EMPTY',
 PHYS_PAGE='353',
 XY='(-1125,1350)',
 ROT='0',
 VER='2',
 PACK_TYPE='0201LF',
 LOCATION='R1511',
 CDS_LIB='pure_quanta',
 CDS_PART_NAME='Q_RES_0201LF-4.7K,5%,1/20W,EMPTY,CS24701JE04',
 PART_NUMBER='CS24701JE04',
 VALUE='4.7K',
 PRIM_FILE='./archive_libs/logical/q_res/chips/chips.prt';

PART_NAME
 R1512 'Q_RES_0201LF-1K,1%,1/20W,EMPTY,CS21001FE07':;

SECTION_NUMBER 1
 '@T6G_MB_LIB.T6G(SCH_1):PAGE462_I140@PURE_QUANTA.Q_RES(CHIPS)':
 C_PATH='@t6g_mb_lib.t6g(sch_1):page462_i140@pure_quanta.q_res(chips)',
 P_PATH='@t6g_mb_lib.t6g(sch_1):page353_i140@pure_quanta.q_res(chips)',
 PATH='I140',
 DRAWING='@T6G_MB_LIB.T6G(SCH_1):PAGE462',
 WATTAGE='1/20W',
 TOLERANCE='1%',
 MATERIAL='EMPTY',
 PHYS_PAGE='353',
 XY='(-850,1350)',
 ROT='0',
 VER='2',
 PACK_TYPE='0201LF',
 LOCATION='R1512',
 CDS_LIB='pure_quanta',
 CDS_PART_NAME='Q_RES_0201LF-1K,1%,1/20W,EMPTY,CS21001FE07',
 PART_NUMBER='CS21001FE07',
 VALUE='1K',
 PRIM_FILE='./archive_libs/logical/q_res/chips/chips.prt';

PART_NAME
 R1513 'Q_RES_0201LF-4.7K,5%,1/20W,EMPTY,CS24701JE04':;

SECTION_NUMBER 1
 '@T6G_MB_LIB.T6G(SCH_1):PAGE462_I137@PURE_QUANTA.Q_RES(CHIPS)':
 C_PATH='@t6g_mb_lib.t6g(sch_1):page462_i137@pure_quanta.q_res(chips)',
 P_PATH='@t6g_mb_lib.t6g(sch_1):page353_i137@pure_quanta.q_res(chips)',
 PATH='I137',
 DRAWING='@T6G_MB_LIB.T6G(SCH_1):PAGE462',
 WATTAGE='1/20W',
 TOLERANCE='5%',
 MATERIAL='EMPTY',
 PHYS_PAGE='353',
 XY='(-575,1375)',
 ROT='0',
 VER='2',
 PACK_TYPE='0201LF',
 LOCATION='R1513',
 CDS_LIB='pure_quanta',
 CDS_PART_NAME='Q_RES_0201LF-4.7K,5%,1/20W,EMPTY,CS24701JE04',
 PART_NUMBER='CS24701JE04',
 VALUE='4.7K',
 PRIM_FILE='./archive_libs/logical/q_res/chips/chips.prt';

PART_NAME
 R1514 'Q_RES_0201LF-0,5%,1/20W,CHIP,CS00001JE10':;

SECTION_NUMBER 1
 '@T6G_MB_LIB.T6G(SCH_1):PAGE378_I118@PURE_QUANTA.Q_RES(CHIPS)':
 C_PATH='@t6g_mb_lib.t6g(sch_1):page378_i118@pure_quanta.q_res(chips)',
 P_PATH='@t6g_mb_lib.t6g(sch_1):page184_i118@pure_quanta.q_res(chips)',
 PATH='I118',
 DRAWING='@T6G_MB_LIB.T6G(SCH_1):PAGE378',
 WATTAGE='1/20W',
 TOLERANCE='5%',
 MATERIAL='CHIP',
 PHYS_PAGE='184',
 XY='(-2150,5500)',
 ROT='0',
 VER='1',
 PACK_TYPE='0201LF',
 LOCATION='R1514',
 CDS_LIB='pure_quanta',
 CDS_PART_NAME='Q_RES_0201LF-0,5%,1/20W,CHIP,CS00001JE10',
 PART_NUMBER='CS00001JE10',
 VALUE='0',
 PRIM_FILE='./archive_libs/logical/q_res/chips/chips.prt';

PART_NAME
 R1515 'Q_RES_0201LF-0,5%,1/20W,CHIP,CS00001JE10':;

SECTION_NUMBER 1
 '@T6G_MB_LIB.T6G(SCH_1):PAGE378_I117@PURE_QUANTA.Q_RES(CHIPS)':
 C_PATH='@t6g_mb_lib.t6g(sch_1):page378_i117@pure_quanta.q_res(chips)',
 P_PATH='@t6g_mb_lib.t6g(sch_1):page184_i117@pure_quanta.q_res(chips)',
 PATH='I117',
 DRAWING='@T6G_MB_LIB.T6G(SCH_1):PAGE378',
 WATTAGE='1/20W',
 TOLERANCE='5%',
 MATERIAL='CHIP',
 PHYS_PAGE='184',
 XY='(-2150,5450)',
 ROT='0',
 VER='1',
 PACK_TYPE='0201LF',
 LOCATION='R1515',
 CDS_LIB='pure_quanta',
 CDS_PART_NAME='Q_RES_0201LF-0,5%,1/20W,CHIP,CS00001JE10',
 PART_NUMBER='CS00001JE10',
 VALUE='0',
 PRIM_FILE='./archive_libs/logical/q_res/chips/chips.prt';

PART_NAME
 R1516 'Q_RES_0402LF-33.2,1%,1/16W,CHIP,CS03322FB03':;

SECTION_NUMBER 1
 '@T6G_MB_LIB.T6G(SCH_1):PAGE349_I222@PURE_QUANTA.Q_RES(CHIPS)':
 C_PATH='@t6g_mb_lib.t6g(sch_1):page349_i222@pure_quanta.q_res(chips)',
 P_PATH='@t6g_mb_lib.t6g(sch_1):page151_i222@pure_quanta.q_res(chips)',
 PATH='I222',
 DRAWING='@T6G_MB_LIB.T6G(SCH_1):PAGE349',
 WATTAGE='1/16W',
 TOLERANCE='1%',
 MATERIAL='CHIP',
 PHYS_PAGE='151',
 XY='(600,5525)',
 ROT='0',
 VER='1',
 PACK_TYPE='0402LF',
 LOCATION='R1516',
 CDS_LIB='pure_quanta',
 CDS_PART_NAME='Q_RES_0402LF-33.2,1%,1/16W,CHIP,CS03322FB03',
 PART_NUMBER='CS03322FB03',
 VALUE='33.2',
 PRIM_FILE='./archive_libs/logical/q_res/chips/chips.prt';

PART_NAME
 R1517 'Q_RES_0402LF-33.2,1%,1/16W,CHIP,CS03322FB03':;

SECTION_NUMBER 1
 '@T6G_MB_LIB.T6G(SCH_1):PAGE349_I223@PURE_QUANTA.Q_RES(CHIPS)':
 C_PATH='@t6g_mb_lib.t6g(sch_1):page349_i223@pure_quanta.q_res(chips)',
 P_PATH='@t6g_mb_lib.t6g(sch_1):page151_i223@pure_quanta.q_res(chips)',
 PATH='I223',
 DRAWING='@T6G_MB_LIB.T6G(SCH_1):PAGE349',
 WATTAGE='1/16W',
 TOLERANCE='1%',
 MATERIAL='CHIP',
 PHYS_PAGE='151',
 XY='(600,5475)',
 ROT='0',
 VER='1',
 PACK_TYPE='0402LF',
 LOCATION='R1517',
 CDS_LIB='pure_quanta',
 CDS_PART_NAME='Q_RES_0402LF-33.2,1%,1/16W,CHIP,CS03322FB03',
 PART_NUMBER='CS03322FB03',
 VALUE='33.2',
 PRIM_FILE='./archive_libs/logical/q_res/chips/chips.prt';

PART_NAME
 R1518 'Q_RES_0402LF-0,5%,1/16W,CHIP,CS00002JB13':;

SECTION_NUMBER 1
 '@T6G_MB_LIB.T6G(SCH_1):PAGE340_I102@PURE_QUANTA.Q_RES(CHIPS)':
 C_PATH='@t6g_mb_lib.t6g(sch_1):page340_i102@pure_quanta.q_res(chips)',
 P_PATH='@t6g_mb_lib.t6g(sch_1):page136_i102@pure_quanta.q_res(chips)',
 PATH='I102',
 DRAWING='@T6G_MB_LIB.T6G(SCH_1):PAGE340',
 WATTAGE='1/16W',
 TOLERANCE='5%',
 MATERIAL='CHIP',
 PHYS_PAGE='136',
 XY='(-2000,6325)',
 ROT='0',
 VER='1',
 PACK_TYPE='0402LF',
 LOCATION='R1518',
 CDS_LIB='pure_quanta',
 CDS_PART_NAME='Q_RES_0402LF-0,5%,1/16W,CHIP,CS00002JB13',
 PART_NUMBER='CS00002JB13',
 VALUE='0',
 PRIM_FILE='./archive_libs/logical/q_res/chips/chips.prt';

PART_NAME
 R1519 'Q_RES_0402LF-0,5%,1/16W,EMPTY,CS00002JB13':;

SECTION_NUMBER 1
 '@T6G_MB_LIB.T6G(SCH_1):PAGE340_I101@PURE_QUANTA.Q_RES(CHIPS)':
 C_PATH='@t6g_mb_lib.t6g(sch_1):page340_i101@pure_quanta.q_res(chips)',
 P_PATH='@t6g_mb_lib.t6g(sch_1):page136_i101@pure_quanta.q_res(chips)',
 PATH='I101',
 DRAWING='@T6G_MB_LIB.T6G(SCH_1):PAGE340',
 WATTAGE='1/16W',
 TOLERANCE='5%',
 MATERIAL='EMPTY',
 PHYS_PAGE='136',
 XY='(-1950,6600)',
 ROT='2',
 VER='1',
 PACK_TYPE='0402LF',
 LOCATION='R1519',
 CDS_LIB='pure_quanta',
 CDS_PART_NAME='Q_RES_0402LF-0,5%,1/16W,EMPTY,CS00002JB13',
 PART_NUMBER='CS00002JB13',
 VALUE='0',
 PRIM_FILE='./archive_libs/logical/q_res/chips/chips.prt';

PART_NAME
 R1520 'Q_RES_0402LF-0,5%,1/16W,CHIP,CS00002JB13':
 ROOM='NIC_P3V3_BOM1';

SECTION_NUMBER 1
 '@T6G_MB_LIB.T6G(SCH_1):PAGE343_I130@PURE_QUANTA.Q_RES(CHIPS)':
 C_PATH='@t6g_mb_lib.t6g(sch_1):page343_i130@pure_quanta.q_res(chips)',
 P_PATH='@t6g_mb_lib.t6g(sch_1):page140_i130@pure_quanta.q_res(chips)',
 PATH='I130',
 DRAWING='@T6G_MB_LIB.T6G(SCH_1):PAGE343',
 WATTAGE='1/16W',
 TOLERANCE='5%',
 MATERIAL='CHIP',
 PHYS_PAGE='140',
 XY='(-3100,8550)',
 ROT='0',
 VER='1',
 PACK_TYPE='0402LF',
 LOCATION='R1520',
 CDS_LIB='pure_quanta',
 CDS_PART_NAME='Q_RES_0402LF-0,5%,1/16W,CHIP,CS00002JB13',
 ROOM='NIC_P3V3_BOM1',
 PART_NUMBER='CS00002JB13',
 VALUE='0',
 PRIM_FILE='./archive_libs/logical/q_res/chips/chips.prt';

PART_NAME
 R1521 'Q_RES_0402LF-0,5%,1/16W,CHIP,CS00002JB13':
 ROOM='NIC_P3V3_BOM2';

SECTION_NUMBER 1
 '@T6G_MB_LIB.T6G(SCH_1):PAGE344_I80@PURE_QUANTA.Q_RES(CHIPS)':
 C_PATH='@t6g_mb_lib.t6g(sch_1):page344_i80@pure_quanta.q_res(chips)',
 P_PATH='@t6g_mb_lib.t6g(sch_1):page141_i80@pure_quanta.q_res(chips)',
 PATH='I80',
 DRAWING='@T6G_MB_LIB.T6G(SCH_1):PAGE344',
 WATTAGE='1/16W',
 TOLERANCE='5%',
 MATERIAL='CHIP',
 PHYS_PAGE='141',
 XY='(125,7275)',
 ROT='0',
 VER='1',
 PACK_TYPE='0402LF',
 LOCATION='R1521',
 CDS_LIB='pure_quanta',
 CDS_PART_NAME='Q_RES_0402LF-0,5%,1/16W,CHIP,CS00002JB13',
 ROOM='NIC_P3V3_BOM2',
 PART_NUMBER='CS00002JB13',
 VALUE='0',
 PRIM_FILE='./archive_libs/logical/q_res/chips/chips.prt';

PART_NAME
 R1522 'Q_RES_0402LF-0,5%,1/16W,CHIP,CS00002JB13':;

SECTION_NUMBER 1
 '@T6G_MB_LIB.T6G(SCH_1):PAGE248_I44@PURE_QUANTA.Q_RES(CHIPS)':
 C_PATH='@t6g_mb_lib.t6g(sch_1):page248_i44@pure_quanta.q_res(chips)',
 P_PATH='@t6g_mb_lib.t6g(sch_1):page247_i44@pure_quanta.q_res(chips)',
 PATH='I44',
 DRAWING='@T6G_MB_LIB.T6G(SCH_1):PAGE248',
 WATTAGE='1/16W',
 TOLERANCE='5%',
 MATERIAL='CHIP',
 PHYS_PAGE='247',
 XY='(-3350,2600)',
 ROT='0',
 VER='1',
 PACK_TYPE='0402LF',
 LOCATION='R1522',
 CDS_LIB='pure_quanta',
 CDS_PART_NAME='Q_RES_0402LF-0,5%,1/16W,CHIP,CS00002JB13',
 PART_NUMBER='CS00002JB13',
 VALUE='0',
 PRIM_FILE='./archive_libs/logical/q_res/chips/chips.prt';

PART_NAME
 R1523 'Q_RES_0402LF-0,5%,1/16W,CHIP,CS00002JB13':;

SECTION_NUMBER 1
 '@T6G_MB_LIB.T6G(SCH_1):PAGE257_I84@PURE_QUANTA.Q_RES(CHIPS)':
 C_PATH='@t6g_mb_lib.t6g(sch_1):page257_i84@pure_quanta.q_res(chips)',
 P_PATH='@t6g_mb_lib.t6g(sch_1):page142_i84@pure_quanta.q_res(chips)',
 PATH='I84',
 DRAWING='@T6G_MB_LIB.T6G(SCH_1):PAGE257',
 WATTAGE='1/16W',
 TOLERANCE='5%',
 MATERIAL='CHIP',
 PHYS_PAGE='142',
 XY='(-4325,75)',
 ROT='0',
 VER='1',
 PACK_TYPE='0402LF',
 LOCATION='R1523',
 CDS_LIB='pure_quanta',
 CDS_PART_NAME='Q_RES_0402LF-0,5%,1/16W,CHIP,CS00002JB13',
 PART_NUMBER='CS00002JB13',
 VALUE='0',
 PRIM_FILE='./archive_libs/logical/q_res/chips/chips.prt';

PART_NAME
 R1524 'Q_RES_0402LF-0,5%,1/16W,CHIP,CS00002JB13':;

SECTION_NUMBER 1
 '@T6G_MB_LIB.T6G(SCH_1):PAGE257_I89@PURE_QUANTA.Q_RES(CHIPS)':
 C_PATH='@t6g_mb_lib.t6g(sch_1):page257_i89@pure_quanta.q_res(chips)',
 P_PATH='@t6g_mb_lib.t6g(sch_1):page142_i89@pure_quanta.q_res(chips)',
 PATH='I89',
 DRAWING='@T6G_MB_LIB.T6G(SCH_1):PAGE257',
 WATTAGE='1/16W',
 TOLERANCE='5%',
 MATERIAL='CHIP',
 PHYS_PAGE='142',
 XY='(-2875,575)',
 ROT='0',
 VER='1',
 PACK_TYPE='0402LF',
 LOCATION='R1524',
 CDS_LIB='pure_quanta',
 CDS_PART_NAME='Q_RES_0402LF-0,5%,1/16W,CHIP,CS00002JB13',
 PART_NUMBER='CS00002JB13',
 VALUE='0',
 PRIM_FILE='./archive_libs/logical/q_res/chips/chips.prt';

PART_NAME
 R1525 'Q_RES_0402LF-0,5%,1/16W,EMPTY,CS00002JB13':;

SECTION_NUMBER 1
 '@T6G_MB_LIB.T6G(SCH_1):PAGE257_I88@PURE_QUANTA.Q_RES(CHIPS)':
 C_PATH='@t6g_mb_lib.t6g(sch_1):page257_i88@pure_quanta.q_res(chips)',
 P_PATH='@t6g_mb_lib.t6g(sch_1):page142_i88@pure_quanta.q_res(chips)',
 PATH='I88',
 DRAWING='@T6G_MB_LIB.T6G(SCH_1):PAGE257',
 WATTAGE='1/16W',
 TOLERANCE='5%',
 MATERIAL='EMPTY',
 PHYS_PAGE='142',
 XY='(-2300,725)',
 ROT='0',
 VER='1',
 PACK_TYPE='0402LF',
 LOCATION='R1525',
 CDS_LIB='pure_quanta',
 CDS_PART_NAME='Q_RES_0402LF-0,5%,1/16W,EMPTY,CS00002JB13',
 PART_NUMBER='CS00002JB13',
 VALUE='0',
 PRIM_FILE='./archive_libs/logical/q_res/chips/chips.prt';

PART_NAME
 R1526 'Q_RES_0402LF-0,5%,1/16W,CHIP,CS00002JB13':;

SECTION_NUMBER 1
 '@T6G_MB_LIB.T6G(SCH_1):PAGE363_I476@PURE_QUANTA.Q_RES(CHIPS)':
 C_PATH='@t6g_mb_lib.t6g(sch_1):page363_i476@pure_quanta.q_res(chips)',
 P_PATH='@t6g_mb_lib.t6g(sch_1):page240_i476@pure_quanta.q_res(chips)',
 PATH='I476',
 DRAWING='@T6G_MB_LIB.T6G(SCH_1):PAGE363',
 WATTAGE='1/16W',
 TOLERANCE='5%',
 MATERIAL='CHIP',
 PHYS_PAGE='240',
 XY='(-2150,575)',
 ROT='0',
 VER='1',
 PACK_TYPE='0402LF',
 LOCATION='R1526',
 CDS_LIB='pure_quanta',
 CDS_PART_NAME='Q_RES_0402LF-0,5%,1/16W,CHIP,CS00002JB13',
 PART_NUMBER='CS00002JB13',
 VALUE='0',
 PRIM_FILE='./archive_libs/logical/q_res/chips/chips.prt';

PART_NAME
 R1527 'Q_RES_0402LF-1K,1%,1/16W,CHIP,CS21002FB06':;

SECTION_NUMBER 1
 '@T6G_MB_LIB.T6G(SCH_1):PAGE82_I56@PURE_QUANTA.Q_RES(CHIPS)':
 C_PATH='@t6g_mb_lib.t6g(sch_1):page82_i56@pure_quanta.q_res(chips)',
 P_PATH='@t6g_mb_lib.t6g(sch_1):page83_i56@pure_quanta.q_res(chips)',
 PATH='I56',
 DRAWING='@T6G_MB_LIB.T6G(SCH_1):PAGE82',
 WATTAGE='1/16W',
 TOLERANCE='1%',
 MATERIAL='CHIP',
 PHYS_PAGE='83',
 XY='(-7050,5250)',
 ROT='0',
 VER='1',
 PACK_TYPE='0402LF',
 LOCATION='R1527',
 CDS_LIB='pure_quanta',
 CDS_PART_NAME='Q_RES_0402LF-1K,1%,1/16W,CHIP,CS21002FB06',
 PART_NUMBER='CS21002FB06',
 VALUE='1K',
 PRIM_FILE='./archive_libs/logical/q_res/chips/chips.prt';

PART_NAME
 R1528 'Q_RES_0402LF-33,5%,1/16W,CHIP,CS03302JB10':;

SECTION_NUMBER 1
 '@T6G_MB_LIB.T6G(SCH_1):PAGE149_I157@PURE_QUANTA.Q_RES(CHIPS)':
 C_PATH='@t6g_mb_lib.t6g(sch_1):page149_i157@pure_quanta.q_res(chips)',
 P_PATH='@t6g_mb_lib.t6g(sch_1):page172_i157@pure_quanta.q_res(chips)',
 PATH='I157',
 DRAWING='@T6G_MB_LIB.T6G(SCH_1):PAGE149',
 WATTAGE='1/16W',
 TOLERANCE='5%',
 MATERIAL='CHIP',
 PHYS_PAGE='172',
 XY='(-6300,5900)',
 ROT='0',
 VER='1',
 PACK_TYPE='0402LF',
 LOCATION='R1528',
 CDS_LIB='pure_quanta',
 CDS_PART_NAME='Q_RES_0402LF-33,5%,1/16W,CHIP,CS03302JB10',
 PART_NUMBER='CS03302JB10',
 VALUE='33',
 PRIM_FILE='./archive_libs/logical/q_res/chips/chips.prt';

PART_NAME
 R1529 'Q_RES_0402LF-1K,1%,1/16W,EMPTY,CS21002FB06':;

SECTION_NUMBER 1
 '@T6G_MB_LIB.T6G(SCH_1):PAGE76_I134@PURE_QUANTA.Q_RES(CHIPS)':
 C_PATH='@t6g_mb_lib.t6g(sch_1):page76_i134@pure_quanta.q_res(chips)',
 P_PATH='@t6g_mb_lib.t6g(sch_1):page77_i134@pure_quanta.q_res(chips)',
 PATH='I134',
 DRAWING='@T6G_MB_LIB.T6G(SCH_1):PAGE76',
 WATTAGE='1/16W',
 TOLERANCE='1%',
 MATERIAL='EMPTY',
 PHYS_PAGE='77',
 XY='(-9075,5875)',
 ROT='0',
 VER='2',
 PACK_TYPE='0402LF',
 LOCATION='R1529',
 CDS_LIB='pure_quanta',
 CDS_PART_NAME='Q_RES_0402LF-1K,1%,1/16W,EMPTY,CS21002FB06',
 PART_NUMBER='CS21002FB06',
 VALUE='1K',
 PRIM_FILE='./archive_libs/logical/q_res/chips/chips.prt';

PART_NAME
 R1530 'Q_RES_0402LF-1K,1%,1/16W,EMPTY,CS21002FB06':;

SECTION_NUMBER 1
 '@T6G_MB_LIB.T6G(SCH_1):PAGE76_I133@PURE_QUANTA.Q_RES(CHIPS)':
 C_PATH='@t6g_mb_lib.t6g(sch_1):page76_i133@pure_quanta.q_res(chips)',
 P_PATH='@t6g_mb_lib.t6g(sch_1):page77_i133@pure_quanta.q_res(chips)',
 PATH='I133',
 DRAWING='@T6G_MB_LIB.T6G(SCH_1):PAGE76',
 WATTAGE='1/16W',
 TOLERANCE='1%',
 MATERIAL='EMPTY',
 PHYS_PAGE='77',
 XY='(-8900,5875)',
 ROT='0',
 VER='2',
 PACK_TYPE='0402LF',
 LOCATION='R1530',
 CDS_LIB='pure_quanta',
 CDS_PART_NAME='Q_RES_0402LF-1K,1%,1/16W,EMPTY,CS21002FB06',
 PART_NUMBER='CS21002FB06',
 VALUE='1K',
 PRIM_FILE='./archive_libs/logical/q_res/chips/chips.prt';

PART_NAME
 R1531 'Q_RES_0402LF-1K,1%,1/16W,EMPTY,CS21002FB06':;

SECTION_NUMBER 1
 '@T6G_MB_LIB.T6G(SCH_1):PAGE76_I132@PURE_QUANTA.Q_RES(CHIPS)':
 C_PATH='@t6g_mb_lib.t6g(sch_1):page76_i132@pure_quanta.q_res(chips)',
 P_PATH='@t6g_mb_lib.t6g(sch_1):page77_i132@pure_quanta.q_res(chips)',
 PATH='I132',
 DRAWING='@T6G_MB_LIB.T6G(SCH_1):PAGE76',
 WATTAGE='1/16W',
 TOLERANCE='1%',
 MATERIAL='EMPTY',
 PHYS_PAGE='77',
 XY='(-8725,5875)',
 ROT='0',
 VER='2',
 PACK_TYPE='0402LF',
 LOCATION='R1531',
 CDS_LIB='pure_quanta',
 CDS_PART_NAME='Q_RES_0402LF-1K,1%,1/16W,EMPTY,CS21002FB06',
 PART_NUMBER='CS21002FB06',
 VALUE='1K',
 PRIM_FILE='./archive_libs/logical/q_res/chips/chips.prt';

PART_NAME
 R1532 'Q_RES_0402LF-1K,1%,1/16W,EMPTY,CS21002FB06':;

SECTION_NUMBER 1
 '@T6G_MB_LIB.T6G(SCH_1):PAGE76_I131@PURE_QUANTA.Q_RES(CHIPS)':
 C_PATH='@t6g_mb_lib.t6g(sch_1):page76_i131@pure_quanta.q_res(chips)',
 P_PATH='@t6g_mb_lib.t6g(sch_1):page77_i131@pure_quanta.q_res(chips)',
 PATH='I131',
 DRAWING='@T6G_MB_LIB.T6G(SCH_1):PAGE76',
 WATTAGE='1/16W',
 TOLERANCE='1%',
 MATERIAL='EMPTY',
 PHYS_PAGE='77',
 XY='(-8550,5875)',
 ROT='0',
 VER='2',
 PACK_TYPE='0402LF',
 LOCATION='R1532',
 CDS_LIB='pure_quanta',
 CDS_PART_NAME='Q_RES_0402LF-1K,1%,1/16W,EMPTY,CS21002FB06',
 PART_NUMBER='CS21002FB06',
 VALUE='1K',
 PRIM_FILE='./archive_libs/logical/q_res/chips/chips.prt';

PART_NAME
 R1533 'Q_RES_0402LF-0,5%,1/16W,CHIP,CS00002JB13':;

SECTION_NUMBER 1
 '@T6G_MB_LIB.T6G(SCH_1):PAGE27_I429@PURE_QUANTA.Q_RES(CHIPS)':
 C_PATH='@t6g_mb_lib.t6g(sch_1):page27_i429@pure_quanta.q_res(chips)',
 P_PATH='@t6g_mb_lib.t6g(sch_1):page27_i429@pure_quanta.q_res(chips)',
 PATH='I429',
 DRAWING='@T6G_MB_LIB.T6G(SCH_1):PAGE27',
 WATTAGE='1/16W',
 TOLERANCE='5%',
 MATERIAL='CHIP',
 PHYS_PAGE='27',
 XY='(-1075,3825)',
 ROT='0',
 VER='1',
 PACK_TYPE='0402LF',
 LOCATION='R1533',
 CDS_LIB='pure_quanta',
 CDS_PART_NAME='Q_RES_0402LF-0,5%,1/16W,CHIP,CS00002JB13',
 PART_NUMBER='CS00002JB13',
 VALUE='0',
 PRIM_FILE='./archive_libs/logical/q_res/chips/chips.prt';

PART_NAME
 R1546 'Q_RES_0402LF-1K,1%,1/16W,CHIP,CS21002FB06':;

SECTION_NUMBER 1
 '@T6G_MB_LIB.T6G(SCH_1):PAGE349_I30@PURE_QUANTA.Q_RES(CHIPS)':
 C_PATH='@t6g_mb_lib.t6g(sch_1):page349_i30@pure_quanta.q_res(chips)',
 P_PATH='@t6g_mb_lib.t6g(sch_1):page151_i30@pure_quanta.q_res(chips)',
 PATH='I30',
 DRAWING='@T6G_MB_LIB.T6G(SCH_1):PAGE349',
 WATTAGE='1/16W',
 TOLERANCE='1%',
 MATERIAL='CHIP',
 PHYS_PAGE='151',
 XY='(-2100,6000)',
 ROT='0',
 VER='1',
 PACK_TYPE='0402LF',
 LOCATION='R1546',
 CDS_LIB='pure_quanta',
 CDS_PART_NAME='Q_RES_0402LF-1K,1%,1/16W,CHIP,CS21002FB06',
 PART_NUMBER='CS21002FB06',
 VALUE='1K',
 PRIM_FILE='./archive_libs/logical/q_res/chips/chips.prt';

PART_NAME
 R1547 'Q_RES_0402LF-4.7K,5%,1/16W,CHIP,CS24702JB10':;

SECTION_NUMBER 1
 '@T6G_MB_LIB.T6G(SCH_1):PAGE76_I148@PURE_QUANTA.Q_RES(CHIPS)':
 C_PATH='@t6g_mb_lib.t6g(sch_1):page76_i148@pure_quanta.q_res(chips)',
 P_PATH='@t6g_mb_lib.t6g(sch_1):page77_i148@pure_quanta.q_res(chips)',
 PATH='I148',
 DRAWING='@T6G_MB_LIB.T6G(SCH_1):PAGE76',
 WATTAGE='1/16W',
 TOLERANCE='5%',
 MATERIAL='CHIP',
 PHYS_PAGE='77',
 XY='(-1175,5625)',
 ROT='0',
 VER='2',
 PACK_TYPE='0402LF',
 LOCATION='R1547',
 CDS_LIB='pure_quanta',
 CDS_PART_NAME='Q_RES_0402LF-4.7K,5%,1/16W,CHIP,CS24702JB10',
 PART_NUMBER='CS24702JB10',
 VALUE='4.7K',
 PRIM_FILE='./archive_libs/logical/q_res/chips/chips.prt';

PART_NAME
 R1549 'Q_RES_0402LF-33,5%,1/16W,CHIP,CS03302JB10':;

SECTION_NUMBER 1
 '@T6G_MB_LIB.T6G(SCH_1):PAGE80_I173@PURE_QUANTA.Q_RES(CHIPS)':
 C_PATH='@t6g_mb_lib.t6g(sch_1):page80_i173@pure_quanta.q_res(chips)',
 P_PATH='@t6g_mb_lib.t6g(sch_1):page81_i173@pure_quanta.q_res(chips)',
 PATH='I173',
 DRAWING='@T6G_MB_LIB.T6G(SCH_1):PAGE80',
 BOM_COST='MEM',
 WATTAGE='1/16W',
 TOLERANCE='5%',
 MATERIAL='CHIP',
 PHYS_PAGE='81',
 XY='(-3225,5325)',
 ROT='0',
 VER='1',
 PACK_TYPE='0402LF',
 LOCATION='R1549',
 CDS_LIB='pure_quanta',
 CDS_PART_NAME='Q_RES_0402LF-33,5%,1/16W,CHIP,CS03302JB10',
 PART_NUMBER='CS03302JB10',
 VALUE='33',
 PRIM_FILE='./archive_libs/logical/q_res/chips/chips.prt';

PART_NAME
 R1550 'Q_RES_0402LF-33,5%,1/16W,CHIP,CS03302JB10':;

SECTION_NUMBER 1
 '@T6G_MB_LIB.T6G(SCH_1):PAGE80_I171@PURE_QUANTA.Q_RES(CHIPS)':
 C_PATH='@t6g_mb_lib.t6g(sch_1):page80_i171@pure_quanta.q_res(chips)',
 P_PATH='@t6g_mb_lib.t6g(sch_1):page81_i171@pure_quanta.q_res(chips)',
 PATH='I171',
 DRAWING='@T6G_MB_LIB.T6G(SCH_1):PAGE80',
 BOM_COST='MEM',
 WATTAGE='1/16W',
 TOLERANCE='5%',
 MATERIAL='CHIP',
 PHYS_PAGE='81',
 XY='(-3225,5275)',
 ROT='0',
 VER='1',
 PACK_TYPE='0402LF',
 LOCATION='R1550',
 CDS_LIB='pure_quanta',
 CDS_PART_NAME='Q_RES_0402LF-33,5%,1/16W,CHIP,CS03302JB10',
 PART_NUMBER='CS03302JB10',
 VALUE='33',
 PRIM_FILE='./archive_libs/logical/q_res/chips/chips.prt';

PART_NAME
 R1551 'Q_RES_0402LF-33,5%,1/16W,CHIP,CS03302JB10':;

SECTION_NUMBER 1
 '@T6G_MB_LIB.T6G(SCH_1):PAGE80_I169@PURE_QUANTA.Q_RES(CHIPS)':
 C_PATH='@t6g_mb_lib.t6g(sch_1):page80_i169@pure_quanta.q_res(chips)',
 P_PATH='@t6g_mb_lib.t6g(sch_1):page81_i169@pure_quanta.q_res(chips)',
 PATH='I169',
 DRAWING='@T6G_MB_LIB.T6G(SCH_1):PAGE80',
 BOM_COST='MEM',
 WATTAGE='1/16W',
 TOLERANCE='5%',
 MATERIAL='CHIP',
 PHYS_PAGE='81',
 XY='(-3225,5225)',
 ROT='0',
 VER='1',
 PACK_TYPE='0402LF',
 LOCATION='R1551',
 CDS_LIB='pure_quanta',
 CDS_PART_NAME='Q_RES_0402LF-33,5%,1/16W,CHIP,CS03302JB10',
 PART_NUMBER='CS03302JB10',
 VALUE='33',
 PRIM_FILE='./archive_libs/logical/q_res/chips/chips.prt';

PART_NAME
 R1552 'Q_RES_0402LF-33,5%,1/16W,CHIP,CS03302JB10':;

SECTION_NUMBER 1
 '@T6G_MB_LIB.T6G(SCH_1):PAGE80_I170@PURE_QUANTA.Q_RES(CHIPS)':
 C_PATH='@t6g_mb_lib.t6g(sch_1):page80_i170@pure_quanta.q_res(chips)',
 P_PATH='@t6g_mb_lib.t6g(sch_1):page81_i170@pure_quanta.q_res(chips)',
 PATH='I170',
 DRAWING='@T6G_MB_LIB.T6G(SCH_1):PAGE80',
 BOM_COST='MEM',
 WATTAGE='1/16W',
 TOLERANCE='5%',
 MATERIAL='CHIP',
 PHYS_PAGE='81',
 XY='(-3225,5175)',
 ROT='0',
 VER='1',
 PACK_TYPE='0402LF',
 LOCATION='R1552',
 CDS_LIB='pure_quanta',
 CDS_PART_NAME='Q_RES_0402LF-33,5%,1/16W,CHIP,CS03302JB10',
 PART_NUMBER='CS03302JB10',
 VALUE='33',
 PRIM_FILE='./archive_libs/logical/q_res/chips/chips.prt';

PART_NAME
 R1553 'Q_RES_0402LF-33,5%,1/16W,CHIP,CS03302JB10':;

SECTION_NUMBER 1
 '@T6G_MB_LIB.T6G(SCH_1):PAGE80_I174@PURE_QUANTA.Q_RES(CHIPS)':
 C_PATH='@t6g_mb_lib.t6g(sch_1):page80_i174@pure_quanta.q_res(chips)',
 P_PATH='@t6g_mb_lib.t6g(sch_1):page81_i174@pure_quanta.q_res(chips)',
 PATH='I174',
 DRAWING='@T6G_MB_LIB.T6G(SCH_1):PAGE80',
 WATTAGE='1/16W',
 TOLERANCE='5%',
 MATERIAL='CHIP',
 PHYS_PAGE='81',
 XY='(-3225,5475)',
 ROT='0',
 VER='1',
 PACK_TYPE='0402LF',
 LOCATION='R1553',
 CDS_LIB='pure_quanta',
 CDS_PART_NAME='Q_RES_0402LF-33,5%,1/16W,CHIP,CS03302JB10',
 PART_NUMBER='CS03302JB10',
 VALUE='33',
 PRIM_FILE='./archive_libs/logical/q_res/chips/chips.prt';

PART_NAME
 R1556 'Q_RES_0402LF-33,5%,1/16W,CHIP,CS03302JB10':;

SECTION_NUMBER 1
 '@T6G_MB_LIB.T6G(SCH_1):PAGE80_I176@PURE_QUANTA.Q_RES(CHIPS)':
 C_PATH='@t6g_mb_lib.t6g(sch_1):page80_i176@pure_quanta.q_res(chips)',
 P_PATH='@t6g_mb_lib.t6g(sch_1):page81_i176@pure_quanta.q_res(chips)',
 PATH='I176',
 DRAWING='@T6G_MB_LIB.T6G(SCH_1):PAGE80',
 WATTAGE='1/16W',
 TOLERANCE='5%',
 MATERIAL='CHIP',
 PHYS_PAGE='81',
 XY='(-3225,5525)',
 ROT='0',
 VER='1',
 PACK_TYPE='0402LF',
 LOCATION='R1556',
 CDS_LIB='pure_quanta',
 CDS_PART_NAME='Q_RES_0402LF-33,5%,1/16W,CHIP,CS03302JB10',
 PART_NUMBER='CS03302JB10',
 VALUE='33',
 PRIM_FILE='./archive_libs/logical/q_res/chips/chips.prt';

PART_NAME
 R1557 'Q_RES_0402LF-33,5%,1/16W,CHIP,CS03302JB10':;

SECTION_NUMBER 1
 '@T6G_MB_LIB.T6G(SCH_1):PAGE80_I175@PURE_QUANTA.Q_RES(CHIPS)':
 C_PATH='@t6g_mb_lib.t6g(sch_1):page80_i175@pure_quanta.q_res(chips)',
 P_PATH='@t6g_mb_lib.t6g(sch_1):page81_i175@pure_quanta.q_res(chips)',
 PATH='I175',
 DRAWING='@T6G_MB_LIB.T6G(SCH_1):PAGE80',
 WATTAGE='1/16W',
 TOLERANCE='5%',
 MATERIAL='CHIP',
 PHYS_PAGE='81',
 XY='(-3225,5425)',
 ROT='0',
 VER='1',
 PACK_TYPE='0402LF',
 LOCATION='R1557',
 CDS_LIB='pure_quanta',
 CDS_PART_NAME='Q_RES_0402LF-33,5%,1/16W,CHIP,CS03302JB10',
 PART_NUMBER='CS03302JB10',
 VALUE='33',
 PRIM_FILE='./archive_libs/logical/q_res/chips/chips.prt';

PART_NAME
 R1558 'Q_RES_0402LF-33,5%,1/16W,CHIP,CS03302JB10':;

SECTION_NUMBER 1
 '@T6G_MB_LIB.T6G(SCH_1):PAGE80_I172@PURE_QUANTA.Q_RES(CHIPS)':
 C_PATH='@t6g_mb_lib.t6g(sch_1):page80_i172@pure_quanta.q_res(chips)',
 P_PATH='@t6g_mb_lib.t6g(sch_1):page81_i172@pure_quanta.q_res(chips)',
 PATH='I172',
 DRAWING='@T6G_MB_LIB.T6G(SCH_1):PAGE80',
 WATTAGE='1/16W',
 TOLERANCE='5%',
 MATERIAL='CHIP',
 PHYS_PAGE='81',
 XY='(-3225,5375)',
 ROT='0',
 VER='1',
 PACK_TYPE='0402LF',
 LOCATION='R1558',
 CDS_LIB='pure_quanta',
 CDS_PART_NAME='Q_RES_0402LF-33,5%,1/16W,CHIP,CS03302JB10',
 PART_NUMBER='CS03302JB10',
 VALUE='33',
 PRIM_FILE='./archive_libs/logical/q_res/chips/chips.prt';

PART_NAME
 R1563 'Q_RES_0402LF-33,5%,1/16W,CHIP,CS03302JB10':;

SECTION_NUMBER 1
 '@T6G_MB_LIB.T6G(SCH_1):PAGE80_I63@PURE_QUANTA.Q_RES(CHIPS)':
 C_PATH='@t6g_mb_lib.t6g(sch_1):page80_i63@pure_quanta.q_res(chips)',
 P_PATH='@t6g_mb_lib.t6g(sch_1):page81_i63@pure_quanta.q_res(chips)',
 PATH='I63',
 DRAWING='@T6G_MB_LIB.T6G(SCH_1):PAGE80',
 BOM_COST='MEM',
 WATTAGE='1/16W',
 TOLERANCE='5%',
 MATERIAL='CHIP',
 PHYS_PAGE='81',
 XY='(-6725,2675)',
 ROT='0',
 VER='1',
 PACK_TYPE='0402LF',
 LOCATION='R1563',
 CDS_LIB='pure_quanta',
 CDS_PART_NAME='Q_RES_0402LF-33,5%,1/16W,CHIP,CS03302JB10',
 PART_NUMBER='CS03302JB10',
 VALUE='33',
 PRIM_FILE='./archive_libs/logical/q_res/chips/chips.prt';

PART_NAME
 R1564 'Q_RES_0402LF-33,5%,1/16W,CHIP,CS03302JB10':;

SECTION_NUMBER 1
 '@T6G_MB_LIB.T6G(SCH_1):PAGE80_I156@PURE_QUANTA.Q_RES(CHIPS)':
 C_PATH='@t6g_mb_lib.t6g(sch_1):page80_i156@pure_quanta.q_res(chips)',
 P_PATH='@t6g_mb_lib.t6g(sch_1):page81_i156@pure_quanta.q_res(chips)',
 PATH='I156',
 DRAWING='@T6G_MB_LIB.T6G(SCH_1):PAGE80',
 BOM_COST='MEM',
 WATTAGE='1/16W',
 TOLERANCE='5%',
 MATERIAL='CHIP',
 PHYS_PAGE='81',
 XY='(-3225,4325)',
 ROT='0',
 VER='1',
 PACK_TYPE='0402LF',
 LOCATION='R1564',
 CDS_LIB='pure_quanta',
 CDS_PART_NAME='Q_RES_0402LF-33,5%,1/16W,CHIP,CS03302JB10',
 PART_NUMBER='CS03302JB10',
 VALUE='33',
 PRIM_FILE='./archive_libs/logical/q_res/chips/chips.prt';

PART_NAME
 R1567 'Q_RES_0402LF-4.7K,5%,1/16W,CHIP,CS24702JB10':;

SECTION_NUMBER 1
 '@T6G_MB_LIB.T6G(SCH_1):PAGE76_I150@PURE_QUANTA.Q_RES(CHIPS)':
 C_PATH='@t6g_mb_lib.t6g(sch_1):page76_i150@pure_quanta.q_res(chips)',
 P_PATH='@t6g_mb_lib.t6g(sch_1):page77_i150@pure_quanta.q_res(chips)',
 PATH='I150',
 DRAWING='@T6G_MB_LIB.T6G(SCH_1):PAGE76',
 WATTAGE='1/16W',
 TOLERANCE='5%',
 MATERIAL='CHIP',
 PHYS_PAGE='77',
 XY='(-9250,5875)',
 ROT='0',
 VER='2',
 PACK_TYPE='0402LF',
 LOCATION='R1567',
 CDS_LIB='pure_quanta',
 CDS_PART_NAME='Q_RES_0402LF-4.7K,5%,1/16W,CHIP,CS24702JB10',
 PART_NUMBER='CS24702JB10',
 VALUE='4.7K',
 PRIM_FILE='./archive_libs/logical/q_res/chips/chips.prt';

PART_NAME
 R1568 'Q_RES_0402LF-49.9,1%,1/16W,CHIP,CS04992FB07':;

SECTION_NUMBER 1
 '@T6G_MB_LIB.T6G(SCH_1):PAGE85_I539@PURE_QUANTA.Q_RES(CHIPS)':
 C_PATH='@t6g_mb_lib.t6g(sch_1):page85_i539@pure_quanta.q_res(chips)',
 P_PATH='@t6g_mb_lib.t6g(sch_1):page86_i539@pure_quanta.q_res(chips)',
 PATH='I539',
 DRAWING='@T6G_MB_LIB.T6G(SCH_1):PAGE85',
 WATTAGE='1/16W',
 TOLERANCE='1%',
 MATERIAL='CHIP',
 PHYS_PAGE='86',
 XY='(-7775,2700)',
 ROT='0',
 VER='1',
 PACK_TYPE='0402LF',
 LOCATION='R1568',
 CDS_LIB='pure_quanta',
 CDS_PART_NAME='Q_RES_0402LF-49.9,1%,1/16W,CHIP,CS04992FB07',
 PART_NUMBER='CS04992FB07',
 VALUE='49.9',
 PRIM_FILE='./archive_libs/logical/q_res/chips/chips.prt';

PART_NAME
 R1569 'Q_RES_0402LF-49.9,1%,1/16W,CHIP,CS04992FB07':;

SECTION_NUMBER 1
 '@T6G_MB_LIB.T6G(SCH_1):PAGE86_I372@PURE_QUANTA.Q_RES(CHIPS)':
 C_PATH='@t6g_mb_lib.t6g(sch_1):page86_i372@pure_quanta.q_res(chips)',
 P_PATH='@t6g_mb_lib.t6g(sch_1):page87_i372@pure_quanta.q_res(chips)',
 PATH='I372',
 DRAWING='@T6G_MB_LIB.T6G(SCH_1):PAGE86',
 WATTAGE='1/16W',
 TOLERANCE='1%',
 MATERIAL='CHIP',
 PHYS_PAGE='87',
 XY='(-7975,2775)',
 ROT='0',
 VER='1',
 PACK_TYPE='0402LF',
 LOCATION='R1569',
 CDS_LIB='pure_quanta',
 CDS_PART_NAME='Q_RES_0402LF-49.9,1%,1/16W,CHIP,CS04992FB07',
 PART_NUMBER='CS04992FB07',
 VALUE='49.9',
 PRIM_FILE='./archive_libs/logical/q_res/chips/chips.prt';

PART_NAME
 R1570 'Q_RES_0402LF-49.9,1%,1/16W,CHIP,CS04992FB07':;

SECTION_NUMBER 1
 '@T6G_MB_LIB.T6G(SCH_1):PAGE87_I417@PURE_QUANTA.Q_RES(CHIPS)':
 C_PATH='@t6g_mb_lib.t6g(sch_1):page87_i417@pure_quanta.q_res(chips)',
 P_PATH='@t6g_mb_lib.t6g(sch_1):page88_i417@pure_quanta.q_res(chips)',
 PATH='I417',
 DRAWING='@T6G_MB_LIB.T6G(SCH_1):PAGE87',
 WATTAGE='1/16W',
 TOLERANCE='1%',
 MATERIAL='CHIP',
 PHYS_PAGE='88',
 XY='(-7950,2950)',
 ROT='0',
 VER='1',
 PACK_TYPE='0402LF',
 LOCATION='R1570',
 CDS_LIB='pure_quanta',
 CDS_PART_NAME='Q_RES_0402LF-49.9,1%,1/16W,CHIP,CS04992FB07',
 PART_NUMBER='CS04992FB07',
 VALUE='49.9',
 PRIM_FILE='./archive_libs/logical/q_res/chips/chips.prt';

PART_NAME
 R1571 'Q_RES_0402LF-0,5%,1/16W,CHIP,CS00002JB13':;

SECTION_NUMBER 1
 '@T6G_MB_LIB.T6G(SCH_1):PAGE245_I11@PURE_QUANTA.Q_RES(CHIPS)':
 C_PATH='@t6g_mb_lib.t6g(sch_1):page245_i11@pure_quanta.q_res(chips)',
 P_PATH='@t6g_mb_lib.t6g(sch_1):page190_i11@pure_quanta.q_res(chips)',
 PATH='I11',
 DRAWING='@T6G_MB_LIB.T6G(SCH_1):PAGE245',
 WATTAGE='1/16W',
 TOLERANCE='5%',
 MATERIAL='CHIP',
 PHYS_PAGE='190',
 XY='(-2800,-600)',
 ROT='0',
 VER='2',
 PACK_TYPE='0402LF',
 LOCATION='R1571',
 CDS_LIB='pure_quanta',
 CDS_PART_NAME='Q_RES_0402LF-0,5%,1/16W,CHIP,CS00002JB13',
 PART_NUMBER='CS00002JB13',
 VALUE='0',
 PRIM_FILE='./archive_libs/logical/q_res/chips/chips.prt';

PART_NAME
 R1572 'Q_RES_0402LF-49.9,1%,1/16W,CHIP,CS04992FB07':;

SECTION_NUMBER 1
 '@T6G_MB_LIB.T6G(SCH_1):PAGE89_I416@PURE_QUANTA.Q_RES(CHIPS)':
 C_PATH='@t6g_mb_lib.t6g(sch_1):page89_i416@pure_quanta.q_res(chips)',
 P_PATH='@t6g_mb_lib.t6g(sch_1):page90_i416@pure_quanta.q_res(chips)',
 PATH='I416',
 DRAWING='@T6G_MB_LIB.T6G(SCH_1):PAGE89',
 WATTAGE='1/16W',
 TOLERANCE='1%',
 MATERIAL='CHIP',
 PHYS_PAGE='90',
 XY='(-8025,2825)',
 ROT='0',
 VER='1',
 PACK_TYPE='0402LF',
 LOCATION='R1572',
 CDS_LIB='pure_quanta',
 CDS_PART_NAME='Q_RES_0402LF-49.9,1%,1/16W,CHIP,CS04992FB07',
 PART_NUMBER='CS04992FB07',
 VALUE='49.9',
 PRIM_FILE='./archive_libs/logical/q_res/chips/chips.prt';

PART_NAME
 R1573 'Q_RES_0402LF-49.9,1%,1/16W,CHIP,CS04992FB07':;

SECTION_NUMBER 1
 '@T6G_MB_LIB.T6G(SCH_1):PAGE90_I418@PURE_QUANTA.Q_RES(CHIPS)':
 C_PATH='@t6g_mb_lib.t6g(sch_1):page90_i418@pure_quanta.q_res(chips)',
 P_PATH='@t6g_mb_lib.t6g(sch_1):page91_i418@pure_quanta.q_res(chips)',
 PATH='I418',
 DRAWING='@T6G_MB_LIB.T6G(SCH_1):PAGE90',
 WATTAGE='1/16W',
 TOLERANCE='1%',
 MATERIAL='CHIP',
 PHYS_PAGE='91',
 XY='(-7825,2975)',
 ROT='0',
 VER='1',
 PACK_TYPE='0402LF',
 LOCATION='R1573',
 CDS_LIB='pure_quanta',
 CDS_PART_NAME='Q_RES_0402LF-49.9,1%,1/16W,CHIP,CS04992FB07',
 PART_NUMBER='CS04992FB07',
 VALUE='49.9',
 PRIM_FILE='./archive_libs/logical/q_res/chips/chips.prt';

PART_NAME
 R1574 'Q_RES_0402LF-49.9,1%,1/16W,CHIP,CS04992FB07':;

SECTION_NUMBER 1
 '@T6G_MB_LIB.T6G(SCH_1):PAGE91_I242@PURE_QUANTA.Q_RES(CHIPS)':
 C_PATH='@t6g_mb_lib.t6g(sch_1):page91_i242@pure_quanta.q_res(chips)',
 P_PATH='@t6g_mb_lib.t6g(sch_1):page92_i242@pure_quanta.q_res(chips)',
 PATH='I242',
 DRAWING='@T6G_MB_LIB.T6G(SCH_1):PAGE91',
 WATTAGE='1/16W',
 TOLERANCE='1%',
 MATERIAL='CHIP',
 PHYS_PAGE='92',
 XY='(-7375,2650)',
 ROT='0',
 VER='1',
 PACK_TYPE='0402LF',
 LOCATION='R1574',
 CDS_LIB='pure_quanta',
 CDS_PART_NAME='Q_RES_0402LF-49.9,1%,1/16W,CHIP,CS04992FB07',
 PART_NUMBER='CS04992FB07',
 VALUE='49.9',
 PRIM_FILE='./archive_libs/logical/q_res/chips/chips.prt';

PART_NAME
 R1575 'Q_RES_0402LF-49.9,1%,1/16W,CHIP,CS04992FB07':;

SECTION_NUMBER 1
 '@T6G_MB_LIB.T6G(SCH_1):PAGE92_I243@PURE_QUANTA.Q_RES(CHIPS)':
 C_PATH='@t6g_mb_lib.t6g(sch_1):page92_i243@pure_quanta.q_res(chips)',
 P_PATH='@t6g_mb_lib.t6g(sch_1):page93_i243@pure_quanta.q_res(chips)',
 PATH='I243',
 DRAWING='@T6G_MB_LIB.T6G(SCH_1):PAGE92',
 WATTAGE='1/16W',
 TOLERANCE='1%',
 MATERIAL='CHIP',
 PHYS_PAGE='93',
 XY='(-7750,2575)',
 ROT='0',
 VER='1',
 PACK_TYPE='0402LF',
 LOCATION='R1575',
 CDS_LIB='pure_quanta',
 CDS_PART_NAME='Q_RES_0402LF-49.9,1%,1/16W,CHIP,CS04992FB07',
 PART_NUMBER='CS04992FB07',
 VALUE='49.9',
 PRIM_FILE='./archive_libs/logical/q_res/chips/chips.prt';

PART_NAME
 R1576 'Q_RES_0402LF-49.9,1%,1/16W,CHIP,CS04992FB07':;

SECTION_NUMBER 1
 '@T6G_MB_LIB.T6G(SCH_1):PAGE93_I242@PURE_QUANTA.Q_RES(CHIPS)':
 C_PATH='@t6g_mb_lib.t6g(sch_1):page93_i242@pure_quanta.q_res(chips)',
 P_PATH='@t6g_mb_lib.t6g(sch_1):page94_i242@pure_quanta.q_res(chips)',
 PATH='I242',
 DRAWING='@T6G_MB_LIB.T6G(SCH_1):PAGE93',
 WATTAGE='1/16W',
 TOLERANCE='1%',
 MATERIAL='CHIP',
 PHYS_PAGE='94',
 XY='(-7750,2675)',
 ROT='0',
 VER='1',
 PACK_TYPE='0402LF',
 LOCATION='R1576',
 CDS_LIB='pure_quanta',
 CDS_PART_NAME='Q_RES_0402LF-49.9,1%,1/16W,CHIP,CS04992FB07',
 PART_NUMBER='CS04992FB07',
 VALUE='49.9',
 PRIM_FILE='./archive_libs/logical/q_res/chips/chips.prt';

PART_NAME
 R1577 'Q_RES_0402LF-49.9,1%,1/16W,CHIP,CS04992FB07':;

SECTION_NUMBER 1
 '@T6G_MB_LIB.T6G(SCH_1):PAGE94_I242@PURE_QUANTA.Q_RES(CHIPS)':
 C_PATH='@t6g_mb_lib.t6g(sch_1):page94_i242@pure_quanta.q_res(chips)',
 P_PATH='@t6g_mb_lib.t6g(sch_1):page95_i242@pure_quanta.q_res(chips)',
 PATH='I242',
 DRAWING='@T6G_MB_LIB.T6G(SCH_1):PAGE94',
 WATTAGE='1/16W',
 TOLERANCE='1%',
 MATERIAL='CHIP',
 PHYS_PAGE='95',
 XY='(-7700,2550)',
 ROT='0',
 VER='1',
 PACK_TYPE='0402LF',
 LOCATION='R1577',
 CDS_LIB='pure_quanta',
 CDS_PART_NAME='Q_RES_0402LF-49.9,1%,1/16W,CHIP,CS04992FB07',
 PART_NUMBER='CS04992FB07',
 VALUE='49.9',
 PRIM_FILE='./archive_libs/logical/q_res/chips/chips.prt';

PART_NAME
 R1578 'Q_RES_0402LF-49.9,1%,1/16W,CHIP,CS04992FB07':;

SECTION_NUMBER 1
 '@T6G_MB_LIB.T6G(SCH_1):PAGE95_I242@PURE_QUANTA.Q_RES(CHIPS)':
 C_PATH='@t6g_mb_lib.t6g(sch_1):page95_i242@pure_quanta.q_res(chips)',
 P_PATH='@t6g_mb_lib.t6g(sch_1):page96_i242@pure_quanta.q_res(chips)',
 PATH='I242',
 DRAWING='@T6G_MB_LIB.T6G(SCH_1):PAGE95',
 WATTAGE='1/16W',
 TOLERANCE='1%',
 MATERIAL='CHIP',
 PHYS_PAGE='96',
 XY='(-7775,2600)',
 ROT='0',
 VER='1',
 PACK_TYPE='0402LF',
 LOCATION='R1578',
 CDS_LIB='pure_quanta',
 CDS_PART_NAME='Q_RES_0402LF-49.9,1%,1/16W,CHIP,CS04992FB07',
 PART_NUMBER='CS04992FB07',
 VALUE='49.9',
 PRIM_FILE='./archive_libs/logical/q_res/chips/chips.prt';

PART_NAME
 R1579 'Q_RES_0402LF-49.9,1%,1/16W,CHIP,CS04992FB07':;

SECTION_NUMBER 1
 '@T6G_MB_LIB.T6G(SCH_1):PAGE96_I242@PURE_QUANTA.Q_RES(CHIPS)':
 C_PATH='@t6g_mb_lib.t6g(sch_1):page96_i242@pure_quanta.q_res(chips)',
 P_PATH='@t6g_mb_lib.t6g(sch_1):page97_i242@pure_quanta.q_res(chips)',
 PATH='I242',
 DRAWING='@T6G_MB_LIB.T6G(SCH_1):PAGE96',
 WATTAGE='1/16W',
 TOLERANCE='1%',
 MATERIAL='CHIP',
 PHYS_PAGE='97',
 XY='(-7775,2300)',
 ROT='0',
 VER='1',
 PACK_TYPE='0402LF',
 LOCATION='R1579',
 CDS_LIB='pure_quanta',
 CDS_PART_NAME='Q_RES_0402LF-49.9,1%,1/16W,CHIP,CS04992FB07',
 PART_NUMBER='CS04992FB07',
 VALUE='49.9',
 PRIM_FILE='./archive_libs/logical/q_res/chips/chips.prt';

PART_NAME
 R1580 'Q_RES_0402LF-49.9,1%,1/16W,CHIP,CS04992FB07':;

SECTION_NUMBER 1
 '@T6G_MB_LIB.T6G(SCH_1):PAGE97_I244@PURE_QUANTA.Q_RES(CHIPS)':
 C_PATH='@t6g_mb_lib.t6g(sch_1):page97_i244@pure_quanta.q_res(chips)',
 P_PATH='@t6g_mb_lib.t6g(sch_1):page98_i244@pure_quanta.q_res(chips)',
 PATH='I244',
 DRAWING='@T6G_MB_LIB.T6G(SCH_1):PAGE97',
 WATTAGE='1/16W',
 TOLERANCE='1%',
 MATERIAL='CHIP',
 PHYS_PAGE='98',
 XY='(-7475,2725)',
 ROT='0',
 VER='1',
 PACK_TYPE='0402LF',
 LOCATION='R1580',
 CDS_LIB='pure_quanta',
 CDS_PART_NAME='Q_RES_0402LF-49.9,1%,1/16W,CHIP,CS04992FB07',
 PART_NUMBER='CS04992FB07',
 VALUE='49.9',
 PRIM_FILE='./archive_libs/logical/q_res/chips/chips.prt';

PART_NAME
 R1581 'Q_RES_0402LF-49.9,1%,1/16W,CHIP,CS04992FB07':;

SECTION_NUMBER 1
 '@T6G_MB_LIB.T6G(SCH_1):PAGE98_I242@PURE_QUANTA.Q_RES(CHIPS)':
 C_PATH='@t6g_mb_lib.t6g(sch_1):page98_i242@pure_quanta.q_res(chips)',
 P_PATH='@t6g_mb_lib.t6g(sch_1):page99_i242@pure_quanta.q_res(chips)',
 PATH='I242',
 DRAWING='@T6G_MB_LIB.T6G(SCH_1):PAGE98',
 WATTAGE='1/16W',
 TOLERANCE='1%',
 MATERIAL='CHIP',
 PHYS_PAGE='99',
 XY='(-7825,2750)',
 ROT='0',
 VER='1',
 PACK_TYPE='0402LF',
 LOCATION='R1581',
 CDS_LIB='pure_quanta',
 CDS_PART_NAME='Q_RES_0402LF-49.9,1%,1/16W,CHIP,CS04992FB07',
 PART_NUMBER='CS04992FB07',
 VALUE='49.9',
 PRIM_FILE='./archive_libs/logical/q_res/chips/chips.prt';

PART_NAME
 R1582 'Q_RES_0402LF-49.9,1%,1/16W,CHIP,CS04992FB07':;

SECTION_NUMBER 1
 '@T6G_MB_LIB.T6G(SCH_1):PAGE99_I242@PURE_QUANTA.Q_RES(CHIPS)':
 C_PATH='@t6g_mb_lib.t6g(sch_1):page99_i242@pure_quanta.q_res(chips)',
 P_PATH='@t6g_mb_lib.t6g(sch_1):page100_i242@pure_quanta.q_res(chips)',
 PATH='I242',
 DRAWING='@T6G_MB_LIB.T6G(SCH_1):PAGE99',
 WATTAGE='1/16W',
 TOLERANCE='1%',
 MATERIAL='CHIP',
 PHYS_PAGE='100',
 XY='(-7925,2625)',
 ROT='0',
 VER='1',
 PACK_TYPE='0402LF',
 LOCATION='R1582',
 CDS_LIB='pure_quanta',
 CDS_PART_NAME='Q_RES_0402LF-49.9,1%,1/16W,CHIP,CS04992FB07',
 PART_NUMBER='CS04992FB07',
 VALUE='49.9',
 PRIM_FILE='./archive_libs/logical/q_res/chips/chips.prt';

PART_NAME
 R1583 'Q_RES_0402LF-49.9,1%,1/16W,CHIP,CS04992FB07':;

SECTION_NUMBER 1
 '@T6G_MB_LIB.T6G(SCH_1):PAGE100_I242@PURE_QUANTA.Q_RES(CHIPS)':
 C_PATH='@t6g_mb_lib.t6g(sch_1):page100_i242@pure_quanta.q_res(chips)',
 P_PATH='@t6g_mb_lib.t6g(sch_1):page101_i242@pure_quanta.q_res(chips)',
 PATH='I242',
 DRAWING='@T6G_MB_LIB.T6G(SCH_1):PAGE100',
 WATTAGE='1/16W',
 TOLERANCE='1%',
 MATERIAL='CHIP',
 PHYS_PAGE='101',
 XY='(-7850,2800)',
 ROT='0',
 VER='1',
 PACK_TYPE='0402LF',
 LOCATION='R1583',
 CDS_LIB='pure_quanta',
 CDS_PART_NAME='Q_RES_0402LF-49.9,1%,1/16W,CHIP,CS04992FB07',
 PART_NUMBER='CS04992FB07',
 VALUE='49.9',
 PRIM_FILE='./archive_libs/logical/q_res/chips/chips.prt';

PART_NAME
 R1584 'Q_RES_0402LF-49.9,1%,1/16W,CHIP,CS04992FB07':;

SECTION_NUMBER 1
 '@T6G_MB_LIB.T6G(SCH_1):PAGE101_I242@PURE_QUANTA.Q_RES(CHIPS)':
 C_PATH='@t6g_mb_lib.t6g(sch_1):page101_i242@pure_quanta.q_res(chips)',
 P_PATH='@t6g_mb_lib.t6g(sch_1):page102_i242@pure_quanta.q_res(chips)',
 PATH='I242',
 DRAWING='@T6G_MB_LIB.T6G(SCH_1):PAGE101',
 WATTAGE='1/16W',
 TOLERANCE='1%',
 MATERIAL='CHIP',
 PHYS_PAGE='102',
 XY='(-7925,2875)',
 ROT='0',
 VER='1',
 PACK_TYPE='0402LF',
 LOCATION='R1584',
 CDS_LIB='pure_quanta',
 CDS_PART_NAME='Q_RES_0402LF-49.9,1%,1/16W,CHIP,CS04992FB07',
 PART_NUMBER='CS04992FB07',
 VALUE='49.9',
 PRIM_FILE='./archive_libs/logical/q_res/chips/chips.prt';

PART_NAME
 R1585 'Q_RES_0402LF-49.9,1%,1/16W,CHIP,CS04992FB07':;

SECTION_NUMBER 1
 '@T6G_MB_LIB.T6G(SCH_1):PAGE102_I242@PURE_QUANTA.Q_RES(CHIPS)':
 C_PATH='@t6g_mb_lib.t6g(sch_1):page102_i242@pure_quanta.q_res(chips)',
 P_PATH='@t6g_mb_lib.t6g(sch_1):page103_i242@pure_quanta.q_res(chips)',
 PATH='I242',
 DRAWING='@T6G_MB_LIB.T6G(SCH_1):PAGE102',
 WATTAGE='1/16W',
 TOLERANCE='1%',
 MATERIAL='CHIP',
 PHYS_PAGE='103',
 XY='(-7850,2750)',
 ROT='0',
 VER='1',
 PACK_TYPE='0402LF',
 LOCATION='R1585',
 CDS_LIB='pure_quanta',
 CDS_PART_NAME='Q_RES_0402LF-49.9,1%,1/16W,CHIP,CS04992FB07',
 PART_NUMBER='CS04992FB07',
 VALUE='49.9',
 PRIM_FILE='./archive_libs/logical/q_res/chips/chips.prt';

PART_NAME
 R1586 'Q_RES_0402LF-49.9,1%,1/16W,CHIP,CS04992FB07':;

SECTION_NUMBER 1
 '@T6G_MB_LIB.T6G(SCH_1):PAGE103_I244@PURE_QUANTA.Q_RES(CHIPS)':
 C_PATH='@t6g_mb_lib.t6g(sch_1):page103_i244@pure_quanta.q_res(chips)',
 P_PATH='@t6g_mb_lib.t6g(sch_1):page104_i244@pure_quanta.q_res(chips)',
 PATH='I244',
 DRAWING='@T6G_MB_LIB.T6G(SCH_1):PAGE103',
 WATTAGE='1/16W',
 TOLERANCE='1%',
 MATERIAL='CHIP',
 PHYS_PAGE='104',
 XY='(-7525,2575)',
 ROT='0',
 VER='1',
 PACK_TYPE='0402LF',
 LOCATION='R1586',
 CDS_LIB='pure_quanta',
 CDS_PART_NAME='Q_RES_0402LF-49.9,1%,1/16W,CHIP,CS04992FB07',
 PART_NUMBER='CS04992FB07',
 VALUE='49.9',
 PRIM_FILE='./archive_libs/logical/q_res/chips/chips.prt';

PART_NAME
 R1587 'Q_RES_0402LF-49.9,1%,1/16W,CHIP,CS04992FB07':;

SECTION_NUMBER 1
 '@T6G_MB_LIB.T6G(SCH_1):PAGE104_I244@PURE_QUANTA.Q_RES(CHIPS)':
 C_PATH='@t6g_mb_lib.t6g(sch_1):page104_i244@pure_quanta.q_res(chips)',
 P_PATH='@t6g_mb_lib.t6g(sch_1):page105_i244@pure_quanta.q_res(chips)',
 PATH='I244',
 DRAWING='@T6G_MB_LIB.T6G(SCH_1):PAGE104',
 WATTAGE='1/16W',
 TOLERANCE='1%',
 MATERIAL='CHIP',
 PHYS_PAGE='105',
 XY='(-7700,2625)',
 ROT='0',
 VER='1',
 PACK_TYPE='0402LF',
 LOCATION='R1587',
 CDS_LIB='pure_quanta',
 CDS_PART_NAME='Q_RES_0402LF-49.9,1%,1/16W,CHIP,CS04992FB07',
 PART_NUMBER='CS04992FB07',
 VALUE='49.9',
 PRIM_FILE='./archive_libs/logical/q_res/chips/chips.prt';

PART_NAME
 R1588 'Q_RES_0402LF-49.9,1%,1/16W,CHIP,CS04992FB07':;

SECTION_NUMBER 1
 '@T6G_MB_LIB.T6G(SCH_1):PAGE105_I242@PURE_QUANTA.Q_RES(CHIPS)':
 C_PATH='@t6g_mb_lib.t6g(sch_1):page105_i242@pure_quanta.q_res(chips)',
 P_PATH='@t6g_mb_lib.t6g(sch_1):page106_i242@pure_quanta.q_res(chips)',
 PATH='I242',
 DRAWING='@T6G_MB_LIB.T6G(SCH_1):PAGE105',
 WATTAGE='1/16W',
 TOLERANCE='1%',
 MATERIAL='CHIP',
 PHYS_PAGE='106',
 XY='(-7725,2575)',
 ROT='0',
 VER='1',
 PACK_TYPE='0402LF',
 LOCATION='R1588',
 CDS_LIB='pure_quanta',
 CDS_PART_NAME='Q_RES_0402LF-49.9,1%,1/16W,CHIP,CS04992FB07',
 PART_NUMBER='CS04992FB07',
 VALUE='49.9',
 PRIM_FILE='./archive_libs/logical/q_res/chips/chips.prt';

PART_NAME
 R1589 'Q_RES_0402LF-49.9,1%,1/16W,CHIP,CS04992FB07':;

SECTION_NUMBER 1
 '@T6G_MB_LIB.T6G(SCH_1):PAGE106_I242@PURE_QUANTA.Q_RES(CHIPS)':
 C_PATH='@t6g_mb_lib.t6g(sch_1):page106_i242@pure_quanta.q_res(chips)',
 P_PATH='@t6g_mb_lib.t6g(sch_1):page107_i242@pure_quanta.q_res(chips)',
 PATH='I242',
 DRAWING='@T6G_MB_LIB.T6G(SCH_1):PAGE106',
 WATTAGE='1/16W',
 TOLERANCE='1%',
 MATERIAL='CHIP',
 PHYS_PAGE='107',
 XY='(-7600,2575)',
 ROT='0',
 VER='1',
 PACK_TYPE='0402LF',
 LOCATION='R1589',
 CDS_LIB='pure_quanta',
 CDS_PART_NAME='Q_RES_0402LF-49.9,1%,1/16W,CHIP,CS04992FB07',
 PART_NUMBER='CS04992FB07',
 VALUE='49.9',
 PRIM_FILE='./archive_libs/logical/q_res/chips/chips.prt';

PART_NAME
 R1590 'Q_RES_0402LF-49.9,1%,1/16W,CHIP,CS04992FB07':;

SECTION_NUMBER 1
 '@T6G_MB_LIB.T6G(SCH_1):PAGE107_I241@PURE_QUANTA.Q_RES(CHIPS)':
 C_PATH='@t6g_mb_lib.t6g(sch_1):page107_i241@pure_quanta.q_res(chips)',
 P_PATH='@t6g_mb_lib.t6g(sch_1):page108_i241@pure_quanta.q_res(chips)',
 PATH='I241',
 DRAWING='@T6G_MB_LIB.T6G(SCH_1):PAGE107',
 WATTAGE='1/16W',
 TOLERANCE='1%',
 MATERIAL='CHIP',
 PHYS_PAGE='108',
 XY='(-7750,2550)',
 ROT='0',
 VER='1',
 PACK_TYPE='0402LF',
 LOCATION='R1590',
 CDS_LIB='pure_quanta',
 CDS_PART_NAME='Q_RES_0402LF-49.9,1%,1/16W,CHIP,CS04992FB07',
 PART_NUMBER='CS04992FB07',
 VALUE='49.9',
 PRIM_FILE='./archive_libs/logical/q_res/chips/chips.prt';

PART_NAME
 R1591 'Q_RES_0402LF-49.9,1%,1/16W,CHIP,CS04992FB07':;

SECTION_NUMBER 1
 '@T6G_MB_LIB.T6G(SCH_1):PAGE108_I241@PURE_QUANTA.Q_RES(CHIPS)':
 C_PATH='@t6g_mb_lib.t6g(sch_1):page108_i241@pure_quanta.q_res(chips)',
 P_PATH='@t6g_mb_lib.t6g(sch_1):page109_i241@pure_quanta.q_res(chips)',
 PATH='I241',
 DRAWING='@T6G_MB_LIB.T6G(SCH_1):PAGE108',
 WATTAGE='1/16W',
 TOLERANCE='1%',
 MATERIAL='CHIP',
 PHYS_PAGE='109',
 XY='(-7700,2625)',
 ROT='0',
 VER='1',
 PACK_TYPE='0402LF',
 LOCATION='R1591',
 CDS_LIB='pure_quanta',
 CDS_PART_NAME='Q_RES_0402LF-49.9,1%,1/16W,CHIP,CS04992FB07',
 PART_NUMBER='CS04992FB07',
 VALUE='49.9',
 PRIM_FILE='./archive_libs/logical/q_res/chips/chips.prt';

PART_NAME
 R1592 'Q_RES_0402LF-33,5%,1/16W,CHIP,CS03302JB10':;

SECTION_NUMBER 1
 '@T6G_MB_LIB.T6G(SCH_1):PAGE29_I426@PURE_QUANTA.Q_RES(CHIPS)':
 C_PATH='@t6g_mb_lib.t6g(sch_1):page29_i426@pure_quanta.q_res(chips)',
 P_PATH='@t6g_mb_lib.t6g(sch_1):page29_i426@pure_quanta.q_res(chips)',
 PATH='I426',
 DRAWING='@T6G_MB_LIB.T6G(SCH_1):PAGE29',
 WATTAGE='1/16W',
 TOLERANCE='5%',
 MATERIAL='CHIP',
 PHYS_PAGE='29',
 XY='(-6950,5600)',
 ROT='0',
 VER='1',
 PACK_TYPE='0402LF',
 LOCATION='R1592',
 CDS_LIB='pure_quanta',
 CDS_PART_NAME='Q_RES_0402LF-33,5%,1/16W,CHIP,CS03302JB10',
 PART_NUMBER='CS03302JB10',
 VALUE='33',
 PRIM_FILE='./archive_libs/logical/q_res/chips/chips.prt';

PART_NAME
 R1593 'Q_RES_0402LF-33,5%,1/16W,CHIP,CS03302JB10':;

SECTION_NUMBER 1
 '@T6G_MB_LIB.T6G(SCH_1):PAGE29_I427@PURE_QUANTA.Q_RES(CHIPS)':
 C_PATH='@t6g_mb_lib.t6g(sch_1):page29_i427@pure_quanta.q_res(chips)',
 P_PATH='@t6g_mb_lib.t6g(sch_1):page29_i427@pure_quanta.q_res(chips)',
 PATH='I427',
 DRAWING='@T6G_MB_LIB.T6G(SCH_1):PAGE29',
 WATTAGE='1/16W',
 TOLERANCE='5%',
 MATERIAL='CHIP',
 PHYS_PAGE='29',
 XY='(-6950,4500)',
 ROT='0',
 VER='1',
 PACK_TYPE='0402LF',
 LOCATION='R1593',
 CDS_LIB='pure_quanta',
 CDS_PART_NAME='Q_RES_0402LF-33,5%,1/16W,CHIP,CS03302JB10',
 PART_NUMBER='CS03302JB10',
 VALUE='33',
 PRIM_FILE='./archive_libs/logical/q_res/chips/chips.prt';

PART_NAME
 R1594 'Q_RES_0402LF-33.2,1%,1/16W,CHIP,CS03322FB03':;

SECTION_NUMBER 1
 '@T6G_MB_LIB.T6G(SCH_1):PAGE337_I31@PURE_QUANTA.Q_RES(CHIPS)':
 C_PATH='@t6g_mb_lib.t6g(sch_1):page337_i31@pure_quanta.q_res(chips)',
 P_PATH='@t6g_mb_lib.t6g(sch_1):page133_i31@pure_quanta.q_res(chips)',
 PATH='I31',
 DRAWING='@T6G_MB_LIB.T6G(SCH_1):PAGE337',
 WATTAGE='1/16W',
 TOLERANCE='1%',
 MATERIAL='CHIP',
 PHYS_PAGE='133',
 XY='(-6725,4250)',
 ROT='0',
 VER='1',
 PACK_TYPE='0402LF',
 LOCATION='R1594',
 CDS_LIB='pure_quanta',
 CDS_PART_NAME='Q_RES_0402LF-33.2,1%,1/16W,CHIP,CS03322FB03',
 PART_NUMBER='CS03322FB03',
 VALUE='33.2',
 PRIM_FILE='./archive_libs/logical/q_res/chips/chips.prt';

PART_NAME
 R1595 'Q_RES_0402LF-33.2,1%,1/16W,CHIP,CS03322FB03':;

SECTION_NUMBER 1
 '@T6G_MB_LIB.T6G(SCH_1):PAGE337_I44@PURE_QUANTA.Q_RES(CHIPS)':
 C_PATH='@t6g_mb_lib.t6g(sch_1):page337_i44@pure_quanta.q_res(chips)',
 P_PATH='@t6g_mb_lib.t6g(sch_1):page133_i44@pure_quanta.q_res(chips)',
 PATH='I44',
 DRAWING='@T6G_MB_LIB.T6G(SCH_1):PAGE337',
 WATTAGE='1/16W',
 TOLERANCE='1%',
 MATERIAL='CHIP',
 PHYS_PAGE='133',
 XY='(-5325,5725)',
 ROT='0',
 VER='1',
 PACK_TYPE='0402LF',
 LOCATION='R1595',
 CDS_LIB='pure_quanta',
 CDS_PART_NAME='Q_RES_0402LF-33.2,1%,1/16W,CHIP,CS03322FB03',
 PART_NUMBER='CS03322FB03',
 VALUE='33.2',
 PRIM_FILE='./archive_libs/logical/q_res/chips/chips.prt';

PART_NAME
 R1605 'Q_RES_0402LF-1K,1%,1/16W,CHIP,CS21002FB06':;

SECTION_NUMBER 1
 '@T6G_MB_LIB.T6G(SCH_1):PAGE345_I83@PURE_QUANTA.Q_RES(CHIPS)':
 C_PATH='@t6g_mb_lib.t6g(sch_1):page345_i83@pure_quanta.q_res(chips)',
 P_PATH='@t6g_mb_lib.t6g(sch_1):page144_i83@pure_quanta.q_res(chips)',
 PATH='I83',
 DRAWING='@T6G_MB_LIB.T6G(SCH_1):PAGE345',
 WATTAGE='1/16W',
 TOLERANCE='1%',
 MATERIAL='CHIP',
 PHYS_PAGE='144',
 XY='(13300,2825)',
 ROT='0',
 VER='2',
 PACK_TYPE='0402LF',
 LOCATION='R1605',
 CDS_LIB='pure_quanta',
 CDS_PART_NAME='Q_RES_0402LF-1K,1%,1/16W,CHIP,CS21002FB06',
 PART_NUMBER='CS21002FB06',
 VALUE='1K',
 PRIM_FILE='./archive_libs/logical/q_res/chips/chips.prt';

PART_NAME
 R1616 'Q_RES_0402LF-33,5%,1/16W,CHIP,CS03302JB10':;

SECTION_NUMBER 1
 '@T6G_MB_LIB.T6G(SCH_1):PAGE80_I157@PURE_QUANTA.Q_RES(CHIPS)':
 C_PATH='@t6g_mb_lib.t6g(sch_1):page80_i157@pure_quanta.q_res(chips)',
 P_PATH='@t6g_mb_lib.t6g(sch_1):page81_i157@pure_quanta.q_res(chips)',
 PATH='I157',
 DRAWING='@T6G_MB_LIB.T6G(SCH_1):PAGE80',
 BOM_COST='MEM',
 WATTAGE='1/16W',
 TOLERANCE='5%',
 MATERIAL='CHIP',
 PHYS_PAGE='81',
 XY='(-3225,4275)',
 ROT='0',
 VER='1',
 PACK_TYPE='0402LF',
 LOCATION='R1616',
 CDS_LIB='pure_quanta',
 CDS_PART_NAME='Q_RES_0402LF-33,5%,1/16W,CHIP,CS03302JB10',
 PART_NUMBER='CS03302JB10',
 VALUE='33',
 PRIM_FILE='./archive_libs/logical/q_res/chips/chips.prt';

PART_NAME
 R1619 'Q_RES_0402LF-0,5%,1/16W,CHIP,CS00002JB13':;

SECTION_NUMBER 1
 '@T6G_MB_LIB.T6G(SCH_1):PAGE149_I92@PURE_QUANTA.Q_RES(CHIPS)':
 C_PATH='@t6g_mb_lib.t6g(sch_1):page149_i92@pure_quanta.q_res(chips)',
 P_PATH='@t6g_mb_lib.t6g(sch_1):page172_i92@pure_quanta.q_res(chips)',
 PATH='I92',
 DRAWING='@T6G_MB_LIB.T6G(SCH_1):PAGE149',
 WATTAGE='1/16W',
 TOLERANCE='5%',
 MATERIAL='CHIP',
 PHYS_PAGE='172',
 XY='(-8325,3350)',
 ROT='0',
 VER='1',
 PACK_TYPE='0402LF',
 LOCATION='R1619',
 CDS_LIB='pure_quanta',
 CDS_PART_NAME='Q_RES_0402LF-0,5%,1/16W,CHIP,CS00002JB13',
 PART_NUMBER='CS00002JB13',
 VALUE='0',
 PRIM_FILE='./archive_libs/logical/q_res/chips/chips.prt';

PART_NAME
 R1620 'Q_RES_0402LF-33,5%,1/16W,CHIP,CS03302JB10':;

SECTION_NUMBER 1
 '@T6G_MB_LIB.T6G(SCH_1):PAGE149_I149@PURE_QUANTA.Q_RES(CHIPS)':
 C_PATH='@t6g_mb_lib.t6g(sch_1):page149_i149@pure_quanta.q_res(chips)',
 P_PATH='@t6g_mb_lib.t6g(sch_1):page172_i149@pure_quanta.q_res(chips)',
 PATH='I149',
 DRAWING='@T6G_MB_LIB.T6G(SCH_1):PAGE149',
 WATTAGE='1/16W',
 TOLERANCE='5%',
 MATERIAL='CHIP',
 PHYS_PAGE='172',
 XY='(-6300,5750)',
 ROT='0',
 VER='1',
 PACK_TYPE='0402LF',
 LOCATION='R1620',
 CDS_LIB='pure_quanta',
 CDS_PART_NAME='Q_RES_0402LF-33,5%,1/16W,CHIP,CS03302JB10',
 PART_NUMBER='CS03302JB10',
 VALUE='33',
 PRIM_FILE='./archive_libs/logical/q_res/chips/chips.prt';

PART_NAME
 R1621 'Q_RES_0402LF-1K,1%,1/16W,CHIP,CS21002FB06':;

SECTION_NUMBER 1
 '@T6G_MB_LIB.T6G(SCH_1):PAGE149_I146@PURE_QUANTA.Q_RES(CHIPS)':
 C_PATH='@t6g_mb_lib.t6g(sch_1):page149_i146@pure_quanta.q_res(chips)',
 P_PATH='@t6g_mb_lib.t6g(sch_1):page172_i146@pure_quanta.q_res(chips)',
 PATH='I146',
 DRAWING='@T6G_MB_LIB.T6G(SCH_1):PAGE149',
 WATTAGE='1/16W',
 TOLERANCE='1%',
 MATERIAL='CHIP',
 PHYS_PAGE='172',
 XY='(-6050,6250)',
 ROT='0',
 VER='2',
 PACK_TYPE='0402LF',
 LOCATION='R1621',
 CDS_LIB='pure_quanta',
 CDS_PART_NAME='Q_RES_0402LF-1K,1%,1/16W,CHIP,CS21002FB06',
 PART_NUMBER='CS21002FB06',
 VALUE='1K',
 PRIM_FILE='./archive_libs/logical/q_res/chips/chips.prt';

PART_NAME
 R1622 'Q_RES_0402LF-4.7K,5%,1/16W,CHIP,CS24702JB10':;

SECTION_NUMBER 1
 '@T6G_MB_LIB.T6G(SCH_1):PAGE149_I83@PURE_QUANTA.Q_RES(CHIPS)':
 C_PATH='@t6g_mb_lib.t6g(sch_1):page149_i83@pure_quanta.q_res(chips)',
 P_PATH='@t6g_mb_lib.t6g(sch_1):page172_i83@pure_quanta.q_res(chips)',
 PATH='I83',
 DRAWING='@T6G_MB_LIB.T6G(SCH_1):PAGE149',
 WATTAGE='1/16W',
 TOLERANCE='5%',
 MATERIAL='CHIP',
 PHYS_PAGE='172',
 XY='(-7475,1200)',
 ROT='0',
 VER='2',
 PACK_TYPE='0402LF',
 LOCATION='R1622',
 CDS_LIB='pure_quanta',
 CDS_PART_NAME='Q_RES_0402LF-4.7K,5%,1/16W,CHIP,CS24702JB10',
 PART_NUMBER='CS24702JB10',
 VALUE='4.7K',
 PRIM_FILE='./archive_libs/logical/q_res/chips/chips.prt';

PART_NAME
 R1624 'Q_RES_0402LF-1K,1%,1/16W,CHIP,CS21002FB06':;

SECTION_NUMBER 1
 '@T6G_MB_LIB.T6G(SCH_1):PAGE149_I111@PURE_QUANTA.Q_RES(CHIPS)':
 C_PATH='@t6g_mb_lib.t6g(sch_1):page149_i111@pure_quanta.q_res(chips)',
 P_PATH='@t6g_mb_lib.t6g(sch_1):page172_i111@pure_quanta.q_res(chips)',
 PATH='I111',
 DRAWING='@T6G_MB_LIB.T6G(SCH_1):PAGE149',
 WATTAGE='1/16W',
 TOLERANCE='1%',
 MATERIAL='CHIP',
 PHYS_PAGE='172',
 XY='(-3650,6125)',
 ROT='0',
 VER='2',
 PACK_TYPE='0402LF',
 LOCATION='R1624',
 CDS_LIB='pure_quanta',
 CDS_PART_NAME='Q_RES_0402LF-1K,1%,1/16W,CHIP,CS21002FB06',
 PART_NUMBER='CS21002FB06',
 VALUE='1K',
 PRIM_FILE='./archive_libs/logical/q_res/chips/chips.prt';

PART_NAME
 R1625 'Q_RES_0402LF-0,5%,1/16W,CHIP,CS00002JB13':;

SECTION_NUMBER 1
 '@T6G_MB_LIB.T6G(SCH_1):PAGE149_I53@PURE_QUANTA.Q_RES(CHIPS)':
 C_PATH='@t6g_mb_lib.t6g(sch_1):page149_i53@pure_quanta.q_res(chips)',
 P_PATH='@t6g_mb_lib.t6g(sch_1):page172_i53@pure_quanta.q_res(chips)',
 PATH='I53',
 DRAWING='@T6G_MB_LIB.T6G(SCH_1):PAGE149',
 WATTAGE='1/16W',
 TOLERANCE='5%',
 MATERIAL='CHIP',
 PHYS_PAGE='172',
 XY='(-5675,4075)',
 ROT='0',
 VER='1',
 PACK_TYPE='0402LF',
 LOCATION='R1625',
 CDS_LIB='pure_quanta',
 CDS_PART_NAME='Q_RES_0402LF-0,5%,1/16W,CHIP,CS00002JB13',
 PART_NUMBER='CS00002JB13',
 VALUE='0',
 PRIM_FILE='./archive_libs/logical/q_res/chips/chips.prt';

PART_NAME
 R1626 'Q_RES_0402LF-1K,1%,1/16W,CHIP,CS21002FB06':;

SECTION_NUMBER 1
 '@T6G_MB_LIB.T6G(SCH_1):PAGE149_I115@PURE_QUANTA.Q_RES(CHIPS)':
 C_PATH='@t6g_mb_lib.t6g(sch_1):page149_i115@pure_quanta.q_res(chips)',
 P_PATH='@t6g_mb_lib.t6g(sch_1):page172_i115@pure_quanta.q_res(chips)',
 PATH='I115',
 DRAWING='@T6G_MB_LIB.T6G(SCH_1):PAGE149',
 WATTAGE='1/16W',
 TOLERANCE='1%',
 MATERIAL='CHIP',
 PHYS_PAGE='172',
 XY='(-3525,6125)',
 ROT='0',
 VER='2',
 PACK_TYPE='0402LF',
 LOCATION='R1626',
 CDS_LIB='pure_quanta',
 CDS_PART_NAME='Q_RES_0402LF-1K,1%,1/16W,CHIP,CS21002FB06',
 PART_NUMBER='CS21002FB06',
 VALUE='1K',
 PRIM_FILE='./archive_libs/logical/q_res/chips/chips.prt';

PART_NAME
 R1627 'Q_RES_0402LF-1K,1%,1/16W,CHIP,CS21002FB06':;

SECTION_NUMBER 1
 '@T6G_MB_LIB.T6G(SCH_1):PAGE149_I116@PURE_QUANTA.Q_RES(CHIPS)':
 C_PATH='@t6g_mb_lib.t6g(sch_1):page149_i116@pure_quanta.q_res(chips)',
 P_PATH='@t6g_mb_lib.t6g(sch_1):page172_i116@pure_quanta.q_res(chips)',
 PATH='I116',
 DRAWING='@T6G_MB_LIB.T6G(SCH_1):PAGE149',
 WATTAGE='1/16W',
 TOLERANCE='1%',
 MATERIAL='CHIP',
 PHYS_PAGE='172',
 XY='(-3400,6125)',
 ROT='0',
 VER='2',
 PACK_TYPE='0402LF',
 LOCATION='R1627',
 CDS_LIB='pure_quanta',
 CDS_PART_NAME='Q_RES_0402LF-1K,1%,1/16W,CHIP,CS21002FB06',
 PART_NUMBER='CS21002FB06',
 VALUE='1K',
 PRIM_FILE='./archive_libs/logical/q_res/chips/chips.prt';

PART_NAME
 R1628 'Q_RES_0402LF-1K,1%,1/16W,CHIP,CS21002FB06':;

SECTION_NUMBER 1
 '@T6G_MB_LIB.T6G(SCH_1):PAGE149_I117@PURE_QUANTA.Q_RES(CHIPS)':
 C_PATH='@t6g_mb_lib.t6g(sch_1):page149_i117@pure_quanta.q_res(chips)',
 P_PATH='@t6g_mb_lib.t6g(sch_1):page172_i117@pure_quanta.q_res(chips)',
 PATH='I117',
 DRAWING='@T6G_MB_LIB.T6G(SCH_1):PAGE149',
 WATTAGE='1/16W',
 TOLERANCE='1%',
 MATERIAL='CHIP',
 PHYS_PAGE='172',
 XY='(-3275,6125)',
 ROT='0',
 VER='2',
 PACK_TYPE='0402LF',
 LOCATION='R1628',
 CDS_LIB='pure_quanta',
 CDS_PART_NAME='Q_RES_0402LF-1K,1%,1/16W,CHIP,CS21002FB06',
 PART_NUMBER='CS21002FB06',
 VALUE='1K',
 PRIM_FILE='./archive_libs/logical/q_res/chips/chips.prt';

PART_NAME
 R1629 'Q_RES_0402LF-1K,1%,1/16W,CHIP,CS21002FB06':;

SECTION_NUMBER 1
 '@T6G_MB_LIB.T6G(SCH_1):PAGE149_I112@PURE_QUANTA.Q_RES(CHIPS)':
 C_PATH='@t6g_mb_lib.t6g(sch_1):page149_i112@pure_quanta.q_res(chips)',
 P_PATH='@t6g_mb_lib.t6g(sch_1):page172_i112@pure_quanta.q_res(chips)',
 PATH='I112',
 DRAWING='@T6G_MB_LIB.T6G(SCH_1):PAGE149',
 WATTAGE='1/16W',
 TOLERANCE='1%',
 MATERIAL='CHIP',
 PHYS_PAGE='172',
 XY='(-3675,5325)',
 ROT='0',
 VER='2',
 PACK_TYPE='0402LF',
 LOCATION='R1629',
 CDS_LIB='pure_quanta',
 CDS_PART_NAME='Q_RES_0402LF-1K,1%,1/16W,CHIP,CS21002FB06',
 PART_NUMBER='CS21002FB06',
 VALUE='1K',
 PRIM_FILE='./archive_libs/logical/q_res/chips/chips.prt';

PART_NAME
 R1630 'Q_RES_0402LF-1K,1%,1/16W,CHIP,CS21002FB06':;

SECTION_NUMBER 1
 '@T6G_MB_LIB.T6G(SCH_1):PAGE149_I118@PURE_QUANTA.Q_RES(CHIPS)':
 C_PATH='@t6g_mb_lib.t6g(sch_1):page149_i118@pure_quanta.q_res(chips)',
 P_PATH='@t6g_mb_lib.t6g(sch_1):page172_i118@pure_quanta.q_res(chips)',
 PATH='I118',
 DRAWING='@T6G_MB_LIB.T6G(SCH_1):PAGE149',
 WATTAGE='1/16W',
 TOLERANCE='1%',
 MATERIAL='CHIP',
 PHYS_PAGE='172',
 XY='(-3150,6125)',
 ROT='0',
 VER='2',
 PACK_TYPE='0402LF',
 LOCATION='R1630',
 CDS_LIB='pure_quanta',
 CDS_PART_NAME='Q_RES_0402LF-1K,1%,1/16W,CHIP,CS21002FB06',
 PART_NUMBER='CS21002FB06',
 VALUE='1K',
 PRIM_FILE='./archive_libs/logical/q_res/chips/chips.prt';

PART_NAME
 R1631 'Q_RES_0402LF-33,5%,1/16W,CHIP,CS03302JB10':;

SECTION_NUMBER 1
 '@T6G_MB_LIB.T6G(SCH_1):PAGE149_I113@PURE_QUANTA.Q_RES(CHIPS)':
 C_PATH='@t6g_mb_lib.t6g(sch_1):page149_i113@pure_quanta.q_res(chips)',
 P_PATH='@t6g_mb_lib.t6g(sch_1):page172_i113@pure_quanta.q_res(chips)',
 PATH='I113',
 DRAWING='@T6G_MB_LIB.T6G(SCH_1):PAGE149',
 WATTAGE='1/16W',
 TOLERANCE='5%',
 MATERIAL='CHIP',
 PHYS_PAGE='172',
 XY='(-3025,5600)',
 ROT='0',
 VER='1',
 PACK_TYPE='0402LF',
 LOCATION='R1631',
 CDS_LIB='pure_quanta',
 CDS_PART_NAME='Q_RES_0402LF-33,5%,1/16W,CHIP,CS03302JB10',
 PART_NUMBER='CS03302JB10',
 VALUE='33',
 PRIM_FILE='./archive_libs/logical/q_res/chips/chips.prt';

PART_NAME
 R1632 'Q_RES_0402LF-33,5%,1/16W,CHIP,CS03302JB10':;

SECTION_NUMBER 1
 '@T6G_MB_LIB.T6G(SCH_1):PAGE149_I114@PURE_QUANTA.Q_RES(CHIPS)':
 C_PATH='@t6g_mb_lib.t6g(sch_1):page149_i114@pure_quanta.q_res(chips)',
 P_PATH='@t6g_mb_lib.t6g(sch_1):page172_i114@pure_quanta.q_res(chips)',
 PATH='I114',
 DRAWING='@T6G_MB_LIB.T6G(SCH_1):PAGE149',
 WATTAGE='1/16W',
 TOLERANCE='5%',
 MATERIAL='CHIP',
 PHYS_PAGE='172',
 XY='(-3025,5550)',
 ROT='0',
 VER='1',
 PACK_TYPE='0402LF',
 LOCATION='R1632',
 CDS_LIB='pure_quanta',
 CDS_PART_NAME='Q_RES_0402LF-33,5%,1/16W,CHIP,CS03302JB10',
 PART_NUMBER='CS03302JB10',
 VALUE='33',
 PRIM_FILE='./archive_libs/logical/q_res/chips/chips.prt';

PART_NAME
 R1633 'Q_RES_0402LF-0,5%,1/16W,CHIP,CS00002JB13':;

SECTION_NUMBER 1
 '@T6G_MB_LIB.T6G(SCH_1):PAGE149_I7@PURE_QUANTA.Q_RES(CHIPS)':
 C_PATH='@t6g_mb_lib.t6g(sch_1):page149_i7@pure_quanta.q_res(chips)',
 P_PATH='@t6g_mb_lib.t6g(sch_1):page172_i7@pure_quanta.q_res(chips)',
 PATH='I7',
 DRAWING='@T6G_MB_LIB.T6G(SCH_1):PAGE149',
 WATTAGE='1/16W',
 TOLERANCE='5%',
 MATERIAL='CHIP',
 PHYS_PAGE='172',
 XY='(-1675,4225)',
 ROT='0',
 VER='1',
 PACK_TYPE='0402LF',
 LOCATION='R1633',
 CDS_LIB='pure_quanta',
 CDS_PART_NAME='Q_RES_0402LF-0,5%,1/16W,CHIP,CS00002JB13',
 PART_NUMBER='CS00002JB13',
 VALUE='0',
 PRIM_FILE='./archive_libs/logical/q_res/chips/chips.prt';

PART_NAME
 R1634 'Q_RES_0402LF-0,5%,1/16W,CHIP,CS00002JB13':;

SECTION_NUMBER 1
 '@T6G_MB_LIB.T6G(SCH_1):PAGE149_I96@PURE_QUANTA.Q_RES(CHIPS)':
 C_PATH='@t6g_mb_lib.t6g(sch_1):page149_i96@pure_quanta.q_res(chips)',
 P_PATH='@t6g_mb_lib.t6g(sch_1):page172_i96@pure_quanta.q_res(chips)',
 PATH='I96',
 DRAWING='@T6G_MB_LIB.T6G(SCH_1):PAGE149',
 WATTAGE='1/16W',
 TOLERANCE='5%',
 MATERIAL='CHIP',
 PHYS_PAGE='172',
 XY='(-1675,4175)',
 ROT='0',
 VER='1',
 PACK_TYPE='0402LF',
 LOCATION='R1634',
 CDS_LIB='pure_quanta',
 CDS_PART_NAME='Q_RES_0402LF-0,5%,1/16W,CHIP,CS00002JB13',
 PART_NUMBER='CS00002JB13',
 VALUE='0',
 PRIM_FILE='./archive_libs/logical/q_res/chips/chips.prt';

PART_NAME
 R1635 'Q_RES_0402LF-22,1%,1/16W,CHIP,CS02202FB02':;

SECTION_NUMBER 1
 '@T6G_MB_LIB.T6G(SCH_1):PAGE149_I8@PURE_QUANTA.Q_RES(CHIPS)':
 C_PATH='@t6g_mb_lib.t6g(sch_1):page149_i8@pure_quanta.q_res(chips)',
 P_PATH='@t6g_mb_lib.t6g(sch_1):page172_i8@pure_quanta.q_res(chips)',
 PATH='I8',
 DRAWING='@T6G_MB_LIB.T6G(SCH_1):PAGE149',
 WATTAGE='1/16W',
 TOLERANCE='1%',
 MATERIAL='CHIP',
 PHYS_PAGE='172',
 XY='(-1675,4125)',
 ROT='0',
 VER='1',
 PACK_TYPE='0402LF',
 LOCATION='R1635',
 CDS_LIB='pure_quanta',
 CDS_PART_NAME='Q_RES_0402LF-22,1%,1/16W,CHIP,CS02202FB02',
 PART_NUMBER='CS02202FB02',
 VALUE='22',
 PRIM_FILE='./archive_libs/logical/q_res/chips/chips.prt';

PART_NAME
 R1636 'Q_RES_0402LF-22,1%,1/16W,CHIP,CS02202FB02':;

SECTION_NUMBER 1
 '@T6G_MB_LIB.T6G(SCH_1):PAGE149_I9@PURE_QUANTA.Q_RES(CHIPS)':
 C_PATH='@t6g_mb_lib.t6g(sch_1):page149_i9@pure_quanta.q_res(chips)',
 P_PATH='@t6g_mb_lib.t6g(sch_1):page172_i9@pure_quanta.q_res(chips)',
 PATH='I9',
 DRAWING='@T6G_MB_LIB.T6G(SCH_1):PAGE149',
 WATTAGE='1/16W',
 TOLERANCE='1%',
 MATERIAL='CHIP',
 PHYS_PAGE='172',
 XY='(-1675,4075)',
 ROT='0',
 VER='1',
 PACK_TYPE='0402LF',
 LOCATION='R1636',
 CDS_LIB='pure_quanta',
 CDS_PART_NAME='Q_RES_0402LF-22,1%,1/16W,CHIP,CS02202FB02',
 PART_NUMBER='CS02202FB02',
 VALUE='22',
 PRIM_FILE='./archive_libs/logical/q_res/chips/chips.prt';

PART_NAME
 R1637 'Q_RES_0402LF-4.7K,5%,1/16W,CHIP,CS24702JB10':;

SECTION_NUMBER 1
 '@T6G_MB_LIB.T6G(SCH_1):PAGE150_I71@PURE_QUANTA.Q_RES(CHIPS)':
 C_PATH='@t6g_mb_lib.t6g(sch_1):page150_i71@pure_quanta.q_res(chips)',
 P_PATH='@t6g_mb_lib.t6g(sch_1):page173_i71@pure_quanta.q_res(chips)',
 PATH='I71',
 DRAWING='@T6G_MB_LIB.T6G(SCH_1):PAGE150',
 WATTAGE='1/16W',
 TOLERANCE='5%',
 MATERIAL='CHIP',
 PHYS_PAGE='173',
 XY='(-6600,1800)',
 ROT='2',
 VER='2',
 PACK_TYPE='0402LF',
 LOCATION='R1637',
 CDS_LIB='pure_quanta',
 CDS_PART_NAME='Q_RES_0402LF-4.7K,5%,1/16W,CHIP,CS24702JB10',
 PART_NUMBER='CS24702JB10',
 VALUE='4.7K',
 PRIM_FILE='./archive_libs/logical/q_res/chips/chips.prt';

PART_NAME
 R1638 'Q_RES_0402LF-22,1%,1/16W,CHIP,CS02202FB02':;

SECTION_NUMBER 1
 '@T6G_MB_LIB.T6G(SCH_1):PAGE150_I27@PURE_QUANTA.Q_RES(CHIPS)':
 C_PATH='@t6g_mb_lib.t6g(sch_1):page150_i27@pure_quanta.q_res(chips)',
 P_PATH='@t6g_mb_lib.t6g(sch_1):page173_i27@pure_quanta.q_res(chips)',
 PATH='I27',
 DRAWING='@T6G_MB_LIB.T6G(SCH_1):PAGE150',
 WATTAGE='1/16W',
 TOLERANCE='1%',
 MATERIAL='CHIP',
 PHYS_PAGE='173',
 XY='(-3625,5700)',
 ROT='0',
 VER='1',
 PACK_TYPE='0402LF',
 LOCATION='R1638',
 CDS_LIB='pure_quanta',
 CDS_PART_NAME='Q_RES_0402LF-22,1%,1/16W,CHIP,CS02202FB02',
 PART_NUMBER='CS02202FB02',
 VALUE='22',
 PRIM_FILE='./archive_libs/logical/q_res/chips/chips.prt';

PART_NAME
 R1639 'Q_RES_0402LF-22,1%,1/16W,CHIP,CS02202FB02':;

SECTION_NUMBER 1
 '@T6G_MB_LIB.T6G(SCH_1):PAGE150_I25@PURE_QUANTA.Q_RES(CHIPS)':
 C_PATH='@t6g_mb_lib.t6g(sch_1):page150_i25@pure_quanta.q_res(chips)',
 P_PATH='@t6g_mb_lib.t6g(sch_1):page173_i25@pure_quanta.q_res(chips)',
 PATH='I25',
 DRAWING='@T6G_MB_LIB.T6G(SCH_1):PAGE150',
 WATTAGE='1/16W',
 TOLERANCE='1%',
 MATERIAL='CHIP',
 PHYS_PAGE='173',
 XY='(-3625,5650)',
 ROT='0',
 VER='1',
 PACK_TYPE='0402LF',
 LOCATION='R1639',
 CDS_LIB='pure_quanta',
 CDS_PART_NAME='Q_RES_0402LF-22,1%,1/16W,CHIP,CS02202FB02',
 PART_NUMBER='CS02202FB02',
 VALUE='22',
 PRIM_FILE='./archive_libs/logical/q_res/chips/chips.prt';

PART_NAME
 R1640 'Q_RES_0402LF-22,1%,1/16W,CHIP,CS02202FB02':;

SECTION_NUMBER 1
 '@T6G_MB_LIB.T6G(SCH_1):PAGE150_I26@PURE_QUANTA.Q_RES(CHIPS)':
 C_PATH='@t6g_mb_lib.t6g(sch_1):page150_i26@pure_quanta.q_res(chips)',
 P_PATH='@t6g_mb_lib.t6g(sch_1):page173_i26@pure_quanta.q_res(chips)',
 PATH='I26',
 DRAWING='@T6G_MB_LIB.T6G(SCH_1):PAGE150',
 WATTAGE='1/16W',
 TOLERANCE='1%',
 MATERIAL='CHIP',
 PHYS_PAGE='173',
 XY='(-3625,5600)',
 ROT='0',
 VER='1',
 PACK_TYPE='0402LF',
 LOCATION='R1640',
 CDS_LIB='pure_quanta',
 CDS_PART_NAME='Q_RES_0402LF-22,1%,1/16W,CHIP,CS02202FB02',
 PART_NUMBER='CS02202FB02',
 VALUE='22',
 PRIM_FILE='./archive_libs/logical/q_res/chips/chips.prt';

PART_NAME
 R1641 'Q_RES_0402LF-22,1%,1/16W,CHIP,CS02202FB02':;

SECTION_NUMBER 1
 '@T6G_MB_LIB.T6G(SCH_1):PAGE150_I24@PURE_QUANTA.Q_RES(CHIPS)':
 C_PATH='@t6g_mb_lib.t6g(sch_1):page150_i24@pure_quanta.q_res(chips)',
 P_PATH='@t6g_mb_lib.t6g(sch_1):page173_i24@pure_quanta.q_res(chips)',
 PATH='I24',
 DRAWING='@T6G_MB_LIB.T6G(SCH_1):PAGE150',
 WATTAGE='1/16W',
 TOLERANCE='1%',
 MATERIAL='CHIP',
 PHYS_PAGE='173',
 XY='(-3625,5550)',
 ROT='0',
 VER='1',
 PACK_TYPE='0402LF',
 LOCATION='R1641',
 CDS_LIB='pure_quanta',
 CDS_PART_NAME='Q_RES_0402LF-22,1%,1/16W,CHIP,CS02202FB02',
 PART_NUMBER='CS02202FB02',
 VALUE='22',
 PRIM_FILE='./archive_libs/logical/q_res/chips/chips.prt';

PART_NAME
 R1642 'Q_RES_0402LF-22,1%,1/16W,CHIP,CS02202FB02':;

SECTION_NUMBER 1
 '@T6G_MB_LIB.T6G(SCH_1):PAGE150_I33@PURE_QUANTA.Q_RES(CHIPS)':
 C_PATH='@t6g_mb_lib.t6g(sch_1):page150_i33@pure_quanta.q_res(chips)',
 P_PATH='@t6g_mb_lib.t6g(sch_1):page173_i33@pure_quanta.q_res(chips)',
 PATH='I33',
 DRAWING='@T6G_MB_LIB.T6G(SCH_1):PAGE150',
 WATTAGE='1/16W',
 TOLERANCE='1%',
 MATERIAL='CHIP',
 PHYS_PAGE='173',
 XY='(-3625,4025)',
 ROT='0',
 VER='1',
 PACK_TYPE='0402LF',
 LOCATION='R1642',
 CDS_LIB='pure_quanta',
 CDS_PART_NAME='Q_RES_0402LF-22,1%,1/16W,CHIP,CS02202FB02',
 PART_NUMBER='CS02202FB02',
 VALUE='22',
 PRIM_FILE='./archive_libs/logical/q_res/chips/chips.prt';

PART_NAME
 R1643 'Q_RES_0402LF-22,1%,1/16W,CHIP,CS02202FB02':;

SECTION_NUMBER 1
 '@T6G_MB_LIB.T6G(SCH_1):PAGE150_I34@PURE_QUANTA.Q_RES(CHIPS)':
 C_PATH='@t6g_mb_lib.t6g(sch_1):page150_i34@pure_quanta.q_res(chips)',
 P_PATH='@t6g_mb_lib.t6g(sch_1):page173_i34@pure_quanta.q_res(chips)',
 PATH='I34',
 DRAWING='@T6G_MB_LIB.T6G(SCH_1):PAGE150',
 WATTAGE='1/16W',
 TOLERANCE='1%',
 MATERIAL='CHIP',
 PHYS_PAGE='173',
 XY='(-3625,3975)',
 ROT='0',
 VER='1',
 PACK_TYPE='0402LF',
 LOCATION='R1643',
 CDS_LIB='pure_quanta',
 CDS_PART_NAME='Q_RES_0402LF-22,1%,1/16W,CHIP,CS02202FB02',
 PART_NUMBER='CS02202FB02',
 VALUE='22',
 PRIM_FILE='./archive_libs/logical/q_res/chips/chips.prt';

PART_NAME
 R1644 'Q_RES_0402LF-22,1%,1/16W,CHIP,CS02202FB02':;

SECTION_NUMBER 1
 '@T6G_MB_LIB.T6G(SCH_1):PAGE150_I35@PURE_QUANTA.Q_RES(CHIPS)':
 C_PATH='@t6g_mb_lib.t6g(sch_1):page150_i35@pure_quanta.q_res(chips)',
 P_PATH='@t6g_mb_lib.t6g(sch_1):page173_i35@pure_quanta.q_res(chips)',
 PATH='I35',
 DRAWING='@T6G_MB_LIB.T6G(SCH_1):PAGE150',
 WATTAGE='1/16W',
 TOLERANCE='1%',
 MATERIAL='CHIP',
 PHYS_PAGE='173',
 XY='(-3625,3925)',
 ROT='0',
 VER='1',
 PACK_TYPE='0402LF',
 LOCATION='R1644',
 CDS_LIB='pure_quanta',
 CDS_PART_NAME='Q_RES_0402LF-22,1%,1/16W,CHIP,CS02202FB02',
 PART_NUMBER='CS02202FB02',
 VALUE='22',
 PRIM_FILE='./archive_libs/logical/q_res/chips/chips.prt';

PART_NAME
 R1645 'Q_RES_0402LF-22,1%,1/16W,CHIP,CS02202FB02':;

SECTION_NUMBER 1
 '@T6G_MB_LIB.T6G(SCH_1):PAGE150_I36@PURE_QUANTA.Q_RES(CHIPS)':
 C_PATH='@t6g_mb_lib.t6g(sch_1):page150_i36@pure_quanta.q_res(chips)',
 P_PATH='@t6g_mb_lib.t6g(sch_1):page173_i36@pure_quanta.q_res(chips)',
 PATH='I36',
 DRAWING='@T6G_MB_LIB.T6G(SCH_1):PAGE150',
 WATTAGE='1/16W',
 TOLERANCE='1%',
 MATERIAL='CHIP',
 PHYS_PAGE='173',
 XY='(-3625,3875)',
 ROT='0',
 VER='1',
 PACK_TYPE='0402LF',
 LOCATION='R1645',
 CDS_LIB='pure_quanta',
 CDS_PART_NAME='Q_RES_0402LF-22,1%,1/16W,CHIP,CS02202FB02',
 PART_NUMBER='CS02202FB02',
 VALUE='22',
 PRIM_FILE='./archive_libs/logical/q_res/chips/chips.prt';

PART_NAME
 R1646 'Q_RES_0402LF-1K,1%,1/16W,CHIP,CS21002FB06':;

SECTION_NUMBER 1
 '@T6G_MB_LIB.T6G(SCH_1):PAGE151_I10@PURE_QUANTA.Q_RES(CHIPS)':
 C_PATH='@t6g_mb_lib.t6g(sch_1):page151_i10@pure_quanta.q_res(chips)',
 P_PATH='@t6g_mb_lib.t6g(sch_1):page174_i10@pure_quanta.q_res(chips)',
 PATH='I10',
 DRAWING='@T6G_MB_LIB.T6G(SCH_1):PAGE151',
 WATTAGE='1/16W',
 TOLERANCE='1%',
 MATERIAL='CHIP',
 PHYS_PAGE='174',
 XY='(-8200,5325)',
 ROT='2',
 VER='2',
 PACK_TYPE='0402LF',
 LOCATION='R1646',
 CDS_LIB='pure_quanta',
 CDS_PART_NAME='Q_RES_0402LF-1K,1%,1/16W,CHIP,CS21002FB06',
 PART_NUMBER='CS21002FB06',
 VALUE='1K',
 PRIM_FILE='./archive_libs/logical/q_res/chips/chips.prt';

PART_NAME
 R1647 'Q_RES_0402LF-1K,1%,1/16W,CHIP,CS21002FB06':;

SECTION_NUMBER 1
 '@T6G_MB_LIB.T6G(SCH_1):PAGE151_I11@PURE_QUANTA.Q_RES(CHIPS)':
 C_PATH='@t6g_mb_lib.t6g(sch_1):page151_i11@pure_quanta.q_res(chips)',
 P_PATH='@t6g_mb_lib.t6g(sch_1):page174_i11@pure_quanta.q_res(chips)',
 PATH='I11',
 DRAWING='@T6G_MB_LIB.T6G(SCH_1):PAGE151',
 WATTAGE='1/16W',
 TOLERANCE='1%',
 MATERIAL='CHIP',
 PHYS_PAGE='174',
 XY='(-7600,5500)',
 ROT='0',
 VER='2',
 PACK_TYPE='0402LF',
 LOCATION='R1647',
 CDS_LIB='pure_quanta',
 CDS_PART_NAME='Q_RES_0402LF-1K,1%,1/16W,CHIP,CS21002FB06',
 PART_NUMBER='CS21002FB06',
 VALUE='1K',
 PRIM_FILE='./archive_libs/logical/q_res/chips/chips.prt';

PART_NAME
 R1648 'Q_RES_0402LF-0,5%,1/16W,CHIP,CS00002JB13':;

SECTION_NUMBER 1
 '@T6G_MB_LIB.T6G(SCH_1):PAGE151_I2@PURE_QUANTA.Q_RES(CHIPS)':
 C_PATH='@t6g_mb_lib.t6g(sch_1):page151_i2@pure_quanta.q_res(chips)',
 P_PATH='@t6g_mb_lib.t6g(sch_1):page174_i2@pure_quanta.q_res(chips)',
 PATH='I2',
 DRAWING='@T6G_MB_LIB.T6G(SCH_1):PAGE151',
 WATTAGE='1/16W',
 TOLERANCE='5%',
 MATERIAL='CHIP',
 PHYS_PAGE='174',
 XY='(-5225,5825)',
 ROT='0',
 VER='1',
 PACK_TYPE='0402LF',
 LOCATION='R1648',
 CDS_LIB='pure_quanta',
 CDS_PART_NAME='Q_RES_0402LF-0,5%,1/16W,CHIP,CS00002JB13',
 PART_NUMBER='CS00002JB13',
 VALUE='0',
 PRIM_FILE='./archive_libs/logical/q_res/chips/chips.prt';

PART_NAME
 R1649 'Q_RES_0402LF-1K,1%,1/16W,CHIP,CS21002FB06':;

SECTION_NUMBER 1
 '@T6G_MB_LIB.T6G(SCH_1):PAGE151_I25@PURE_QUANTA.Q_RES(CHIPS)':
 C_PATH='@t6g_mb_lib.t6g(sch_1):page151_i25@pure_quanta.q_res(chips)',
 P_PATH='@t6g_mb_lib.t6g(sch_1):page174_i25@pure_quanta.q_res(chips)',
 PATH='I25',
 DRAWING='@T6G_MB_LIB.T6G(SCH_1):PAGE151',
 WATTAGE='1/16W',
 TOLERANCE='1%',
 MATERIAL='CHIP',
 PHYS_PAGE='174',
 XY='(-5225,3400)',
 ROT='2',
 VER='2',
 PACK_TYPE='0402LF',
 LOCATION='R1649',
 CDS_LIB='pure_quanta',
 CDS_PART_NAME='Q_RES_0402LF-1K,1%,1/16W,CHIP,CS21002FB06',
 PART_NUMBER='CS21002FB06',
 VALUE='1K',
 PRIM_FILE='./archive_libs/logical/q_res/chips/chips.prt';

PART_NAME
 R1650 'Q_RES_0402LF-1K,1%,1/16W,CHIP,CS21002FB06':;

SECTION_NUMBER 1
 '@T6G_MB_LIB.T6G(SCH_1):PAGE151_I27@PURE_QUANTA.Q_RES(CHIPS)':
 C_PATH='@t6g_mb_lib.t6g(sch_1):page151_i27@pure_quanta.q_res(chips)',
 P_PATH='@t6g_mb_lib.t6g(sch_1):page174_i27@pure_quanta.q_res(chips)',
 PATH='I27',
 DRAWING='@T6G_MB_LIB.T6G(SCH_1):PAGE151',
 WATTAGE='1/16W',
 TOLERANCE='1%',
 MATERIAL='CHIP',
 PHYS_PAGE='174',
 XY='(-4550,3525)',
 ROT='0',
 VER='2',
 PACK_TYPE='0402LF',
 LOCATION='R1650',
 CDS_LIB='pure_quanta',
 CDS_PART_NAME='Q_RES_0402LF-1K,1%,1/16W,CHIP,CS21002FB06',
 PART_NUMBER='CS21002FB06',
 VALUE='1K',
 PRIM_FILE='./archive_libs/logical/q_res/chips/chips.prt';

PART_NAME
 R1651 'Q_RES_0402LF-0,5%,1/16W,CHIP,CS00002JB13':;

SECTION_NUMBER 1
 '@T6G_MB_LIB.T6G(SCH_1):PAGE151_I34@PURE_QUANTA.Q_RES(CHIPS)':
 C_PATH='@t6g_mb_lib.t6g(sch_1):page151_i34@pure_quanta.q_res(chips)',
 P_PATH='@t6g_mb_lib.t6g(sch_1):page174_i34@pure_quanta.q_res(chips)',
 PATH='I34',
 DRAWING='@T6G_MB_LIB.T6G(SCH_1):PAGE151',
 WATTAGE='1/16W',
 TOLERANCE='5%',
 MATERIAL='CHIP',
 PHYS_PAGE='174',
 XY='(-1975,4425)',
 ROT='0',
 VER='1',
 PACK_TYPE='0402LF',
 LOCATION='R1651',
 CDS_LIB='pure_quanta',
 CDS_PART_NAME='Q_RES_0402LF-0,5%,1/16W,CHIP,CS00002JB13',
 PART_NUMBER='CS00002JB13',
 VALUE='0',
 PRIM_FILE='./archive_libs/logical/q_res/chips/chips.prt';

PART_NAME
 R1654 'Q_RES_0402LF-1K,1%,1/16W,CHIP,CS21002FB06':
 REUSE_ID='3';

SECTION_NUMBER 1
 '@T6G_MB_LIB.T6G(SCH_1):PAGE273_I22@PURE_QUANTA.Q_RES(CHIPS)':
 C_PATH='@t6g_mb_lib.t6g(sch_1):page273_i22@pure_quanta.q_res(chips)',
 P_PATH='@t6g_mb_lib.t6g(sch_1):page188_i22@pure_quanta.q_res(chips)',
 PATH='I22',
 DRAWING='@T6G_MB_LIB.T6G(SCH_1):PAGE273',
 BOM_COST='VR_SYSTEM ',
 WATTAGE='1/16W',
 TOLERANCE='1%',
 MATERIAL='CHIP',
 PHYS_PAGE='188',
 XY='(-4350,6325)',
 ROT='0',
 VER='2',
 PACK_TYPE='0402LF',
 LOCATION='R1654',
 CDS_LIB='pure_quanta',
 CDS_PART_NAME='Q_RES_0402LF-1K,1%,1/16W,CHIP,CS21002FB06',
 REUSE_ID='3',
 PART_NUMBER='CS21002FB06',
 VALUE='1K',
 PRIM_FILE='./archive_libs/logical/q_res/chips/chips.prt';

PART_NAME
 R1655 'Q_RES_0402LF-1K,1%,1/16W,EMPTY,CS21002FB06':;

SECTION_NUMBER 1
 '@T6G_MB_LIB.T6G(SCH_1):PAGE76_I191@PURE_QUANTA.Q_RES(CHIPS)':
 C_PATH='@t6g_mb_lib.t6g(sch_1):page76_i191@pure_quanta.q_res(chips)',
 P_PATH='@t6g_mb_lib.t6g(sch_1):page77_i191@pure_quanta.q_res(chips)',
 PATH='I191',
 DRAWING='@T6G_MB_LIB.T6G(SCH_1):PAGE76',
 WATTAGE='1/16W',
 TOLERANCE='1%',
 MATERIAL='EMPTY',
 PHYS_PAGE='77',
 XY='(-1025,5625)',
 ROT='2',
 VER='2',
 PACK_TYPE='0402LF',
 LOCATION='R1655',
 CDS_LIB='pure_quanta',
 CDS_PART_NAME='Q_RES_0402LF-1K,1%,1/16W,EMPTY,CS21002FB06',
 PART_NUMBER='CS21002FB06',
 VALUE='1K',
 PRIM_FILE='./archive_libs/logical/q_res/chips/chips.prt';

PART_NAME
 R1658 'Q_RES_0402LF-4.7K,5%,1/16W,CHIP,CS24702JB10':;

SECTION_NUMBER 1
 '@T6G_MB_LIB.T6G(SCH_1):PAGE148_I310@PURE_QUANTA.Q_RES(CHIPS)':
 C_PATH='@t6g_mb_lib.t6g(sch_1):page148_i310@pure_quanta.q_res(chips)',
 P_PATH='@t6g_mb_lib.t6g(sch_1):page171_i310@pure_quanta.q_res(chips)',
 PATH='I310',
 DRAWING='@T6G_MB_LIB.T6G(SCH_1):PAGE148',
 WATTAGE='1/16W',
 TOLERANCE='5%',
 MATERIAL='CHIP',
 PHYS_PAGE='171',
 XY='(-7750,1650)',
 ROT='0',
 VER='2',
 PACK_TYPE='0402LF',
 LOCATION='R1658',
 CDS_LIB='pure_quanta',
 CDS_PART_NAME='Q_RES_0402LF-4.7K,5%,1/16W,CHIP,CS24702JB10',
 PART_NUMBER='CS24702JB10',
 VALUE='4.7K',
 PRIM_FILE='./archive_libs/logical/q_res/chips/chips.prt';

PART_NAME
 R1659 'Q_RES_0402LF-4.7K,5%,1/16W,EMPTY,CS24702JB10':;

SECTION_NUMBER 1
 '@T6G_MB_LIB.T6G(SCH_1):PAGE148_I309@PURE_QUANTA.Q_RES(CHIPS)':
 C_PATH='@t6g_mb_lib.t6g(sch_1):page148_i309@pure_quanta.q_res(chips)',
 P_PATH='@t6g_mb_lib.t6g(sch_1):page171_i309@pure_quanta.q_res(chips)',
 PATH='I309',
 DRAWING='@T6G_MB_LIB.T6G(SCH_1):PAGE148',
 WATTAGE='1/16W',
 TOLERANCE='5%',
 MATERIAL='EMPTY',
 PHYS_PAGE='171',
 XY='(-7700,2150)',
 ROT='0',
 VER='2',
 PACK_TYPE='0402LF',
 LOCATION='R1659',
 CDS_LIB='pure_quanta',
 CDS_PART_NAME='Q_RES_0402LF-4.7K,5%,1/16W,EMPTY,CS24702JB10',
 PART_NUMBER='CS24702JB10',
 VALUE='4.7K',
 PRIM_FILE='./archive_libs/logical/q_res/chips/chips.prt';

PART_NAME
 R1671 'Q_RES_0402LF-0,5%,1/16W,CHIP,CS00002JB13':;

SECTION_NUMBER 1
 '@T6G_MB_LIB.T6G(SCH_1):PAGE335_I54@PURE_QUANTA.Q_RES(CHIPS)':
 C_PATH='@t6g_mb_lib.t6g(sch_1):page335_i54@pure_quanta.q_res(chips)',
 P_PATH='@t6g_mb_lib.t6g(sch_1):page131_i54@pure_quanta.q_res(chips)',
 PATH='I54',
 DRAWING='@T6G_MB_LIB.T6G(SCH_1):PAGE335',
 WATTAGE='1/16W',
 TOLERANCE='5%',
 MATERIAL='CHIP',
 PHYS_PAGE='131',
 XY='(-2875,5750)',
 ROT='0',
 VER='1',
 PACK_TYPE='0402LF',
 LOCATION='R1671',
 CDS_LIB='pure_quanta',
 CDS_PART_NAME='Q_RES_0402LF-0,5%,1/16W,CHIP,CS00002JB13',
 PART_NUMBER='CS00002JB13',
 VALUE='0',
 PRIM_FILE='./archive_libs/logical/q_res/chips/chips.prt';

PART_NAME
 R1673 'Q_RES_0402LF-10K,1%,1/16W,CHIP,CS31002FB08':;

SECTION_NUMBER 1
 '@T6G_MB_LIB.T6G(SCH_1):PAGE297_I105@PURE_QUANTA.Q_RES(CHIPS)':
 C_PATH='@t6g_mb_lib.t6g(sch_1):page297_i105@pure_quanta.q_res(chips)',
 P_PATH='@t6g_mb_lib.t6g(sch_1):page145_i105@pure_quanta.q_res(chips)',
 PATH='I105',
 DRAWING='@T6G_MB_LIB.T6G(SCH_1):PAGE297',
 WATTAGE='1/16W',
 TOLERANCE='1%',
 MATERIAL='CHIP',
 PHYS_PAGE='145',
 XY='(2450,4475)',
 ROT='0',
 VER='2',
 PACK_TYPE='0402LF',
 LOCATION='R1673',
 CDS_LIB='pure_quanta',
 CDS_PART_NAME='Q_RES_0402LF-10K,1%,1/16W,CHIP,CS31002FB08',
 PART_NUMBER='CS31002FB08',
 VALUE='10K',
 PRIM_FILE='./archive_libs/logical/q_res/chips/chips.prt';

PART_NAME
 R1674 'Q_RES_0402LF-10,1%,1/16W,CHIP,CS01002FB07':;

SECTION_NUMBER 1
 '@T6G_MB_LIB.T6G(SCH_1):PAGE85_I554@PURE_QUANTA.Q_RES(CHIPS)':
 C_PATH='@t6g_mb_lib.t6g(sch_1):page85_i554@pure_quanta.q_res(chips)',
 P_PATH='@t6g_mb_lib.t6g(sch_1):page86_i554@pure_quanta.q_res(chips)',
 PATH='I554',
 DRAWING='@T6G_MB_LIB.T6G(SCH_1):PAGE85',
 SEC_TYPE='0402LF',
 WATTAGE='1/16W',
 TOLERANCE='1%',
 MATERIAL='CHIP',
 PHYS_PAGE='86',
 XY='(-8125,2875)',
 ROT='0',
 VER='1',
 PACK_TYPE='0402LF',
 LOCATION='R1674',
 SEC='1',
 CDS_LIB='pure_quanta',
 CDS_PART_NAME='Q_RES_0402LF-10,1%,1/16W,CHIP,CS01002FB07',
 PART_NUMBER='CS01002FB07',
 VALUE='10',
 PRIM_FILE='./archive_libs/logical/q_res/chips/chips.prt';

PART_NAME
 R1675 'Q_RES_0402LF-10,1%,1/16W,CHIP,CS01002FB07':;

SECTION_NUMBER 1
 '@T6G_MB_LIB.T6G(SCH_1):PAGE86_I373@PURE_QUANTA.Q_RES(CHIPS)':
 C_PATH='@t6g_mb_lib.t6g(sch_1):page86_i373@pure_quanta.q_res(chips)',
 P_PATH='@t6g_mb_lib.t6g(sch_1):page87_i373@pure_quanta.q_res(chips)',
 PATH='I373',
 DRAWING='@T6G_MB_LIB.T6G(SCH_1):PAGE86',
 SEC_TYPE='0402LF',
 WATTAGE='1/16W',
 TOLERANCE='1%',
 MATERIAL='CHIP',
 PHYS_PAGE='87',
 XY='(-8300,2975)',
 ROT='0',
 VER='1',
 PACK_TYPE='0402LF',
 LOCATION='R1675',
 SEC='1',
 CDS_LIB='pure_quanta',
 CDS_PART_NAME='Q_RES_0402LF-10,1%,1/16W,CHIP,CS01002FB07',
 PART_NUMBER='CS01002FB07',
 VALUE='10',
 PRIM_FILE='./archive_libs/logical/q_res/chips/chips.prt';

PART_NAME
 R1676 'Q_RES_0402LF-10,1%,1/16W,CHIP,CS01002FB07':;

SECTION_NUMBER 1
 '@T6G_MB_LIB.T6G(SCH_1):PAGE88_I422@PURE_QUANTA.Q_RES(CHIPS)':
 C_PATH='@t6g_mb_lib.t6g(sch_1):page88_i422@pure_quanta.q_res(chips)',
 P_PATH='@t6g_mb_lib.t6g(sch_1):page89_i422@pure_quanta.q_res(chips)',
 PATH='I422',
 DRAWING='@T6G_MB_LIB.T6G(SCH_1):PAGE88',
 SEC_TYPE='0402LF',
 WATTAGE='1/16W',
 TOLERANCE='1%',
 MATERIAL='CHIP',
 PHYS_PAGE='89',
 XY='(-8175,3000)',
 ROT='0',
 VER='1',
 PACK_TYPE='0402LF',
 LOCATION='R1676',
 SEC='1',
 CDS_LIB='pure_quanta',
 CDS_PART_NAME='Q_RES_0402LF-10,1%,1/16W,CHIP,CS01002FB07',
 PART_NUMBER='CS01002FB07',
 VALUE='10',
 PRIM_FILE='./archive_libs/logical/q_res/chips/chips.prt';

PART_NAME
 R1677 'Q_RES_0402LF-10,1%,1/16W,CHIP,CS01002FB07':;

SECTION_NUMBER 1
 '@T6G_MB_LIB.T6G(SCH_1):PAGE87_I418@PURE_QUANTA.Q_RES(CHIPS)':
 C_PATH='@t6g_mb_lib.t6g(sch_1):page87_i418@pure_quanta.q_res(chips)',
 P_PATH='@t6g_mb_lib.t6g(sch_1):page88_i418@pure_quanta.q_res(chips)',
 PATH='I418',
 DRAWING='@T6G_MB_LIB.T6G(SCH_1):PAGE87',
 WATTAGE='1/16W',
 TOLERANCE='1%',
 MATERIAL='CHIP',
 PHYS_PAGE='88',
 XY='(-8275,3175)',
 ROT='0',
 VER='1',
 PACK_TYPE='0402LF',
 LOCATION='R1677',
 CDS_LIB='pure_quanta',
 CDS_PART_NAME='Q_RES_0402LF-10,1%,1/16W,CHIP,CS01002FB07',
 PART_NUMBER='CS01002FB07',
 VALUE='10',
 PRIM_FILE='./archive_libs/logical/q_res/chips/chips.prt';

PART_NAME
 R1678 'Q_RES_0402LF-10,1%,1/16W,CHIP,CS01002FB07':;

SECTION_NUMBER 1
 '@T6G_MB_LIB.T6G(SCH_1):PAGE89_I418@PURE_QUANTA.Q_RES(CHIPS)':
 C_PATH='@t6g_mb_lib.t6g(sch_1):page89_i418@pure_quanta.q_res(chips)',
 P_PATH='@t6g_mb_lib.t6g(sch_1):page90_i418@pure_quanta.q_res(chips)',
 PATH='I418',
 DRAWING='@T6G_MB_LIB.T6G(SCH_1):PAGE89',
 WATTAGE='1/16W',
 TOLERANCE='1%',
 MATERIAL='CHIP',
 PHYS_PAGE='90',
 XY='(-8325,3025)',
 ROT='0',
 VER='1',
 PACK_TYPE='0402LF',
 LOCATION='R1678',
 CDS_LIB='pure_quanta',
 CDS_PART_NAME='Q_RES_0402LF-10,1%,1/16W,CHIP,CS01002FB07',
 PART_NUMBER='CS01002FB07',
 VALUE='10',
 PRIM_FILE='./archive_libs/logical/q_res/chips/chips.prt';

PART_NAME
 R1679 'Q_RES_0402LF-10,1%,1/16W,CHIP,CS01002FB07':;

SECTION_NUMBER 1
 '@T6G_MB_LIB.T6G(SCH_1):PAGE90_I419@PURE_QUANTA.Q_RES(CHIPS)':
 C_PATH='@t6g_mb_lib.t6g(sch_1):page90_i419@pure_quanta.q_res(chips)',
 P_PATH='@t6g_mb_lib.t6g(sch_1):page91_i419@pure_quanta.q_res(chips)',
 PATH='I419',
 DRAWING='@T6G_MB_LIB.T6G(SCH_1):PAGE90',
 WATTAGE='1/16W',
 TOLERANCE='1%',
 MATERIAL='CHIP',
 PHYS_PAGE='91',
 XY='(-8125,3175)',
 ROT='0',
 VER='1',
 PACK_TYPE='0402LF',
 LOCATION='R1679',
 CDS_LIB='pure_quanta',
 CDS_PART_NAME='Q_RES_0402LF-10,1%,1/16W,CHIP,CS01002FB07',
 PART_NUMBER='CS01002FB07',
 VALUE='10',
 PRIM_FILE='./archive_libs/logical/q_res/chips/chips.prt';

PART_NAME
 R1680 'Q_RES_0402LF-10,1%,1/16W,CHIP,CS01002FB07':;

SECTION_NUMBER 1
 '@T6G_MB_LIB.T6G(SCH_1):PAGE91_I254@PURE_QUANTA.Q_RES(CHIPS)':
 C_PATH='@t6g_mb_lib.t6g(sch_1):page91_i254@pure_quanta.q_res(chips)',
 P_PATH='@t6g_mb_lib.t6g(sch_1):page92_i254@pure_quanta.q_res(chips)',
 PATH='I254',
 DRAWING='@T6G_MB_LIB.T6G(SCH_1):PAGE91',
 WATTAGE='1/16W',
 TOLERANCE='1%',
 MATERIAL='CHIP',
 PHYS_PAGE='92',
 XY='(-7750,2850)',
 ROT='0',
 VER='1',
 PACK_TYPE='0402LF',
 LOCATION='R1680',
 CDS_LIB='pure_quanta',
 CDS_PART_NAME='Q_RES_0402LF-10,1%,1/16W,CHIP,CS01002FB07',
 PART_NUMBER='CS01002FB07',
 VALUE='10',
 PRIM_FILE='./archive_libs/logical/q_res/chips/chips.prt';

PART_NAME
 R1681 'Q_RES_0402LF-10,1%,1/16W,CHIP,CS01002FB07':;

SECTION_NUMBER 1
 '@T6G_MB_LIB.T6G(SCH_1):PAGE92_I244@PURE_QUANTA.Q_RES(CHIPS)':
 C_PATH='@t6g_mb_lib.t6g(sch_1):page92_i244@pure_quanta.q_res(chips)',
 P_PATH='@t6g_mb_lib.t6g(sch_1):page93_i244@pure_quanta.q_res(chips)',
 PATH='I244',
 DRAWING='@T6G_MB_LIB.T6G(SCH_1):PAGE92',
 WATTAGE='1/16W',
 TOLERANCE='1%',
 MATERIAL='CHIP',
 PHYS_PAGE='93',
 XY='(-8150,2800)',
 ROT='0',
 VER='1',
 PACK_TYPE='0402LF',
 LOCATION='R1681',
 CDS_LIB='pure_quanta',
 CDS_PART_NAME='Q_RES_0402LF-10,1%,1/16W,CHIP,CS01002FB07',
 PART_NUMBER='CS01002FB07',
 VALUE='10',
 PRIM_FILE='./archive_libs/logical/q_res/chips/chips.prt';

PART_NAME
 R1683 'Q_RES_0402LF-10,1%,1/16W,CHIP,CS01002FB07':;

SECTION_NUMBER 1
 '@T6G_MB_LIB.T6G(SCH_1):PAGE93_I243@PURE_QUANTA.Q_RES(CHIPS)':
 C_PATH='@t6g_mb_lib.t6g(sch_1):page93_i243@pure_quanta.q_res(chips)',
 P_PATH='@t6g_mb_lib.t6g(sch_1):page94_i243@pure_quanta.q_res(chips)',
 PATH='I243',
 DRAWING='@T6G_MB_LIB.T6G(SCH_1):PAGE93',
 WATTAGE='1/16W',
 TOLERANCE='1%',
 MATERIAL='CHIP',
 PHYS_PAGE='94',
 XY='(-8150,2900)',
 ROT='0',
 VER='1',
 PACK_TYPE='0402LF',
 LOCATION='R1683',
 CDS_LIB='pure_quanta',
 CDS_PART_NAME='Q_RES_0402LF-10,1%,1/16W,CHIP,CS01002FB07',
 PART_NUMBER='CS01002FB07',
 VALUE='10',
 PRIM_FILE='./archive_libs/logical/q_res/chips/chips.prt';

PART_NAME
 R1684 'Q_RES_0402LF-10,1%,1/16W,CHIP,CS01002FB07':;

SECTION_NUMBER 1
 '@T6G_MB_LIB.T6G(SCH_1):PAGE94_I243@PURE_QUANTA.Q_RES(CHIPS)':
 C_PATH='@t6g_mb_lib.t6g(sch_1):page94_i243@pure_quanta.q_res(chips)',
 P_PATH='@t6g_mb_lib.t6g(sch_1):page95_i243@pure_quanta.q_res(chips)',
 PATH='I243',
 DRAWING='@T6G_MB_LIB.T6G(SCH_1):PAGE94',
 WATTAGE='1/16W',
 TOLERANCE='1%',
 MATERIAL='CHIP',
 PHYS_PAGE='95',
 XY='(-8100,2775)',
 ROT='0',
 VER='1',
 PACK_TYPE='0402LF',
 LOCATION='R1684',
 CDS_LIB='pure_quanta',
 CDS_PART_NAME='Q_RES_0402LF-10,1%,1/16W,CHIP,CS01002FB07',
 PART_NUMBER='CS01002FB07',
 VALUE='10',
 PRIM_FILE='./archive_libs/logical/q_res/chips/chips.prt';

PART_NAME
 R1685 'Q_RES_0402LF-10,1%,1/16W,CHIP,CS01002FB07':;

SECTION_NUMBER 1
 '@T6G_MB_LIB.T6G(SCH_1):PAGE95_I243@PURE_QUANTA.Q_RES(CHIPS)':
 C_PATH='@t6g_mb_lib.t6g(sch_1):page95_i243@pure_quanta.q_res(chips)',
 P_PATH='@t6g_mb_lib.t6g(sch_1):page96_i243@pure_quanta.q_res(chips)',
 PATH='I243',
 DRAWING='@T6G_MB_LIB.T6G(SCH_1):PAGE95',
 WATTAGE='1/16W',
 TOLERANCE='1%',
 MATERIAL='CHIP',
 PHYS_PAGE='96',
 XY='(-8175,2825)',
 ROT='0',
 VER='1',
 PACK_TYPE='0402LF',
 LOCATION='R1685',
 CDS_LIB='pure_quanta',
 CDS_PART_NAME='Q_RES_0402LF-10,1%,1/16W,CHIP,CS01002FB07',
 PART_NUMBER='CS01002FB07',
 VALUE='10',
 PRIM_FILE='./archive_libs/logical/q_res/chips/chips.prt';

PART_NAME
 R1686 'Q_RES_0402LF-10,1%,1/16W,CHIP,CS01002FB07':;

SECTION_NUMBER 1
 '@T6G_MB_LIB.T6G(SCH_1):PAGE96_I243@PURE_QUANTA.Q_RES(CHIPS)':
 C_PATH='@t6g_mb_lib.t6g(sch_1):page96_i243@pure_quanta.q_res(chips)',
 P_PATH='@t6g_mb_lib.t6g(sch_1):page97_i243@pure_quanta.q_res(chips)',
 PATH='I243',
 DRAWING='@T6G_MB_LIB.T6G(SCH_1):PAGE96',
 WATTAGE='1/16W',
 TOLERANCE='1%',
 MATERIAL='CHIP',
 PHYS_PAGE='97',
 XY='(-8125,2525)',
 ROT='0',
 VER='1',
 PACK_TYPE='0402LF',
 LOCATION='R1686',
 CDS_LIB='pure_quanta',
 CDS_PART_NAME='Q_RES_0402LF-10,1%,1/16W,CHIP,CS01002FB07',
 PART_NUMBER='CS01002FB07',
 VALUE='10',
 PRIM_FILE='./archive_libs/logical/q_res/chips/chips.prt';

PART_NAME
 R1687 'Q_RES_0402LF-10,1%,1/16W,CHIP,CS01002FB07':;

SECTION_NUMBER 1
 '@T6G_MB_LIB.T6G(SCH_1):PAGE97_I256@PURE_QUANTA.Q_RES(CHIPS)':
 C_PATH='@t6g_mb_lib.t6g(sch_1):page97_i256@pure_quanta.q_res(chips)',
 P_PATH='@t6g_mb_lib.t6g(sch_1):page98_i256@pure_quanta.q_res(chips)',
 PATH='I256',
 DRAWING='@T6G_MB_LIB.T6G(SCH_1):PAGE97',
 WATTAGE='1/16W',
 TOLERANCE='1%',
 MATERIAL='CHIP',
 PHYS_PAGE='98',
 XY='(-7875,2925)',
 ROT='0',
 VER='1',
 PACK_TYPE='0402LF',
 LOCATION='R1687',
 CDS_LIB='pure_quanta',
 CDS_PART_NAME='Q_RES_0402LF-10,1%,1/16W,CHIP,CS01002FB07',
 PART_NUMBER='CS01002FB07',
 VALUE='10',
 PRIM_FILE='./archive_libs/logical/q_res/chips/chips.prt';

PART_NAME
 R1696 'Q_RES_0402LF-10,1%,1/16W,CHIP,CS01002FB07':;

SECTION_NUMBER 1
 '@T6G_MB_LIB.T6G(SCH_1):PAGE98_I243@PURE_QUANTA.Q_RES(CHIPS)':
 C_PATH='@t6g_mb_lib.t6g(sch_1):page98_i243@pure_quanta.q_res(chips)',
 P_PATH='@t6g_mb_lib.t6g(sch_1):page99_i243@pure_quanta.q_res(chips)',
 PATH='I243',
 DRAWING='@T6G_MB_LIB.T6G(SCH_1):PAGE98',
 WATTAGE='1/16W',
 TOLERANCE='1%',
 MATERIAL='CHIP',
 PHYS_PAGE='99',
 XY='(-8200,2975)',
 ROT='0',
 VER='1',
 PACK_TYPE='0402LF',
 LOCATION='R1696',
 CDS_LIB='pure_quanta',
 CDS_PART_NAME='Q_RES_0402LF-10,1%,1/16W,CHIP,CS01002FB07',
 PART_NUMBER='CS01002FB07',
 VALUE='10',
 PRIM_FILE='./archive_libs/logical/q_res/chips/chips.prt';

PART_NAME
 R1697 'Q_RES_0402LF-10,1%,1/16W,CHIP,CS01002FB07':;

SECTION_NUMBER 1
 '@T6G_MB_LIB.T6G(SCH_1):PAGE99_I243@PURE_QUANTA.Q_RES(CHIPS)':
 C_PATH='@t6g_mb_lib.t6g(sch_1):page99_i243@pure_quanta.q_res(chips)',
 P_PATH='@t6g_mb_lib.t6g(sch_1):page100_i243@pure_quanta.q_res(chips)',
 PATH='I243',
 DRAWING='@T6G_MB_LIB.T6G(SCH_1):PAGE99',
 WATTAGE='1/16W',
 TOLERANCE='1%',
 MATERIAL='CHIP',
 PHYS_PAGE='100',
 XY='(-8300,2850)',
 ROT='0',
 VER='1',
 PACK_TYPE='0402LF',
 LOCATION='R1697',
 CDS_LIB='pure_quanta',
 CDS_PART_NAME='Q_RES_0402LF-10,1%,1/16W,CHIP,CS01002FB07',
 PART_NUMBER='CS01002FB07',
 VALUE='10',
 PRIM_FILE='./archive_libs/logical/q_res/chips/chips.prt';

PART_NAME
 R1699 'Q_RES_0402LF-10,1%,1/16W,CHIP,CS01002FB07':;

SECTION_NUMBER 1
 '@T6G_MB_LIB.T6G(SCH_1):PAGE100_I243@PURE_QUANTA.Q_RES(CHIPS)':
 C_PATH='@t6g_mb_lib.t6g(sch_1):page100_i243@pure_quanta.q_res(chips)',
 P_PATH='@t6g_mb_lib.t6g(sch_1):page101_i243@pure_quanta.q_res(chips)',
 PATH='I243',
 DRAWING='@T6G_MB_LIB.T6G(SCH_1):PAGE100',
 WATTAGE='1/16W',
 TOLERANCE='1%',
 MATERIAL='CHIP',
 PHYS_PAGE='101',
 XY='(-8225,3025)',
 ROT='0',
 VER='1',
 PACK_TYPE='0402LF',
 LOCATION='R1699',
 CDS_LIB='pure_quanta',
 CDS_PART_NAME='Q_RES_0402LF-10,1%,1/16W,CHIP,CS01002FB07',
 PART_NUMBER='CS01002FB07',
 VALUE='10',
 PRIM_FILE='./archive_libs/logical/q_res/chips/chips.prt';

PART_NAME
 R1700 'Q_RES_0402LF-200K,1%,1/16W,CHIP,CS42002FB05':;

SECTION_NUMBER 1
 '@T6G_MB_LIB.T6G(SCH_1):PAGE346_I72@PURE_QUANTA.Q_RES(CHIPS)':
 C_PATH='@t6g_mb_lib.t6g(sch_1):page346_i72@pure_quanta.q_res(chips)',
 P_PATH='@t6g_mb_lib.t6g(sch_1):page148_i72@pure_quanta.q_res(chips)',
 PATH='I72',
 DRAWING='@T6G_MB_LIB.T6G(SCH_1):PAGE346',
 WATTAGE='1/16W',
 TOLERANCE='1%',
 MATERIAL='CHIP',
 PHYS_PAGE='148',
 XY='(0,3750)',
 ROT='0',
 VER='2',
 PACK_TYPE='0402LF',
 LOCATION='R1700',
 CDS_LIB='pure_quanta',
 CDS_PART_NAME='Q_RES_0402LF-200K,1%,1/16W,CHIP,CS42002FB05',
 PART_NUMBER='CS42002FB05',
 VALUE='200K',
 PRIM_FILE='./archive_libs/logical/q_res/chips/chips.prt';

PART_NAME
 R1701 'Q_RES_0402LF-10,1%,1/16W,CHIP,CS01002FB07':;

SECTION_NUMBER 1
 '@T6G_MB_LIB.T6G(SCH_1):PAGE101_I243@PURE_QUANTA.Q_RES(CHIPS)':
 C_PATH='@t6g_mb_lib.t6g(sch_1):page101_i243@pure_quanta.q_res(chips)',
 P_PATH='@t6g_mb_lib.t6g(sch_1):page102_i243@pure_quanta.q_res(chips)',
 PATH='I243',
 DRAWING='@T6G_MB_LIB.T6G(SCH_1):PAGE101',
 WATTAGE='1/16W',
 TOLERANCE='1%',
 MATERIAL='CHIP',
 PHYS_PAGE='102',
 XY='(-8300,3100)',
 ROT='0',
 VER='1',
 PACK_TYPE='0402LF',
 LOCATION='R1701',
 CDS_LIB='pure_quanta',
 CDS_PART_NAME='Q_RES_0402LF-10,1%,1/16W,CHIP,CS01002FB07',
 PART_NUMBER='CS01002FB07',
 VALUE='10',
 PRIM_FILE='./archive_libs/logical/q_res/chips/chips.prt';

PART_NAME
 R1702 'Q_RES_0402LF-4.7K,5%,1/16W,CHIP,CS24702JB10':;

SECTION_NUMBER 1
 '@T6G_MB_LIB.T6G(SCH_1):PAGE346_I43@PURE_QUANTA.Q_RES(CHIPS)':
 C_PATH='@t6g_mb_lib.t6g(sch_1):page346_i43@pure_quanta.q_res(chips)',
 P_PATH='@t6g_mb_lib.t6g(sch_1):page148_i43@pure_quanta.q_res(chips)',
 PATH='I43',
 DRAWING='@T6G_MB_LIB.T6G(SCH_1):PAGE346',
 WATTAGE='1/16W',
 TOLERANCE='5%',
 MATERIAL='CHIP',
 PHYS_PAGE='148',
 XY='(2250,3775)',
 ROT='0',
 VER='2',
 PACK_TYPE='0402LF',
 LOCATION='R1702',
 CDS_LIB='pure_quanta',
 CDS_PART_NAME='Q_RES_0402LF-4.7K,5%,1/16W,CHIP,CS24702JB10',
 PART_NUMBER='CS24702JB10',
 VALUE='4.7K',
 PRIM_FILE='./archive_libs/logical/q_res/chips/chips.prt';

PART_NAME
 R1703 'Q_RES_0402LF-4.7K,5%,1/16W,CHIP,CS24702JB10':;

SECTION_NUMBER 1
 '@T6G_MB_LIB.T6G(SCH_1):PAGE346_I45@PURE_QUANTA.Q_RES(CHIPS)':
 C_PATH='@t6g_mb_lib.t6g(sch_1):page346_i45@pure_quanta.q_res(chips)',
 P_PATH='@t6g_mb_lib.t6g(sch_1):page148_i45@pure_quanta.q_res(chips)',
 PATH='I45',
 DRAWING='@T6G_MB_LIB.T6G(SCH_1):PAGE346',
 WATTAGE='1/16W',
 TOLERANCE='5%',
 MATERIAL='CHIP',
 PHYS_PAGE='148',
 XY='(2500,3775)',
 ROT='0',
 VER='2',
 PACK_TYPE='0402LF',
 LOCATION='R1703',
 CDS_LIB='pure_quanta',
 CDS_PART_NAME='Q_RES_0402LF-4.7K,5%,1/16W,CHIP,CS24702JB10',
 PART_NUMBER='CS24702JB10',
 VALUE='4.7K',
 PRIM_FILE='./archive_libs/logical/q_res/chips/chips.prt';

PART_NAME
 R1704 'Q_RES_0402LF-10,1%,1/16W,CHIP,CS01002FB07':;

SECTION_NUMBER 1
 '@T6G_MB_LIB.T6G(SCH_1):PAGE102_I243@PURE_QUANTA.Q_RES(CHIPS)':
 C_PATH='@t6g_mb_lib.t6g(sch_1):page102_i243@pure_quanta.q_res(chips)',
 P_PATH='@t6g_mb_lib.t6g(sch_1):page103_i243@pure_quanta.q_res(chips)',
 PATH='I243',
 DRAWING='@T6G_MB_LIB.T6G(SCH_1):PAGE102',
 WATTAGE='1/16W',
 TOLERANCE='1%',
 MATERIAL='CHIP',
 PHYS_PAGE='103',
 XY='(-8250,2975)',
 ROT='0',
 VER='1',
 PACK_TYPE='0402LF',
 LOCATION='R1704',
 CDS_LIB='pure_quanta',
 CDS_PART_NAME='Q_RES_0402LF-10,1%,1/16W,CHIP,CS01002FB07',
 PART_NUMBER='CS01002FB07',
 VALUE='10',
 PRIM_FILE='./archive_libs/logical/q_res/chips/chips.prt';

PART_NAME
 R1705 'Q_RES_0402LF-10,1%,1/16W,CHIP,CS01002FB07':;

SECTION_NUMBER 1
 '@T6G_MB_LIB.T6G(SCH_1):PAGE103_I256@PURE_QUANTA.Q_RES(CHIPS)':
 C_PATH='@t6g_mb_lib.t6g(sch_1):page103_i256@pure_quanta.q_res(chips)',
 P_PATH='@t6g_mb_lib.t6g(sch_1):page104_i256@pure_quanta.q_res(chips)',
 PATH='I256',
 DRAWING='@T6G_MB_LIB.T6G(SCH_1):PAGE103',
 WATTAGE='1/16W',
 TOLERANCE='1%',
 MATERIAL='CHIP',
 PHYS_PAGE='104',
 XY='(-7900,2800)',
 ROT='0',
 VER='1',
 PACK_TYPE='0402LF',
 LOCATION='R1705',
 CDS_LIB='pure_quanta',
 CDS_PART_NAME='Q_RES_0402LF-10,1%,1/16W,CHIP,CS01002FB07',
 PART_NUMBER='CS01002FB07',
 VALUE='10',
 PRIM_FILE='./archive_libs/logical/q_res/chips/chips.prt';

PART_NAME
 R1707 'Q_RES_0402LF-10,1%,1/16W,CHIP,CS01002FB07':;

SECTION_NUMBER 1
 '@T6G_MB_LIB.T6G(SCH_1):PAGE104_I245@PURE_QUANTA.Q_RES(CHIPS)':
 C_PATH='@t6g_mb_lib.t6g(sch_1):page104_i245@pure_quanta.q_res(chips)',
 P_PATH='@t6g_mb_lib.t6g(sch_1):page105_i245@pure_quanta.q_res(chips)',
 PATH='I245',
 DRAWING='@T6G_MB_LIB.T6G(SCH_1):PAGE104',
 WATTAGE='1/16W',
 TOLERANCE='1%',
 MATERIAL='CHIP',
 PHYS_PAGE='105',
 XY='(-8050,2850)',
 ROT='0',
 VER='1',
 PACK_TYPE='0402LF',
 LOCATION='R1707',
 CDS_LIB='pure_quanta',
 CDS_PART_NAME='Q_RES_0402LF-10,1%,1/16W,CHIP,CS01002FB07',
 PART_NUMBER='CS01002FB07',
 VALUE='10',
 PRIM_FILE='./archive_libs/logical/q_res/chips/chips.prt';

PART_NAME
 R1708 'Q_RES_0402LF-10,1%,1/16W,CHIP,CS01002FB07':;

SECTION_NUMBER 1
 '@T6G_MB_LIB.T6G(SCH_1):PAGE105_I243@PURE_QUANTA.Q_RES(CHIPS)':
 C_PATH='@t6g_mb_lib.t6g(sch_1):page105_i243@pure_quanta.q_res(chips)',
 P_PATH='@t6g_mb_lib.t6g(sch_1):page106_i243@pure_quanta.q_res(chips)',
 PATH='I243',
 DRAWING='@T6G_MB_LIB.T6G(SCH_1):PAGE105',
 WATTAGE='1/16W',
 TOLERANCE='1%',
 MATERIAL='CHIP',
 PHYS_PAGE='106',
 XY='(-8100,2800)',
 ROT='0',
 VER='1',
 PACK_TYPE='0402LF',
 LOCATION='R1708',
 CDS_LIB='pure_quanta',
 CDS_PART_NAME='Q_RES_0402LF-10,1%,1/16W,CHIP,CS01002FB07',
 PART_NUMBER='CS01002FB07',
 VALUE='10',
 PRIM_FILE='./archive_libs/logical/q_res/chips/chips.prt';

PART_NAME
 R1709 'Q_RES_0402LF-10,1%,1/16W,CHIP,CS01002FB07':;

SECTION_NUMBER 1
 '@T6G_MB_LIB.T6G(SCH_1):PAGE106_I243@PURE_QUANTA.Q_RES(CHIPS)':
 C_PATH='@t6g_mb_lib.t6g(sch_1):page106_i243@pure_quanta.q_res(chips)',
 P_PATH='@t6g_mb_lib.t6g(sch_1):page107_i243@pure_quanta.q_res(chips)',
 PATH='I243',
 DRAWING='@T6G_MB_LIB.T6G(SCH_1):PAGE106',
 WATTAGE='1/16W',
 TOLERANCE='1%',
 MATERIAL='CHIP',
 PHYS_PAGE='107',
 XY='(-8000,2775)',
 ROT='0',
 VER='1',
 PACK_TYPE='0402LF',
 LOCATION='R1709',
 CDS_LIB='pure_quanta',
 CDS_PART_NAME='Q_RES_0402LF-10,1%,1/16W,CHIP,CS01002FB07',
 PART_NUMBER='CS01002FB07',
 VALUE='10',
 PRIM_FILE='./archive_libs/logical/q_res/chips/chips.prt';

PART_NAME
 R1710 'Q_RES_0402LF-10,1%,1/16W,CHIP,CS01002FB07':;

SECTION_NUMBER 1
 '@T6G_MB_LIB.T6G(SCH_1):PAGE107_I242@PURE_QUANTA.Q_RES(CHIPS)':
 C_PATH='@t6g_mb_lib.t6g(sch_1):page107_i242@pure_quanta.q_res(chips)',
 P_PATH='@t6g_mb_lib.t6g(sch_1):page108_i242@pure_quanta.q_res(chips)',
 PATH='I242',
 DRAWING='@T6G_MB_LIB.T6G(SCH_1):PAGE107',
 WATTAGE='1/16W',
 TOLERANCE='1%',
 MATERIAL='CHIP',
 PHYS_PAGE='108',
 XY='(-8125,2775)',
 ROT='0',
 VER='1',
 PACK_TYPE='0402LF',
 LOCATION='R1710',
 CDS_LIB='pure_quanta',
 CDS_PART_NAME='Q_RES_0402LF-10,1%,1/16W,CHIP,CS01002FB07',
 PART_NUMBER='CS01002FB07',
 VALUE='10',
 PRIM_FILE='./archive_libs/logical/q_res/chips/chips.prt';

PART_NAME
 R1711 'Q_RES_0402LF-10,1%,1/16W,CHIP,CS01002FB07':;

SECTION_NUMBER 1
 '@T6G_MB_LIB.T6G(SCH_1):PAGE108_I242@PURE_QUANTA.Q_RES(CHIPS)':
 C_PATH='@t6g_mb_lib.t6g(sch_1):page108_i242@pure_quanta.q_res(chips)',
 P_PATH='@t6g_mb_lib.t6g(sch_1):page109_i242@pure_quanta.q_res(chips)',
 PATH='I242',
 DRAWING='@T6G_MB_LIB.T6G(SCH_1):PAGE108',
 WATTAGE='1/16W',
 TOLERANCE='1%',
 MATERIAL='CHIP',
 PHYS_PAGE='109',
 XY='(-8075,2850)',
 ROT='0',
 VER='1',
 PACK_TYPE='0402LF',
 LOCATION='R1711',
 CDS_LIB='pure_quanta',
 CDS_PART_NAME='Q_RES_0402LF-10,1%,1/16W,CHIP,CS01002FB07',
 PART_NUMBER='CS01002FB07',
 VALUE='10',
 PRIM_FILE='./archive_libs/logical/q_res/chips/chips.prt';

PART_NAME
 R1714 'Q_RES_0402LF-0,5%,1/16W,CHIP,CS00002JB13':
 ROOM='HSC BOM1';

SECTION_NUMBER 1
 '@T6G_MB_LIB.T6G(SCH_1):PAGE267_I36@PURE_QUANTA.Q_RES(CHIPS)':
 C_PATH='@t6g_mb_lib.t6g(sch_1):page267_i36@pure_quanta.q_res(chips)',
 P_PATH='@t6g_mb_lib.t6g(sch_1):page262_i36@pure_quanta.q_res(chips)',
 PATH='I36',
 DRAWING='@T6G_MB_LIB.T6G(SCH_1):PAGE267',
 WATTAGE='1/16W',
 TOLERANCE='5%',
 MATERIAL='CHIP',
 PHYS_PAGE='262',
 XY='(-13675,3075)',
 ROT='0',
 VER='1',
 PACK_TYPE='0402LF',
 LOCATION='R1714',
 CDS_LIB='pure_quanta',
 CDS_PART_NAME='Q_RES_0402LF-0,5%,1/16W,CHIP,CS00002JB13',
 ROOM='HSC BOM1',
 PART_NUMBER='CS00002JB13',
 VALUE='0',
 PRIM_FILE='./archive_libs/logical/q_res/chips/chips.prt';

PART_NAME
 R1719 'Q_RES_0402LF-33.2,1%,1/16W,CHIP,CS03322FB03':;

SECTION_NUMBER 1
 '@T6G_MB_LIB.T6G(SCH_1):PAGE336_I119@PURE_QUANTA.Q_RES(CHIPS)':
 C_PATH='@t6g_mb_lib.t6g(sch_1):page336_i119@pure_quanta.q_res(chips)',
 P_PATH='@t6g_mb_lib.t6g(sch_1):page132_i119@pure_quanta.q_res(chips)',
 PATH='I119',
 DRAWING='@T6G_MB_LIB.T6G(SCH_1):PAGE336',
 WATTAGE='1/16W',
 TOLERANCE='1%',
 MATERIAL='CHIP',
 PHYS_PAGE='132',
 XY='(-3450,3950)',
 ROT='0',
 VER='1',
 PACK_TYPE='0402LF',
 LOCATION='R1719',
 CDS_LIB='pure_quanta',
 CDS_PART_NAME='Q_RES_0402LF-33.2,1%,1/16W,CHIP,CS03322FB03',
 PART_NUMBER='CS03322FB03',
 VALUE='33.2',
 PRIM_FILE='./archive_libs/logical/q_res/chips/chips.prt';

PART_NAME
 R1727 'Q_RES_0402LF-10K,1%,1/16W,EMPTY,CS31002FB08':;

SECTION_NUMBER 1
 '@T6G_MB_LIB.T6G(SCH_1):PAGE148_I250@PURE_QUANTA.Q_RES(CHIPS)':
 C_PATH='@t6g_mb_lib.t6g(sch_1):page148_i250@pure_quanta.q_res(chips)',
 P_PATH='@t6g_mb_lib.t6g(sch_1):page171_i250@pure_quanta.q_res(chips)',
 PATH='I250',
 DRAWING='@T6G_MB_LIB.T6G(SCH_1):PAGE148',
 WATTAGE='1/16W',
 TOLERANCE='1%',
 MATERIAL='EMPTY',
 PHYS_PAGE='171',
 XY='(-3525,6050)',
 ROT='0',
 VER='2',
 PACK_TYPE='0402LF',
 LOCATION='R1727',
 CDS_LIB='pure_quanta',
 CDS_PART_NAME='Q_RES_0402LF-10K,1%,1/16W,EMPTY,CS31002FB08',
 PART_NUMBER='CS31002FB08',
 VALUE='10K',
 PRIM_FILE='./archive_libs/logical/q_res/chips/chips.prt';

PART_NAME
 R1728 'Q_RES_0402LF-10K,1%,1/16W,EMPTY,CS31002FB08':;

SECTION_NUMBER 1
 '@T6G_MB_LIB.T6G(SCH_1):PAGE148_I249@PURE_QUANTA.Q_RES(CHIPS)':
 C_PATH='@t6g_mb_lib.t6g(sch_1):page148_i249@pure_quanta.q_res(chips)',
 P_PATH='@t6g_mb_lib.t6g(sch_1):page171_i249@pure_quanta.q_res(chips)',
 PATH='I249',
 DRAWING='@T6G_MB_LIB.T6G(SCH_1):PAGE148',
 WATTAGE='1/16W',
 TOLERANCE='1%',
 MATERIAL='EMPTY',
 PHYS_PAGE='171',
 XY='(-3325,6050)',
 ROT='0',
 VER='2',
 PACK_TYPE='0402LF',
 LOCATION='R1728',
 CDS_LIB='pure_quanta',
 CDS_PART_NAME='Q_RES_0402LF-10K,1%,1/16W,EMPTY,CS31002FB08',
 PART_NUMBER='CS31002FB08',
 VALUE='10K',
 PRIM_FILE='./archive_libs/logical/q_res/chips/chips.prt';

PART_NAME
 R1729 'Q_RES_0402LF-4.7K,5%,1/16W,CHIP,CS24702JB10':;

SECTION_NUMBER 1
 '@T6G_MB_LIB.T6G(SCH_1):PAGE148_I306@PURE_QUANTA.Q_RES(CHIPS)':
 C_PATH='@t6g_mb_lib.t6g(sch_1):page148_i306@pure_quanta.q_res(chips)',
 P_PATH='@t6g_mb_lib.t6g(sch_1):page171_i306@pure_quanta.q_res(chips)',
 PATH='I306',
 DRAWING='@T6G_MB_LIB.T6G(SCH_1):PAGE148',
 WATTAGE='1/16W',
 TOLERANCE='5%',
 MATERIAL='CHIP',
 PHYS_PAGE='171',
 XY='(-7750,3650)',
 ROT='0',
 VER='2',
 PACK_TYPE='0402LF',
 LOCATION='R1729',
 CDS_LIB='pure_quanta',
 CDS_PART_NAME='Q_RES_0402LF-4.7K,5%,1/16W,CHIP,CS24702JB10',
 PART_NUMBER='CS24702JB10',
 VALUE='4.7K',
 PRIM_FILE='./archive_libs/logical/q_res/chips/chips.prt';

PART_NAME
 R1730 'Q_RES_0402LF-4.7K,5%,1/16W,EMPTY,CS24702JB10':;

SECTION_NUMBER 1
 '@T6G_MB_LIB.T6G(SCH_1):PAGE148_I305@PURE_QUANTA.Q_RES(CHIPS)':
 C_PATH='@t6g_mb_lib.t6g(sch_1):page148_i305@pure_quanta.q_res(chips)',
 P_PATH='@t6g_mb_lib.t6g(sch_1):page171_i305@pure_quanta.q_res(chips)',
 PATH='I305',
 DRAWING='@T6G_MB_LIB.T6G(SCH_1):PAGE148',
 WATTAGE='1/16W',
 TOLERANCE='5%',
 MATERIAL='EMPTY',
 PHYS_PAGE='171',
 XY='(-7700,4150)',
 ROT='0',
 VER='2',
 PACK_TYPE='0402LF',
 LOCATION='R1730',
 CDS_LIB='pure_quanta',
 CDS_PART_NAME='Q_RES_0402LF-4.7K,5%,1/16W,EMPTY,CS24702JB10',
 PART_NUMBER='CS24702JB10',
 VALUE='4.7K',
 PRIM_FILE='./archive_libs/logical/q_res/chips/chips.prt';

PART_NAME
 R1731 'Q_RES_0402LF-10K,1%,1/16W,EMPTY,CS31002FB08':;

SECTION_NUMBER 1
 '@T6G_MB_LIB.T6G(SCH_1):PAGE148_I245@PURE_QUANTA.Q_RES(CHIPS)':
 C_PATH='@t6g_mb_lib.t6g(sch_1):page148_i245@pure_quanta.q_res(chips)',
 P_PATH='@t6g_mb_lib.t6g(sch_1):page171_i245@pure_quanta.q_res(chips)',
 PATH='I245',
 DRAWING='@T6G_MB_LIB.T6G(SCH_1):PAGE148',
 WATTAGE='1/16W',
 TOLERANCE='1%',
 MATERIAL='EMPTY',
 PHYS_PAGE='171',
 XY='(-3125,6050)',
 ROT='0',
 VER='2',
 PACK_TYPE='0402LF',
 LOCATION='R1731',
 CDS_LIB='pure_quanta',
 CDS_PART_NAME='Q_RES_0402LF-10K,1%,1/16W,EMPTY,CS31002FB08',
 PART_NUMBER='CS31002FB08',
 VALUE='10K',
 PRIM_FILE='./archive_libs/logical/q_res/chips/chips.prt';

PART_NAME
 R1734 'Q_RES_0402LF-10K,1%,1/16W,CHIP,CS31002FB08':;

SECTION_NUMBER 1
 '@T6G_MB_LIB.T6G(SCH_1):PAGE148_I244@PURE_QUANTA.Q_RES(CHIPS)':
 C_PATH='@t6g_mb_lib.t6g(sch_1):page148_i244@pure_quanta.q_res(chips)',
 P_PATH='@t6g_mb_lib.t6g(sch_1):page171_i244@pure_quanta.q_res(chips)',
 PATH='I244',
 DRAWING='@T6G_MB_LIB.T6G(SCH_1):PAGE148',
 WATTAGE='1/16W',
 TOLERANCE='1%',
 MATERIAL='CHIP',
 PHYS_PAGE='171',
 XY='(-2875,6050)',
 ROT='0',
 VER='2',
 PACK_TYPE='0402LF',
 LOCATION='R1734',
 CDS_LIB='pure_quanta',
 CDS_PART_NAME='Q_RES_0402LF-10K,1%,1/16W,CHIP,CS31002FB08',
 PART_NUMBER='CS31002FB08',
 VALUE='10K',
 PRIM_FILE='./archive_libs/logical/q_res/chips/chips.prt';

PART_NAME
 R1735 'Q_RES_0402LF-10K,1%,1/16W,EMPTY,CS31002FB08':;

SECTION_NUMBER 1
 '@T6G_MB_LIB.T6G(SCH_1):PAGE148_I246@PURE_QUANTA.Q_RES(CHIPS)':
 C_PATH='@t6g_mb_lib.t6g(sch_1):page148_i246@pure_quanta.q_res(chips)',
 P_PATH='@t6g_mb_lib.t6g(sch_1):page171_i246@pure_quanta.q_res(chips)',
 PATH='I246',
 DRAWING='@T6G_MB_LIB.T6G(SCH_1):PAGE148',
 WATTAGE='1/16W',
 TOLERANCE='1%',
 MATERIAL='EMPTY',
 PHYS_PAGE='171',
 XY='(-2875,5550)',
 ROT='0',
 VER='2',
 PACK_TYPE='0402LF',
 LOCATION='R1735',
 CDS_LIB='pure_quanta',
 CDS_PART_NAME='Q_RES_0402LF-10K,1%,1/16W,EMPTY,CS31002FB08',
 PART_NUMBER='CS31002FB08',
 VALUE='10K',
 PRIM_FILE='./archive_libs/logical/q_res/chips/chips.prt';

PART_NAME
 R1736 'Q_RES_0402LF-0,5%,1/16W,CHIP,CS00002JB13':;

SECTION_NUMBER 1
 '@T6G_MB_LIB.T6G(SCH_1):PAGE148_I363@PURE_QUANTA.Q_RES(CHIPS)':
 C_PATH='@t6g_mb_lib.t6g(sch_1):page148_i363@pure_quanta.q_res(chips)',
 P_PATH='@t6g_mb_lib.t6g(sch_1):page171_i363@pure_quanta.q_res(chips)',
 PATH='I363',
 DRAWING='@T6G_MB_LIB.T6G(SCH_1):PAGE148',
 WATTAGE='1/16W',
 TOLERANCE='5%',
 MATERIAL='CHIP',
 PHYS_PAGE='171',
 XY='(-3200,4225)',
 ROT='0',
 VER='1',
 PACK_TYPE='0402LF',
 LOCATION='R1736',
 CDS_LIB='pure_quanta',
 CDS_PART_NAME='Q_RES_0402LF-0,5%,1/16W,CHIP,CS00002JB13',
 PART_NUMBER='CS00002JB13',
 VALUE='0',
 PRIM_FILE='./archive_libs/logical/q_res/chips/chips.prt';

PART_NAME
 R1737 'Q_RES_0402LF-0,5%,1/16W,CHIP,CS00002JB13':;

SECTION_NUMBER 1
 '@T6G_MB_LIB.T6G(SCH_1):PAGE148_I357@PURE_QUANTA.Q_RES(CHIPS)':
 C_PATH='@t6g_mb_lib.t6g(sch_1):page148_i357@pure_quanta.q_res(chips)',
 P_PATH='@t6g_mb_lib.t6g(sch_1):page171_i357@pure_quanta.q_res(chips)',
 PATH='I357',
 DRAWING='@T6G_MB_LIB.T6G(SCH_1):PAGE148',
 WATTAGE='1/16W',
 TOLERANCE='5%',
 MATERIAL='CHIP',
 PHYS_PAGE='171',
 XY='(-3200,3975)',
 ROT='0',
 VER='1',
 PACK_TYPE='0402LF',
 LOCATION='R1737',
 CDS_LIB='pure_quanta',
 CDS_PART_NAME='Q_RES_0402LF-0,5%,1/16W,CHIP,CS00002JB13',
 PART_NUMBER='CS00002JB13',
 VALUE='0',
 PRIM_FILE='./archive_libs/logical/q_res/chips/chips.prt';

PART_NAME
 R1738 'Q_RES_0402LF-0,5%,1/16W,CHIP,CS00002JB13':;

SECTION_NUMBER 1
 '@T6G_MB_LIB.T6G(SCH_1):PAGE148_I349@PURE_QUANTA.Q_RES(CHIPS)':
 C_PATH='@t6g_mb_lib.t6g(sch_1):page148_i349@pure_quanta.q_res(chips)',
 P_PATH='@t6g_mb_lib.t6g(sch_1):page171_i349@pure_quanta.q_res(chips)',
 PATH='I349',
 DRAWING='@T6G_MB_LIB.T6G(SCH_1):PAGE148',
 WATTAGE='1/16W',
 TOLERANCE='5%',
 MATERIAL='CHIP',
 PHYS_PAGE='171',
 XY='(-3200,2275)',
 ROT='0',
 VER='1',
 PACK_TYPE='0402LF',
 LOCATION='R1738',
 CDS_LIB='pure_quanta',
 CDS_PART_NAME='Q_RES_0402LF-0,5%,1/16W,CHIP,CS00002JB13',
 PART_NUMBER='CS00002JB13',
 VALUE='0',
 PRIM_FILE='./archive_libs/logical/q_res/chips/chips.prt';

PART_NAME
 R1739 'Q_RES_0402LF-0,5%,1/16W,CHIP,CS00002JB13':;

SECTION_NUMBER 1
 '@T6G_MB_LIB.T6G(SCH_1):PAGE148_I388@PURE_QUANTA.Q_RES(CHIPS)':
 C_PATH='@t6g_mb_lib.t6g(sch_1):page148_i388@pure_quanta.q_res(chips)',
 P_PATH='@t6g_mb_lib.t6g(sch_1):page171_i388@pure_quanta.q_res(chips)',
 PATH='I388',
 DRAWING='@T6G_MB_LIB.T6G(SCH_1):PAGE148',
 WATTAGE='1/16W',
 TOLERANCE='5%',
 MATERIAL='CHIP',
 PHYS_PAGE='171',
 XY='(-3200,2025)',
 ROT='0',
 VER='1',
 PACK_TYPE='0402LF',
 LOCATION='R1739',
 CDS_LIB='pure_quanta',
 CDS_PART_NAME='Q_RES_0402LF-0,5%,1/16W,CHIP,CS00002JB13',
 PART_NUMBER='CS00002JB13',
 VALUE='0',
 PRIM_FILE='./archive_libs/logical/q_res/chips/chips.prt';

PART_NAME
 R1740 'Q_RES_0402LF-22,1%,1/16W,CHIP,CS02202FB02':;

SECTION_NUMBER 1
 '@T6G_MB_LIB.T6G(SCH_1):PAGE148_I368@PURE_QUANTA.Q_RES(CHIPS)':
 C_PATH='@t6g_mb_lib.t6g(sch_1):page148_i368@pure_quanta.q_res(chips)',
 P_PATH='@t6g_mb_lib.t6g(sch_1):page171_i368@pure_quanta.q_res(chips)',
 PATH='I368',
 DRAWING='@T6G_MB_LIB.T6G(SCH_1):PAGE148',
 WATTAGE='1/16W',
 TOLERANCE='1%',
 MATERIAL='CHIP',
 PHYS_PAGE='171',
 XY='(-3200,4275)',
 ROT='0',
 VER='1',
 PACK_TYPE='0402LF',
 LOCATION='R1740',
 CDS_LIB='pure_quanta',
 CDS_PART_NAME='Q_RES_0402LF-22,1%,1/16W,CHIP,CS02202FB02',
 PART_NUMBER='CS02202FB02',
 VALUE='22',
 PRIM_FILE='./archive_libs/logical/q_res/chips/chips.prt';

PART_NAME
 R1741 'Q_RES_0402LF-22,1%,1/16W,CHIP,CS02202FB02':;

SECTION_NUMBER 1
 '@T6G_MB_LIB.T6G(SCH_1):PAGE148_I366@PURE_QUANTA.Q_RES(CHIPS)':
 C_PATH='@t6g_mb_lib.t6g(sch_1):page148_i366@pure_quanta.q_res(chips)',
 P_PATH='@t6g_mb_lib.t6g(sch_1):page171_i366@pure_quanta.q_res(chips)',
 PATH='I366',
 DRAWING='@T6G_MB_LIB.T6G(SCH_1):PAGE148',
 WATTAGE='1/16W',
 TOLERANCE='1%',
 MATERIAL='CHIP',
 PHYS_PAGE='171',
 XY='(-3200,4025)',
 ROT='0',
 VER='1',
 PACK_TYPE='0402LF',
 LOCATION='R1741',
 CDS_LIB='pure_quanta',
 CDS_PART_NAME='Q_RES_0402LF-22,1%,1/16W,CHIP,CS02202FB02',
 PART_NUMBER='CS02202FB02',
 VALUE='22',
 PRIM_FILE='./archive_libs/logical/q_res/chips/chips.prt';

PART_NAME
 R1742 'Q_RES_0402LF-22,1%,1/16W,CHIP,CS02202FB02':;

SECTION_NUMBER 1
 '@T6G_MB_LIB.T6G(SCH_1):PAGE148_I352@PURE_QUANTA.Q_RES(CHIPS)':
 C_PATH='@t6g_mb_lib.t6g(sch_1):page148_i352@pure_quanta.q_res(chips)',
 P_PATH='@t6g_mb_lib.t6g(sch_1):page171_i352@pure_quanta.q_res(chips)',
 PATH='I352',
 DRAWING='@T6G_MB_LIB.T6G(SCH_1):PAGE148',
 WATTAGE='1/16W',
 TOLERANCE='1%',
 MATERIAL='CHIP',
 PHYS_PAGE='171',
 XY='(-3200,2325)',
 ROT='0',
 VER='1',
 PACK_TYPE='0402LF',
 LOCATION='R1742',
 CDS_LIB='pure_quanta',
 CDS_PART_NAME='Q_RES_0402LF-22,1%,1/16W,CHIP,CS02202FB02',
 PART_NUMBER='CS02202FB02',
 VALUE='22',
 PRIM_FILE='./archive_libs/logical/q_res/chips/chips.prt';

PART_NAME
 R1743 'Q_RES_0402LF-22,1%,1/16W,CHIP,CS02202FB02':;

SECTION_NUMBER 1
 '@T6G_MB_LIB.T6G(SCH_1):PAGE148_I332@PURE_QUANTA.Q_RES(CHIPS)':
 C_PATH='@t6g_mb_lib.t6g(sch_1):page148_i332@pure_quanta.q_res(chips)',
 P_PATH='@t6g_mb_lib.t6g(sch_1):page171_i332@pure_quanta.q_res(chips)',
 PATH='I332',
 DRAWING='@T6G_MB_LIB.T6G(SCH_1):PAGE148',
 WATTAGE='1/16W',
 TOLERANCE='1%',
 MATERIAL='CHIP',
 PHYS_PAGE='171',
 XY='(-3200,2075)',
 ROT='0',
 VER='1',
 PACK_TYPE='0402LF',
 LOCATION='R1743',
 CDS_LIB='pure_quanta',
 CDS_PART_NAME='Q_RES_0402LF-22,1%,1/16W,CHIP,CS02202FB02',
 PART_NUMBER='CS02202FB02',
 VALUE='22',
 PRIM_FILE='./archive_libs/logical/q_res/chips/chips.prt';

PART_NAME
 R1744 'Q_RES_0402LF-10K,1%,1/16W,CHIP,CS31002FB08':;

SECTION_NUMBER 1
 '@T6G_MB_LIB.T6G(SCH_1):PAGE148_I261@PURE_QUANTA.Q_RES(CHIPS)':
 C_PATH='@t6g_mb_lib.t6g(sch_1):page148_i261@pure_quanta.q_res(chips)',
 P_PATH='@t6g_mb_lib.t6g(sch_1):page171_i261@pure_quanta.q_res(chips)',
 PATH='I261',
 DRAWING='@T6G_MB_LIB.T6G(SCH_1):PAGE148',
 WATTAGE='1/16W',
 TOLERANCE='1%',
 MATERIAL='CHIP',
 PHYS_PAGE='171',
 XY='(-1075,6025)',
 ROT='0',
 VER='2',
 PACK_TYPE='0402LF',
 LOCATION='R1744',
 CDS_LIB='pure_quanta',
 CDS_PART_NAME='Q_RES_0402LF-10K,1%,1/16W,CHIP,CS31002FB08',
 PART_NUMBER='CS31002FB08',
 VALUE='10K',
 PRIM_FILE='./archive_libs/logical/q_res/chips/chips.prt';

PART_NAME
 R1745 'Q_RES_0402LF-10K,1%,1/16W,CHIP,CS31002FB08':;

SECTION_NUMBER 1
 '@T6G_MB_LIB.T6G(SCH_1):PAGE148_I257@PURE_QUANTA.Q_RES(CHIPS)':
 C_PATH='@t6g_mb_lib.t6g(sch_1):page148_i257@pure_quanta.q_res(chips)',
 P_PATH='@t6g_mb_lib.t6g(sch_1):page171_i257@pure_quanta.q_res(chips)',
 PATH='I257',
 DRAWING='@T6G_MB_LIB.T6G(SCH_1):PAGE148',
 WATTAGE='1/16W',
 TOLERANCE='1%',
 MATERIAL='CHIP',
 PHYS_PAGE='171',
 XY='(-875,6025)',
 ROT='0',
 VER='2',
 PACK_TYPE='0402LF',
 LOCATION='R1745',
 CDS_LIB='pure_quanta',
 CDS_PART_NAME='Q_RES_0402LF-10K,1%,1/16W,CHIP,CS31002FB08',
 PART_NUMBER='CS31002FB08',
 VALUE='10K',
 PRIM_FILE='./archive_libs/logical/q_res/chips/chips.prt';

PART_NAME
 R1746 'Q_RES_0402LF-10K,1%,1/16W,CHIP,CS31002FB08':;

SECTION_NUMBER 1
 '@T6G_MB_LIB.T6G(SCH_1):PAGE148_I256@PURE_QUANTA.Q_RES(CHIPS)':
 C_PATH='@t6g_mb_lib.t6g(sch_1):page148_i256@pure_quanta.q_res(chips)',
 P_PATH='@t6g_mb_lib.t6g(sch_1):page171_i256@pure_quanta.q_res(chips)',
 PATH='I256',
 DRAWING='@T6G_MB_LIB.T6G(SCH_1):PAGE148',
 WATTAGE='1/16W',
 TOLERANCE='1%',
 MATERIAL='CHIP',
 PHYS_PAGE='171',
 XY='(-675,6025)',
 ROT='0',
 VER='2',
 PACK_TYPE='0402LF',
 LOCATION='R1746',
 CDS_LIB='pure_quanta',
 CDS_PART_NAME='Q_RES_0402LF-10K,1%,1/16W,CHIP,CS31002FB08',
 PART_NUMBER='CS31002FB08',
 VALUE='10K',
 PRIM_FILE='./archive_libs/logical/q_res/chips/chips.prt';

PART_NAME
 R1747 'Q_RES_0402LF-10K,1%,1/16W,CHIP,CS31002FB08':;

SECTION_NUMBER 1
 '@T6G_MB_LIB.T6G(SCH_1):PAGE148_I255@PURE_QUANTA.Q_RES(CHIPS)':
 C_PATH='@t6g_mb_lib.t6g(sch_1):page148_i255@pure_quanta.q_res(chips)',
 P_PATH='@t6g_mb_lib.t6g(sch_1):page171_i255@pure_quanta.q_res(chips)',
 PATH='I255',
 DRAWING='@T6G_MB_LIB.T6G(SCH_1):PAGE148',
 WATTAGE='1/16W',
 TOLERANCE='1%',
 MATERIAL='CHIP',
 PHYS_PAGE='171',
 XY='(-450,6025)',
 ROT='0',
 VER='2',
 PACK_TYPE='0402LF',
 LOCATION='R1747',
 CDS_LIB='pure_quanta',
 CDS_PART_NAME='Q_RES_0402LF-10K,1%,1/16W,CHIP,CS31002FB08',
 PART_NUMBER='CS31002FB08',
 VALUE='10K',
 PRIM_FILE='./archive_libs/logical/q_res/chips/chips.prt';

PART_NAME
 R1748 'Q_RES_0402LF-10K,1%,1/16W,EMPTY,CS31002FB08':;

SECTION_NUMBER 1
 '@T6G_MB_LIB.T6G(SCH_1):PAGE148_I258@PURE_QUANTA.Q_RES(CHIPS)':
 C_PATH='@t6g_mb_lib.t6g(sch_1):page148_i258@pure_quanta.q_res(chips)',
 P_PATH='@t6g_mb_lib.t6g(sch_1):page171_i258@pure_quanta.q_res(chips)',
 PATH='I258',
 DRAWING='@T6G_MB_LIB.T6G(SCH_1):PAGE148',
 WATTAGE='1/16W',
 TOLERANCE='1%',
 MATERIAL='EMPTY',
 PHYS_PAGE='171',
 XY='(-450,5525)',
 ROT='0',
 VER='2',
 PACK_TYPE='0402LF',
 LOCATION='R1748',
 CDS_LIB='pure_quanta',
 CDS_PART_NAME='Q_RES_0402LF-10K,1%,1/16W,EMPTY,CS31002FB08',
 PART_NUMBER='CS31002FB08',
 VALUE='10K',
 PRIM_FILE='./archive_libs/logical/q_res/chips/chips.prt';

PART_NAME
 R1775 'Q_RES_0402LF-1K,1%,1/16W,CHIP,CS21002FB06':;

SECTION_NUMBER 1
 '@T6G_MB_LIB.T6G(SCH_1):PAGE156_I131@PURE_QUANTA.Q_RES(CHIPS)':
 C_PATH='@t6g_mb_lib.t6g(sch_1):page156_i131@pure_quanta.q_res(chips)',
 P_PATH='@t6g_mb_lib.t6g(sch_1):page187_i131@pure_quanta.q_res(chips)',
 PATH='I131',
 DRAWING='@T6G_MB_LIB.T6G(SCH_1):PAGE156',
 WATTAGE='1/16W',
 TOLERANCE='1%',
 MATERIAL='CHIP',
 PHYS_PAGE='187',
 XY='(-8175,6950)',
 ROT='0',
 VER='1',
 PACK_TYPE='0402LF',
 LOCATION='R1775',
 CDS_LIB='pure_quanta',
 CDS_PART_NAME='Q_RES_0402LF-1K,1%,1/16W,CHIP,CS21002FB06',
 PART_NUMBER='CS21002FB06',
 VALUE='1K',
 PRIM_FILE='./archive_libs/logical/q_res/chips/chips.prt';

PART_NAME
 R1776 'Q_RES_0402LF-1K,1%,1/16W,CHIP,CS21002FB06':;

SECTION_NUMBER 1
 '@T6G_MB_LIB.T6G(SCH_1):PAGE156_I94@PURE_QUANTA.Q_RES(CHIPS)':
 C_PATH='@t6g_mb_lib.t6g(sch_1):page156_i94@pure_quanta.q_res(chips)',
 P_PATH='@t6g_mb_lib.t6g(sch_1):page187_i94@pure_quanta.q_res(chips)',
 PATH='I94',
 DRAWING='@T6G_MB_LIB.T6G(SCH_1):PAGE156',
 BOM_COST='VR_SYSTEM ',
 WATTAGE='1/16W',
 TOLERANCE='1%',
 MATERIAL='CHIP',
 PHYS_PAGE='187',
 XY='(-6700,4825)',
 ROT='0',
 VER='2',
 PACK_TYPE='0402LF',
 LOCATION='R1776',
 CDS_LIB='pure_quanta',
 CDS_PART_NAME='Q_RES_0402LF-1K,1%,1/16W,CHIP,CS21002FB06',
 PART_NUMBER='CS21002FB06',
 VALUE='1K',
 PRIM_FILE='./archive_libs/logical/q_res/chips/chips.prt';

PART_NAME
 R1777 'Q_RES_0402LF-1K,1%,1/16W,CHIP,CS21002FB06':;

SECTION_NUMBER 1
 '@T6G_MB_LIB.T6G(SCH_1):PAGE156_I129@PURE_QUANTA.Q_RES(CHIPS)':
 C_PATH='@t6g_mb_lib.t6g(sch_1):page156_i129@pure_quanta.q_res(chips)',
 P_PATH='@t6g_mb_lib.t6g(sch_1):page187_i129@pure_quanta.q_res(chips)',
 PATH='I129',
 DRAWING='@T6G_MB_LIB.T6G(SCH_1):PAGE156',
 WATTAGE='1/16W',
 TOLERANCE='1%',
 MATERIAL='CHIP',
 PHYS_PAGE='187',
 XY='(-4825,6350)',
 ROT='0',
 VER='2',
 PACK_TYPE='0402LF',
 LOCATION='R1777',
 CDS_LIB='pure_quanta',
 CDS_PART_NAME='Q_RES_0402LF-1K,1%,1/16W,CHIP,CS21002FB06',
 PART_NUMBER='CS21002FB06',
 VALUE='1K',
 PRIM_FILE='./archive_libs/logical/q_res/chips/chips.prt';

PART_NAME
 R1779 'Q_RES_0402LF-100,1%,1/16W,CHIP,CS11002FB07':;

SECTION_NUMBER 1
 '@T6G_MB_LIB.T6G(SCH_1):PAGE156_I116@PURE_QUANTA.Q_RES(CHIPS)':
 C_PATH='@t6g_mb_lib.t6g(sch_1):page156_i116@pure_quanta.q_res(chips)',
 P_PATH='@t6g_mb_lib.t6g(sch_1):page187_i116@pure_quanta.q_res(chips)',
 PATH='I116',
 DRAWING='@T6G_MB_LIB.T6G(SCH_1):PAGE156',
 WATTAGE='1/16W',
 TOLERANCE='1%',
 MATERIAL='CHIP',
 PHYS_PAGE='187',
 XY='(-2975,5700)',
 ROT='0',
 VER='1',
 PACK_TYPE='0402LF',
 LOCATION='R1779',
 CDS_LIB='pure_quanta',
 CDS_PART_NAME='Q_RES_0402LF-100,1%,1/16W,CHIP,CS11002FB07',
 PART_NUMBER='CS11002FB07',
 VALUE='100',
 PRIM_FILE='./archive_libs/logical/q_res/chips/chips.prt';

PART_NAME
 R1785 'Q_RES_0402LF-4.7K,1%,1/16W,CHIP,CS24702FB06':;

SECTION_NUMBER 1
 '@T6G_MB_LIB.T6G(SCH_1):PAGE369_I26@PURE_QUANTA.Q_RES(CHIPS)':
 C_PATH='@t6g_mb_lib.t6g(sch_1):page369_i26@pure_quanta.q_res(chips)',
 P_PATH='@t6g_mb_lib.t6g(sch_1):page257_i26@pure_quanta.q_res(chips)',
 PATH='I26',
 DRAWING='@T6G_MB_LIB.T6G(SCH_1):PAGE369',
 WATTAGE='1/16W',
 TOLERANCE='1%',
 MATERIAL='CHIP',
 PHYS_PAGE='257',
 XY='(-8900,5700)',
 ROT='0',
 VER='2',
 PACK_TYPE='0402LF',
 LOCATION='R1785',
 CDS_LIB='pure_quanta',
 CDS_PART_NAME='Q_RES_0402LF-4.7K,1%,1/16W,CHIP,CS24702FB06',
 PART_NUMBER='CS24702FB06',
 VALUE='4.7K',
 PRIM_FILE='./archive_libs/logical/q_res/chips/chips.prt';

PART_NAME
 R1791 'Q_RES_0402LF-9.09K,1%,1/16W,CHIP,CS29092FB05':;

SECTION_NUMBER 1
 '@T6G_MB_LIB.T6G(SCH_1):PAGE369_I14@PURE_QUANTA.Q_RES(CHIPS)':
 C_PATH='@t6g_mb_lib.t6g(sch_1):page369_i14@pure_quanta.q_res(chips)',
 P_PATH='@t6g_mb_lib.t6g(sch_1):page257_i14@pure_quanta.q_res(chips)',
 PATH='I14',
 DRAWING='@T6G_MB_LIB.T6G(SCH_1):PAGE369',
 WATTAGE='1/16W',
 TOLERANCE='1%',
 MATERIAL='CHIP',
 PHYS_PAGE='257',
 XY='(-8900,3200)',
 ROT='0',
 VER='2',
 PACK_TYPE='0402LF',
 LOCATION='R1791',
 CDS_LIB='pure_quanta',
 CDS_PART_NAME='Q_RES_0402LF-9.09K,1%,1/16W,CHIP,CS29092FB05',
 PART_NUMBER='CS29092FB05',
 VALUE='9.09K',
 PRIM_FILE='./archive_libs/logical/q_res/chips/chips.prt';

PART_NAME
 R1792 'Q_RES_0402LF-0,5%,1/16W,EMPTY,CS00002JB13':
 ROOM='ADC_MAM_BOM2';

SECTION_NUMBER 1
 '@T6G_MB_LIB.T6G(SCH_1):PAGE369_I146@PURE_QUANTA.Q_RES(CHIPS)':
 C_PATH='@t6g_mb_lib.t6g(sch_1):page369_i146@pure_quanta.q_res(chips)',
 P_PATH='@t6g_mb_lib.t6g(sch_1):page257_i146@pure_quanta.q_res(chips)',
 PATH='I146',
 DRAWING='@T6G_MB_LIB.T6G(SCH_1):PAGE369',
 WATTAGE='1/16W',
 TOLERANCE='5%',
 MATERIAL='EMPTY',
 PHYS_PAGE='257',
 XY='(-2400,3700)',
 ROT='0',
 VER='1',
 PACK_TYPE='0402LF',
 LOCATION='R1792',
 CDS_LIB='pure_quanta',
 CDS_PART_NAME='Q_RES_0402LF-0,5%,1/16W,EMPTY,CS00002JB13',
 ROOM='ADC_MAM_BOM2',
 PART_NUMBER='CS00002JB13',
 VALUE='0',
 PRIM_FILE='./archive_libs/logical/q_res/chips/chips.prt';

PART_NAME
 R1793 'Q_RES_0402LF-0,5%,1/16W,EMPTY,CS00002JB13':
 ROOM='ADC_MAM_BOM2';

SECTION_NUMBER 1
 '@T6G_MB_LIB.T6G(SCH_1):PAGE369_I147@PURE_QUANTA.Q_RES(CHIPS)':
 C_PATH='@t6g_mb_lib.t6g(sch_1):page369_i147@pure_quanta.q_res(chips)',
 P_PATH='@t6g_mb_lib.t6g(sch_1):page257_i147@pure_quanta.q_res(chips)',
 PATH='I147',
 DRAWING='@T6G_MB_LIB.T6G(SCH_1):PAGE369',
 WATTAGE='1/16W',
 TOLERANCE='5%',
 MATERIAL='EMPTY',
 PHYS_PAGE='257',
 XY='(-2400,3650)',
 ROT='0',
 VER='1',
 PACK_TYPE='0402LF',
 LOCATION='R1793',
 CDS_LIB='pure_quanta',
 CDS_PART_NAME='Q_RES_0402LF-0,5%,1/16W,EMPTY,CS00002JB13',
 ROOM='ADC_MAM_BOM2',
 PART_NUMBER='CS00002JB13',
 VALUE='0',
 PRIM_FILE='./archive_libs/logical/q_res/chips/chips.prt';

PART_NAME
 R1798 'Q_RES_0402LF-0,5%,1/16W,CHIP,CS00002JB13':;

SECTION_NUMBER 1
 '@T6G_MB_LIB.T6G(SCH_1):PAGE348_I26@PURE_QUANTA.Q_RES(CHIPS)':
 C_PATH='@t6g_mb_lib.t6g(sch_1):page348_i26@pure_quanta.q_res(chips)',
 P_PATH='@t6g_mb_lib.t6g(sch_1):page150_i26@pure_quanta.q_res(chips)',
 PATH='I26',
 DRAWING='@T6G_MB_LIB.T6G(SCH_1):PAGE348',
 WATTAGE='1/16W',
 TOLERANCE='5%',
 MATERIAL='CHIP',
 PHYS_PAGE='150',
 XY='(-14975,5875)',
 ROT='0',
 VER='1',
 PACK_TYPE='0402LF',
 LOCATION='R1798',
 CDS_LIB='pure_quanta',
 CDS_PART_NAME='Q_RES_0402LF-0,5%,1/16W,CHIP,CS00002JB13',
 PART_NUMBER='CS00002JB13',
 VALUE='0',
 PRIM_FILE='./archive_libs/logical/q_res/chips/chips.prt';

PART_NAME
 R1799 'Q_RES_0402LF-7.87K,1%,1/16W,CHIP,CS27872FB02':;

SECTION_NUMBER 1
 '@T6G_MB_LIB.T6G(SCH_1):PAGE369_I6@PURE_QUANTA.Q_RES(CHIPS)':
 C_PATH='@t6g_mb_lib.t6g(sch_1):page369_i6@pure_quanta.q_res(chips)',
 P_PATH='@t6g_mb_lib.t6g(sch_1):page257_i6@pure_quanta.q_res(chips)',
 PATH='I6',
 DRAWING='@T6G_MB_LIB.T6G(SCH_1):PAGE369',
 WATTAGE='1/16W',
 TOLERANCE='1%',
 MATERIAL='CHIP',
 PHYS_PAGE='257',
 XY='(-8925,2450)',
 ROT='0',
 VER='2',
 PACK_TYPE='0402LF',
 LOCATION='R1799',
 CDS_LIB='pure_quanta',
 CDS_PART_NAME='Q_RES_0402LF-7.87K,1%,1/16W,CHIP,CS27872FB02',
 PART_NUMBER='CS27872FB02',
 VALUE='7.87K',
 PRIM_FILE='./archive_libs/logical/q_res/chips/chips.prt';

PART_NAME
 R1800 'Q_RES_0402LF-1.21K,1%,1/16W,CHIP,CS21212FB05':;

SECTION_NUMBER 1
 '@T6G_MB_LIB.T6G(SCH_1):PAGE369_I170@PURE_QUANTA.Q_RES(CHIPS)':
 C_PATH='@t6g_mb_lib.t6g(sch_1):page369_i170@pure_quanta.q_res(chips)',
 P_PATH='@t6g_mb_lib.t6g(sch_1):page257_i170@pure_quanta.q_res(chips)',
 PATH='I170',
 DRAWING='@T6G_MB_LIB.T6G(SCH_1):PAGE369',
 SEC_TYPE='0402LF',
 WATTAGE='1/16W',
 TOLERANCE='1%',
 MATERIAL='CHIP',
 PHYS_PAGE='257',
 XY='(-8925,2000)',
 ROT='0',
 VER='2',
 PACK_TYPE='0402LF',
 LOCATION='R1800',
 SEC='1',
 CDS_LIB='pure_quanta',
 CDS_PART_NAME='Q_RES_0402LF-1.21K,1%,1/16W,CHIP,CS21212FB05',
 PART_NUMBER='CS21212FB05',
 VALUE='1.21K',
 PRIM_FILE='./archive_libs/logical/q_res/chips/chips.prt';

PART_NAME
 R1801 'Q_RES_0402LF-0,5%,1/16W,CHIP,CS00002JB13':;

SECTION_NUMBER 1
 '@T6G_MB_LIB.T6G(SCH_1):PAGE348_I171@PURE_QUANTA.Q_RES(CHIPS)':
 C_PATH='@t6g_mb_lib.t6g(sch_1):page348_i171@pure_quanta.q_res(chips)',
 P_PATH='@t6g_mb_lib.t6g(sch_1):page150_i171@pure_quanta.q_res(chips)',
 PATH='I171',
 DRAWING='@T6G_MB_LIB.T6G(SCH_1):PAGE348',
 WATTAGE='1/16W',
 TOLERANCE='5%',
 MATERIAL='CHIP',
 PHYS_PAGE='150',
 XY='(-9275,9550)',
 ROT='0',
 VER='2',
 PACK_TYPE='0402LF',
 LOCATION='R1801',
 CDS_LIB='pure_quanta',
 CDS_PART_NAME='Q_RES_0402LF-0,5%,1/16W,CHIP,CS00002JB13',
 PART_NUMBER='CS00002JB13',
 VALUE='0',
 PRIM_FILE='./archive_libs/logical/q_res/chips/chips.prt';

PART_NAME
 R1815 'Q_RES_0402LF-0,5%,1/16W,CHIP,CS00002JB13':;

SECTION_NUMBER 1
 '@T6G_MB_LIB.T6G(SCH_1):PAGE348_I29@PURE_QUANTA.Q_RES(CHIPS)':
 C_PATH='@t6g_mb_lib.t6g(sch_1):page348_i29@pure_quanta.q_res(chips)',
 P_PATH='@t6g_mb_lib.t6g(sch_1):page150_i29@pure_quanta.q_res(chips)',
 PATH='I29',
 DRAWING='@T6G_MB_LIB.T6G(SCH_1):PAGE348',
 WATTAGE='1/16W',
 TOLERANCE='5%',
 MATERIAL='CHIP',
 PHYS_PAGE='150',
 XY='(-14950,6175)',
 ROT='0',
 VER='1',
 PACK_TYPE='0402LF',
 LOCATION='R1815',
 CDS_LIB='pure_quanta',
 CDS_PART_NAME='Q_RES_0402LF-0,5%,1/16W,CHIP,CS00002JB13',
 PART_NUMBER='CS00002JB13',
 VALUE='0',
 PRIM_FILE='./archive_libs/logical/q_res/chips/chips.prt';

PART_NAME
 R1816 'Q_RES_0402LF-0,5%,1/16W,CHIP,CS00002JB13':;

SECTION_NUMBER 1
 '@T6G_MB_LIB.T6G(SCH_1):PAGE348_I32@PURE_QUANTA.Q_RES(CHIPS)':
 C_PATH='@t6g_mb_lib.t6g(sch_1):page348_i32@pure_quanta.q_res(chips)',
 P_PATH='@t6g_mb_lib.t6g(sch_1):page150_i32@pure_quanta.q_res(chips)',
 PATH='I32',
 DRAWING='@T6G_MB_LIB.T6G(SCH_1):PAGE348',
 WATTAGE='1/16W',
 TOLERANCE='5%',
 MATERIAL='CHIP',
 PHYS_PAGE='150',
 XY='(-14950,6325)',
 ROT='0',
 VER='1',
 PACK_TYPE='0402LF',
 LOCATION='R1816',
 CDS_LIB='pure_quanta',
 CDS_PART_NAME='Q_RES_0402LF-0,5%,1/16W,CHIP,CS00002JB13',
 PART_NUMBER='CS00002JB13',
 VALUE='0',
 PRIM_FILE='./archive_libs/logical/q_res/chips/chips.prt';

PART_NAME
 R1822 'Q_RES_0402LF-10K,1%,1/16W,CHIP,CS31002FB08':;

SECTION_NUMBER 1
 '@T6G_MB_LIB.T6G(SCH_1):PAGE252_I21@PURE_QUANTA.Q_RES(CHIPS)':
 C_PATH='@t6g_mb_lib.t6g(sch_1):page252_i21@pure_quanta.q_res(chips)',
 P_PATH='@t6g_mb_lib.t6g(sch_1):page250_i21@pure_quanta.q_res(chips)',
 PATH='I21',
 DRAWING='@T6G_MB_LIB.T6G(SCH_1):PAGE252',
 WATTAGE='1/16W',
 TOLERANCE='1%',
 MATERIAL='CHIP',
 PHYS_PAGE='250',
 XY='(-6600,5025)',
 ROT='2',
 VER='2',
 PACK_TYPE='0402LF',
 LOCATION='R1822',
 CDS_LIB='pure_quanta',
 CDS_PART_NAME='Q_RES_0402LF-10K,1%,1/16W,CHIP,CS31002FB08',
 PART_NUMBER='CS31002FB08',
 VALUE='10K',
 PRIM_FILE='./archive_libs/logical/q_res/chips/chips.prt';

PART_NAME
 R1824 'Q_RES_0402LF-10K,1%,1/16W,CHIP,CS31002FB08':;

SECTION_NUMBER 1
 '@T6G_MB_LIB.T6G(SCH_1):PAGE337_I11@PURE_QUANTA.Q_RES(CHIPS)':
 C_PATH='@t6g_mb_lib.t6g(sch_1):page337_i11@pure_quanta.q_res(chips)',
 P_PATH='@t6g_mb_lib.t6g(sch_1):page133_i11@pure_quanta.q_res(chips)',
 PATH='I11',
 DRAWING='@T6G_MB_LIB.T6G(SCH_1):PAGE337',
 WATTAGE='1/16W',
 TOLERANCE='1%',
 MATERIAL='CHIP',
 PHYS_PAGE='133',
 XY='(-9675,4625)',
 ROT='2',
 VER='2',
 PACK_TYPE='0402LF',
 LOCATION='R1824',
 CDS_LIB='pure_quanta',
 CDS_PART_NAME='Q_RES_0402LF-10K,1%,1/16W,CHIP,CS31002FB08',
 PART_NUMBER='CS31002FB08',
 VALUE='10K',
 PRIM_FILE='./archive_libs/logical/q_res/chips/chips.prt';

PART_NAME
 R1837 'Q_RES_4P_12-0.001,1%,3W,SMLF,CHIP,SP_CS+001DFR10':;

SECTION_NUMBER 1
 '@T6G_MB_LIB.T6G(SCH_1):PAGE264_I54@PURE_QUANTA.Q_RES_4P_12(CHIPS)':
 C_PATH='@t6g_mb_lib.t6g(sch_1):page264_i54@pure_quanta.q_res_4p_12(chips)',
 P_PATH='@t6g_mb_lib.t6g(sch_1):page259_i54@pure_quanta.q_res_4p_12(chips)',
 PATH='I54',
 DRAWING='@T6G_MB_LIB.T6G(SCH_1):PAGE264',
 WATTAGE='3W',
 TOLERANCE='1%',
 PART_TYPE='SMLF',
 MATERIAL='CHIP',
 PHYS_PAGE='259',
 XY='(-7925,4050)',
 ROT='1',
 VER='1',
 LOCATION='R1837',
 CDS_LIB='pure_quanta',
 CDS_PART_NAME='Q_RES_4P_12-0.001,1%,3W,SMLF,CHIP,SP_CS+001DFR10',
 PART_NUMBER='SP_CS+001DFR10',
 VALUE='0.001',
 PRIM_FILE='./archive_libs/logical/q_res_4p_12/chips/chips.prt';

PART_NAME
 R1838 'Q_RES_4P_12-0.001,1%,3W,SMLF,CHIP,SP_CS+001DFR10':;

SECTION_NUMBER 1
 '@T6G_MB_LIB.T6G(SCH_1):PAGE264_I58@PURE_QUANTA.Q_RES_4P_12(CHIPS)':
 C_PATH='@t6g_mb_lib.t6g(sch_1):page264_i58@pure_quanta.q_res_4p_12(chips)',
 P_PATH='@t6g_mb_lib.t6g(sch_1):page259_i58@pure_quanta.q_res_4p_12(chips)',
 PATH='I58',
 DRAWING='@T6G_MB_LIB.T6G(SCH_1):PAGE264',
 WATTAGE='3W',
 TOLERANCE='1%',
 PART_TYPE='SMLF',
 MATERIAL='CHIP',
 PHYS_PAGE='259',
 XY='(-7950,5500)',
 ROT='1',
 VER='1',
 LOCATION='R1838',
 CDS_LIB='pure_quanta',
 CDS_PART_NAME='Q_RES_4P_12-0.001,1%,3W,SMLF,CHIP,SP_CS+001DFR10',
 PART_NUMBER='SP_CS+001DFR10',
 VALUE='0.001',
 PRIM_FILE='./archive_libs/logical/q_res_4p_12/chips/chips.prt';

PART_NAME
 R1854 'Q_RES_0402LF-1K,1%,1/16W,CHIP,CS21002FB06':;

SECTION_NUMBER 1
 '@T6G_MB_LIB.T6G(SCH_1):PAGE350_I2@PURE_QUANTA.Q_RES(CHIPS)':
 C_PATH='@t6g_mb_lib.t6g(sch_1):page350_i2@pure_quanta.q_res(chips)',
 P_PATH='@t6g_mb_lib.t6g(sch_1):page152_i2@pure_quanta.q_res(chips)',
 PATH='I2',
 DRAWING='@T6G_MB_LIB.T6G(SCH_1):PAGE350',
 WATTAGE='1/16W',
 TOLERANCE='1%',
 MATERIAL='CHIP',
 PHYS_PAGE='152',
 XY='(-2750,13400)',
 ROT='2',
 VER='2',
 PACK_TYPE='0402LF',
 LOCATION='R1854',
 CDS_LIB='pure_quanta',
 CDS_PART_NAME='Q_RES_0402LF-1K,1%,1/16W,CHIP,CS21002FB06',
 PART_NUMBER='CS21002FB06',
 VALUE='1K',
 PRIM_FILE='./archive_libs/logical/q_res/chips/chips.prt';

PART_NAME
 R1856 'Q_RES_0402LF-100,1%,1/16W,CHIP,CS11002FB07':;

SECTION_NUMBER 1
 '@T6G_MB_LIB.T6G(SCH_1):PAGE350_I3@PURE_QUANTA.Q_RES(CHIPS)':
 C_PATH='@t6g_mb_lib.t6g(sch_1):page350_i3@pure_quanta.q_res(chips)',
 P_PATH='@t6g_mb_lib.t6g(sch_1):page152_i3@pure_quanta.q_res(chips)',
 PATH='I3',
 DRAWING='@T6G_MB_LIB.T6G(SCH_1):PAGE350',
 WATTAGE='1/16W',
 TOLERANCE='1%',
 MATERIAL='CHIP',
 PHYS_PAGE='152',
 XY='(-1800,13175)',
 ROT='0',
 VER='1',
 PACK_TYPE='0402LF',
 LOCATION='R1856',
 CDS_LIB='pure_quanta',
 CDS_PART_NAME='Q_RES_0402LF-100,1%,1/16W,CHIP,CS11002FB07',
 PART_NUMBER='CS11002FB07',
 VALUE='100',
 PRIM_FILE='./archive_libs/logical/q_res/chips/chips.prt';

PART_NAME
 R1857 'Q_RES_0402LF-10K,1%,1/16W,CHIP,CS31002FB08':;

SECTION_NUMBER 1
 '@T6G_MB_LIB.T6G(SCH_1):PAGE350_I18@PURE_QUANTA.Q_RES(CHIPS)':
 C_PATH='@t6g_mb_lib.t6g(sch_1):page350_i18@pure_quanta.q_res(chips)',
 P_PATH='@t6g_mb_lib.t6g(sch_1):page152_i18@pure_quanta.q_res(chips)',
 PATH='I18',
 DRAWING='@T6G_MB_LIB.T6G(SCH_1):PAGE350',
 WATTAGE='1/16W',
 TOLERANCE='1%',
 MATERIAL='CHIP',
 PHYS_PAGE='152',
 XY='(-2525,14550)',
 ROT='0',
 VER='2',
 PACK_TYPE='0402LF',
 LOCATION='R1857',
 CDS_LIB='pure_quanta',
 CDS_PART_NAME='Q_RES_0402LF-10K,1%,1/16W,CHIP,CS31002FB08',
 PART_NUMBER='CS31002FB08',
 VALUE='10K',
 PRIM_FILE='./archive_libs/logical/q_res/chips/chips.prt';

PART_NAME
 R1895 'Q_RES_0402LF-0,5%,1/16W,CHIP,CS00002JB13':;

SECTION_NUMBER 1
 '@T6G_MB_LIB.T6G(SCH_1):PAGE335_I169@PURE_QUANTA.Q_RES(CHIPS)':
 C_PATH='@t6g_mb_lib.t6g(sch_1):page335_i169@pure_quanta.q_res(chips)',
 P_PATH='@t6g_mb_lib.t6g(sch_1):page131_i169@pure_quanta.q_res(chips)',
 PATH='I169',
 DRAWING='@T6G_MB_LIB.T6G(SCH_1):PAGE335',
 WATTAGE='1/16W',
 TOLERANCE='5%',
 MATERIAL='CHIP',
 PHYS_PAGE='131',
 XY='(3125,5600)',
 ROT='0',
 VER='2',
 PACK_TYPE='0402LF',
 LOCATION='R1895',
 CDS_LIB='pure_quanta',
 CDS_PART_NAME='Q_RES_0402LF-0,5%,1/16W,CHIP,CS00002JB13',
 PART_NUMBER='CS00002JB13',
 VALUE='0',
 PRIM_FILE='./archive_libs/logical/q_res/chips/chips.prt';

PART_NAME
 R1896 'Q_RES_0402LF-100,1%,1/16W,CHIP,CS11002FB07':;

SECTION_NUMBER 1
 '@T6G_MB_LIB.T6G(SCH_1):PAGE336_I123@PURE_QUANTA.Q_RES(CHIPS)':
 C_PATH='@t6g_mb_lib.t6g(sch_1):page336_i123@pure_quanta.q_res(chips)',
 P_PATH='@t6g_mb_lib.t6g(sch_1):page132_i123@pure_quanta.q_res(chips)',
 PATH='I123',
 DRAWING='@T6G_MB_LIB.T6G(SCH_1):PAGE336',
 WATTAGE='1/16W',
 TOLERANCE='1%',
 MATERIAL='CHIP',
 PHYS_PAGE='132',
 XY='(1875,2100)',
 ROT='0',
 VER='2',
 PACK_TYPE='0402LF',
 LOCATION='R1896',
 CDS_LIB='pure_quanta',
 CDS_PART_NAME='Q_RES_0402LF-100,1%,1/16W,CHIP,CS11002FB07',
 PART_NUMBER='CS11002FB07',
 VALUE='100',
 PRIM_FILE='./archive_libs/logical/q_res/chips/chips.prt';

PART_NAME
 R1897 'Q_RES_0402LF-100,1%,1/16W,CHIP,CS11002FB07':;

SECTION_NUMBER 1
 '@T6G_MB_LIB.T6G(SCH_1):PAGE336_I124@PURE_QUANTA.Q_RES(CHIPS)':
 C_PATH='@t6g_mb_lib.t6g(sch_1):page336_i124@pure_quanta.q_res(chips)',
 P_PATH='@t6g_mb_lib.t6g(sch_1):page132_i124@pure_quanta.q_res(chips)',
 PATH='I124',
 DRAWING='@T6G_MB_LIB.T6G(SCH_1):PAGE336',
 WATTAGE='1/16W',
 TOLERANCE='1%',
 MATERIAL='CHIP',
 PHYS_PAGE='132',
 XY='(2125,2100)',
 ROT='0',
 VER='2',
 PACK_TYPE='0402LF',
 LOCATION='R1897',
 CDS_LIB='pure_quanta',
 CDS_PART_NAME='Q_RES_0402LF-100,1%,1/16W,CHIP,CS11002FB07',
 PART_NUMBER='CS11002FB07',
 VALUE='100',
 PRIM_FILE='./archive_libs/logical/q_res/chips/chips.prt';

PART_NAME
 R1898 'Q_RES_0402LF-100,1%,1/16W,CHIP,CS11002FB07':;

SECTION_NUMBER 1
 '@T6G_MB_LIB.T6G(SCH_1):PAGE336_I122@PURE_QUANTA.Q_RES(CHIPS)':
 C_PATH='@t6g_mb_lib.t6g(sch_1):page336_i122@pure_quanta.q_res(chips)',
 P_PATH='@t6g_mb_lib.t6g(sch_1):page132_i122@pure_quanta.q_res(chips)',
 PATH='I122',
 DRAWING='@T6G_MB_LIB.T6G(SCH_1):PAGE336',
 WATTAGE='1/16W',
 TOLERANCE='1%',
 MATERIAL='CHIP',
 PHYS_PAGE='132',
 XY='(2375,2100)',
 ROT='0',
 VER='2',
 PACK_TYPE='0402LF',
 LOCATION='R1898',
 CDS_LIB='pure_quanta',
 CDS_PART_NAME='Q_RES_0402LF-100,1%,1/16W,CHIP,CS11002FB07',
 PART_NUMBER='CS11002FB07',
 VALUE='100',
 PRIM_FILE='./archive_libs/logical/q_res/chips/chips.prt';

PART_NAME
 R1905 'Q_RES_0402LF-1K,1%,1/16W,CHIP,CS21002FB06':;

SECTION_NUMBER 1
 '@T6G_MB_LIB.T6G(SCH_1):PAGE338_I15@PURE_QUANTA.Q_RES(CHIPS)':
 C_PATH='@t6g_mb_lib.t6g(sch_1):page338_i15@pure_quanta.q_res(chips)',
 P_PATH='@t6g_mb_lib.t6g(sch_1):page134_i15@pure_quanta.q_res(chips)',
 PATH='I15',
 DRAWING='@T6G_MB_LIB.T6G(SCH_1):PAGE338',
 WATTAGE='1/16W',
 TOLERANCE='1%',
 MATERIAL='CHIP',
 PHYS_PAGE='134',
 XY='(3950,9750)',
 ROT='0',
 VER='2',
 PACK_TYPE='0402LF',
 LOCATION='R1905',
 CDS_LIB='pure_quanta',
 CDS_PART_NAME='Q_RES_0402LF-1K,1%,1/16W,CHIP,CS21002FB06',
 PART_NUMBER='CS21002FB06',
 VALUE='1K',
 PRIM_FILE='./archive_libs/logical/q_res/chips/chips.prt';

PART_NAME
 R1906 'Q_RES_0402LF-1K,1%,1/16W,CHIP,CS21002FB06':;

SECTION_NUMBER 1
 '@T6G_MB_LIB.T6G(SCH_1):PAGE338_I9@PURE_QUANTA.Q_RES(CHIPS)':
 C_PATH='@t6g_mb_lib.t6g(sch_1):page338_i9@pure_quanta.q_res(chips)',
 P_PATH='@t6g_mb_lib.t6g(sch_1):page134_i9@pure_quanta.q_res(chips)',
 PATH='I9',
 DRAWING='@T6G_MB_LIB.T6G(SCH_1):PAGE338',
 WATTAGE='1/16W',
 TOLERANCE='1%',
 MATERIAL='CHIP',
 PHYS_PAGE='134',
 XY='(3900,8850)',
 ROT='0',
 VER='2',
 PACK_TYPE='0402LF',
 LOCATION='R1906',
 CDS_LIB='pure_quanta',
 CDS_PART_NAME='Q_RES_0402LF-1K,1%,1/16W,CHIP,CS21002FB06',
 PART_NUMBER='CS21002FB06',
 VALUE='1K',
 PRIM_FILE='./archive_libs/logical/q_res/chips/chips.prt';

PART_NAME
 R1907 'Q_RES_0402LF-1K,1%,1/16W,CHIP,CS21002FB06':;

SECTION_NUMBER 1
 '@T6G_MB_LIB.T6G(SCH_1):PAGE338_I28@PURE_QUANTA.Q_RES(CHIPS)':
 C_PATH='@t6g_mb_lib.t6g(sch_1):page338_i28@pure_quanta.q_res(chips)',
 P_PATH='@t6g_mb_lib.t6g(sch_1):page134_i28@pure_quanta.q_res(chips)',
 PATH='I28',
 DRAWING='@T6G_MB_LIB.T6G(SCH_1):PAGE338',
 WATTAGE='1/16W',
 TOLERANCE='1%',
 MATERIAL='CHIP',
 PHYS_PAGE='134',
 XY='(4225,9750)',
 ROT='0',
 VER='2',
 PACK_TYPE='0402LF',
 LOCATION='R1907',
 CDS_LIB='pure_quanta',
 CDS_PART_NAME='Q_RES_0402LF-1K,1%,1/16W,CHIP,CS21002FB06',
 PART_NUMBER='CS21002FB06',
 VALUE='1K',
 PRIM_FILE='./archive_libs/logical/q_res/chips/chips.prt';

PART_NAME
 R1908 'Q_RES_0402LF-1K,1%,1/16W,CHIP,CS21002FB06':;

SECTION_NUMBER 1
 '@T6G_MB_LIB.T6G(SCH_1):PAGE338_I24@PURE_QUANTA.Q_RES(CHIPS)':
 C_PATH='@t6g_mb_lib.t6g(sch_1):page338_i24@pure_quanta.q_res(chips)',
 P_PATH='@t6g_mb_lib.t6g(sch_1):page134_i24@pure_quanta.q_res(chips)',
 PATH='I24',
 DRAWING='@T6G_MB_LIB.T6G(SCH_1):PAGE338',
 WATTAGE='1/16W',
 TOLERANCE='1%',
 MATERIAL='CHIP',
 PHYS_PAGE='134',
 XY='(4125,8850)',
 ROT='0',
 VER='2',
 PACK_TYPE='0402LF',
 LOCATION='R1908',
 CDS_LIB='pure_quanta',
 CDS_PART_NAME='Q_RES_0402LF-1K,1%,1/16W,CHIP,CS21002FB06',
 PART_NUMBER='CS21002FB06',
 VALUE='1K',
 PRIM_FILE='./archive_libs/logical/q_res/chips/chips.prt';

PART_NAME
 R1929 'Q_RES_0402LF-10K,1%,1/16W,CHIP,CS31002FB08':;

SECTION_NUMBER 1
 '@T6G_MB_LIB.T6G(SCH_1):PAGE335_I8@PURE_QUANTA.Q_RES(CHIPS)':
 C_PATH='@t6g_mb_lib.t6g(sch_1):page335_i8@pure_quanta.q_res(chips)',
 P_PATH='@t6g_mb_lib.t6g(sch_1):page131_i8@pure_quanta.q_res(chips)',
 PATH='I8',
 DRAWING='@T6G_MB_LIB.T6G(SCH_1):PAGE335',
 WATTAGE='1/16W',
 TOLERANCE='1%',
 MATERIAL='CHIP',
 PHYS_PAGE='131',
 XY='(-4225,4725)',
 ROT='0',
 VER='1',
 PACK_TYPE='0402LF',
 LOCATION='R1929',
 CDS_LIB='pure_quanta',
 CDS_PART_NAME='Q_RES_0402LF-10K,1%,1/16W,CHIP,CS31002FB08',
 PART_NUMBER='CS31002FB08',
 VALUE='10K',
 PRIM_FILE='./archive_libs/logical/q_res/chips/chips.prt';

PART_NAME
 R1930 'Q_RES_0402LF-10K,1%,1/16W,CHIP,CS31002FB08':;

SECTION_NUMBER 1
 '@T6G_MB_LIB.T6G(SCH_1):PAGE335_I7@PURE_QUANTA.Q_RES(CHIPS)':
 C_PATH='@t6g_mb_lib.t6g(sch_1):page335_i7@pure_quanta.q_res(chips)',
 P_PATH='@t6g_mb_lib.t6g(sch_1):page131_i7@pure_quanta.q_res(chips)',
 PATH='I7',
 DRAWING='@T6G_MB_LIB.T6G(SCH_1):PAGE335',
 WATTAGE='1/16W',
 TOLERANCE='1%',
 MATERIAL='CHIP',
 PHYS_PAGE='131',
 XY='(-4225,4625)',
 ROT='0',
 VER='1',
 PACK_TYPE='0402LF',
 LOCATION='R1930',
 CDS_LIB='pure_quanta',
 CDS_PART_NAME='Q_RES_0402LF-10K,1%,1/16W,CHIP,CS31002FB08',
 PART_NUMBER='CS31002FB08',
 VALUE='10K',
 PRIM_FILE='./archive_libs/logical/q_res/chips/chips.prt';

PART_NAME
 R2113 'Q_RES_0402LF-0,5%,1/16W,CHIP,CS00002JB13':;

SECTION_NUMBER 1
 '@T6G_MB_LIB.T6G(SCH_1):PAGE345_I12@PURE_QUANTA.Q_RES(CHIPS)':
 C_PATH='@t6g_mb_lib.t6g(sch_1):page345_i12@pure_quanta.q_res(chips)',
 P_PATH='@t6g_mb_lib.t6g(sch_1):page144_i12@pure_quanta.q_res(chips)',
 PATH='I12',
 DRAWING='@T6G_MB_LIB.T6G(SCH_1):PAGE345',
 WATTAGE='1/16W',
 TOLERANCE='5%',
 MATERIAL='CHIP',
 PHYS_PAGE='144',
 XY='(11100,-525)',
 ROT='0',
 VER='1',
 PACK_TYPE='0402LF',
 LOCATION='R2113',
 CDS_LIB='pure_quanta',
 CDS_PART_NAME='Q_RES_0402LF-0,5%,1/16W,CHIP,CS00002JB13',
 PART_NUMBER='CS00002JB13',
 VALUE='0',
 PRIM_FILE='./archive_libs/logical/q_res/chips/chips.prt';

PART_NAME
 R2114 'Q_RES_0402LF-0,5%,1/16W,CHIP,CS00002JB13':;

SECTION_NUMBER 1
 '@T6G_MB_LIB.T6G(SCH_1):PAGE297_I37@PURE_QUANTA.Q_RES(CHIPS)':
 C_PATH='@t6g_mb_lib.t6g(sch_1):page297_i37@pure_quanta.q_res(chips)',
 P_PATH='@t6g_mb_lib.t6g(sch_1):page145_i37@pure_quanta.q_res(chips)',
 PATH='I37',
 DRAWING='@T6G_MB_LIB.T6G(SCH_1):PAGE297',
 WATTAGE='1/16W',
 TOLERANCE='5%',
 MATERIAL='CHIP',
 PHYS_PAGE='145',
 XY='(1900,-800)',
 ROT='0',
 VER='1',
 PACK_TYPE='0402LF',
 LOCATION='R2114',
 CDS_LIB='pure_quanta',
 CDS_PART_NAME='Q_RES_0402LF-0,5%,1/16W,CHIP,CS00002JB13',
 PART_NUMBER='CS00002JB13',
 VALUE='0',
 PRIM_FILE='./archive_libs/logical/q_res/chips/chips.prt';

PART_NAME
 R2121 'Q_RES_0402LF-4.7K,5%,1/16W,CHIP,CS24702JB10':;

SECTION_NUMBER 1
 '@T6G_MB_LIB.T6G(SCH_1):PAGE345_I10@PURE_QUANTA.Q_RES(CHIPS)':
 C_PATH='@t6g_mb_lib.t6g(sch_1):page345_i10@pure_quanta.q_res(chips)',
 P_PATH='@t6g_mb_lib.t6g(sch_1):page144_i10@pure_quanta.q_res(chips)',
 PATH='I10',
 DRAWING='@T6G_MB_LIB.T6G(SCH_1):PAGE345',
 WATTAGE='1/16W',
 TOLERANCE='5%',
 MATERIAL='CHIP',
 PHYS_PAGE='144',
 XY='(10675,-325)',
 ROT='0',
 VER='2',
 PACK_TYPE='0402LF',
 LOCATION='R2121',
 CDS_LIB='pure_quanta',
 CDS_PART_NAME='Q_RES_0402LF-4.7K,5%,1/16W,CHIP,CS24702JB10',
 PART_NUMBER='CS24702JB10',
 VALUE='4.7K',
 PRIM_FILE='./archive_libs/logical/q_res/chips/chips.prt';

PART_NAME
 R2125 'Q_RES_0402LF-4.7K,5%,1/16W,CHIP,CS24702JB10':;

SECTION_NUMBER 1
 '@T6G_MB_LIB.T6G(SCH_1):PAGE297_I40@PURE_QUANTA.Q_RES(CHIPS)':
 C_PATH='@t6g_mb_lib.t6g(sch_1):page297_i40@pure_quanta.q_res(chips)',
 P_PATH='@t6g_mb_lib.t6g(sch_1):page145_i40@pure_quanta.q_res(chips)',
 PATH='I40',
 DRAWING='@T6G_MB_LIB.T6G(SCH_1):PAGE297',
 WATTAGE='1/16W',
 TOLERANCE='5%',
 MATERIAL='CHIP',
 PHYS_PAGE='145',
 XY='(3200,-350)',
 ROT='0',
 VER='2',
 PACK_TYPE='0402LF',
 LOCATION='R2125',
 CDS_LIB='pure_quanta',
 CDS_PART_NAME='Q_RES_0402LF-4.7K,5%,1/16W,CHIP,CS24702JB10',
 PART_NUMBER='CS24702JB10',
 VALUE='4.7K',
 PRIM_FILE='./archive_libs/logical/q_res/chips/chips.prt';

PART_NAME
 R2204 'Q_RES_0402LF-2.2K,5%,1/16W,EMPTY,CS22202JB07':;

SECTION_NUMBER 1
 '@T6G_MB_LIB.T6G(SCH_1):PAGE252_I50@PURE_QUANTA.Q_RES(CHIPS)':
 C_PATH='@t6g_mb_lib.t6g(sch_1):page252_i50@pure_quanta.q_res(chips)',
 P_PATH='@t6g_mb_lib.t6g(sch_1):page250_i50@pure_quanta.q_res(chips)',
 PATH='I50',
 DRAWING='@T6G_MB_LIB.T6G(SCH_1):PAGE252',
 WATTAGE='1/16W',
 TOLERANCE='5%',
 MATERIAL='EMPTY',
 PHYS_PAGE='250',
 XY='(-2150,2825)',
 ROT='0',
 VER='1',
 PACK_TYPE='0402LF',
 LOCATION='R2204',
 CDS_LIB='pure_quanta',
 CDS_PART_NAME='Q_RES_0402LF-2.2K,5%,1/16W,EMPTY,CS22202JB07',
 PART_NUMBER='CS22202JB07',
 VALUE='2.2K',
 PRIM_FILE='./archive_libs/logical/q_res/chips/chips.prt';

PART_NAME
 R2205 'Q_RES_0402LF-2.2K,5%,1/16W,EMPTY,CS22202JB07':;

SECTION_NUMBER 1
 '@T6G_MB_LIB.T6G(SCH_1):PAGE252_I49@PURE_QUANTA.Q_RES(CHIPS)':
 C_PATH='@t6g_mb_lib.t6g(sch_1):page252_i49@pure_quanta.q_res(chips)',
 P_PATH='@t6g_mb_lib.t6g(sch_1):page250_i49@pure_quanta.q_res(chips)',
 PATH='I49',
 DRAWING='@T6G_MB_LIB.T6G(SCH_1):PAGE252',
 WATTAGE='1/16W',
 TOLERANCE='5%',
 MATERIAL='EMPTY',
 PHYS_PAGE='250',
 XY='(-2150,2775)',
 ROT='0',
 VER='1',
 PACK_TYPE='0402LF',
 LOCATION='R2205',
 CDS_LIB='pure_quanta',
 CDS_PART_NAME='Q_RES_0402LF-2.2K,5%,1/16W,EMPTY,CS22202JB07',
 PART_NUMBER='CS22202JB07',
 VALUE='2.2K',
 PRIM_FILE='./archive_libs/logical/q_res/chips/chips.prt';

PART_NAME
 R2212 'Q_RES_0402LF-2.2K,5%,1/16W,EMPTY,CS22202JB07':;

SECTION_NUMBER 1
 '@T6G_MB_LIB.T6G(SCH_1):PAGE349_I126@PURE_QUANTA.Q_RES(CHIPS)':
 C_PATH='@t6g_mb_lib.t6g(sch_1):page349_i126@pure_quanta.q_res(chips)',
 P_PATH='@t6g_mb_lib.t6g(sch_1):page151_i126@pure_quanta.q_res(chips)',
 PATH='I126',
 DRAWING='@T6G_MB_LIB.T6G(SCH_1):PAGE349',
 WATTAGE='1/16W',
 TOLERANCE='5%',
 MATERIAL='EMPTY',
 PHYS_PAGE='151',
 XY='(4275,3475)',
 ROT='0',
 VER='1',
 PACK_TYPE='0402LF',
 LOCATION='R2212',
 CDS_LIB='pure_quanta',
 CDS_PART_NAME='Q_RES_0402LF-2.2K,5%,1/16W,EMPTY,CS22202JB07',
 PART_NUMBER='CS22202JB07',
 VALUE='2.2K',
 PRIM_FILE='./archive_libs/logical/q_res/chips/chips.prt';

PART_NAME
 R2213 'Q_RES_0402LF-2.2K,5%,1/16W,EMPTY,CS22202JB07':;

SECTION_NUMBER 1
 '@T6G_MB_LIB.T6G(SCH_1):PAGE349_I125@PURE_QUANTA.Q_RES(CHIPS)':
 C_PATH='@t6g_mb_lib.t6g(sch_1):page349_i125@pure_quanta.q_res(chips)',
 P_PATH='@t6g_mb_lib.t6g(sch_1):page151_i125@pure_quanta.q_res(chips)',
 PATH='I125',
 DRAWING='@T6G_MB_LIB.T6G(SCH_1):PAGE349',
 WATTAGE='1/16W',
 TOLERANCE='5%',
 MATERIAL='EMPTY',
 PHYS_PAGE='151',
 XY='(4275,3425)',
 ROT='0',
 VER='1',
 PACK_TYPE='0402LF',
 LOCATION='R2213',
 CDS_LIB='pure_quanta',
 CDS_PART_NAME='Q_RES_0402LF-2.2K,5%,1/16W,EMPTY,CS22202JB07',
 PART_NUMBER='CS22202JB07',
 VALUE='2.2K',
 PRIM_FILE='./archive_libs/logical/q_res/chips/chips.prt';

PART_NAME
 R2219 'Q_RES_0402LF-267K,1%,1/16W,EMPTY,CS42672FB03':;

SECTION_NUMBER 1
 '@T6G_MB_LIB.T6G(SCH_1):PAGE372_I30@PURE_QUANTA.Q_RES(CHIPS)':
 C_PATH='@t6g_mb_lib.t6g(sch_1):page372_i30@pure_quanta.q_res(chips)',
 P_PATH='@t6g_mb_lib.t6g(sch_1):page268_i30@pure_quanta.q_res(chips)',
 PATH='I30',
 DRAWING='@T6G_MB_LIB.T6G(SCH_1):PAGE372',
 WATTAGE='1/16W',
 TOLERANCE='1%',
 MATERIAL='EMPTY',
 PHYS_PAGE='268',
 XY='(-6200,5550)',
 ROT='0',
 VER='2',
 PACK_TYPE='0402LF',
 LOCATION='R2219',
 CDS_LIB='pure_quanta',
 CDS_PART_NAME='Q_RES_0402LF-267K,1%,1/16W,EMPTY,CS42672FB03',
 PART_NUMBER='CS42672FB03',
 VALUE='267K',
 PRIM_FILE='./archive_libs/logical/q_res/chips/chips.prt';

PART_NAME
 R2221 'Q_RES_0402LF-26.7K,1%,1/16W,EMPTY,CS32672FB03':;

SECTION_NUMBER 1
 '@T6G_MB_LIB.T6G(SCH_1):PAGE372_I35@PURE_QUANTA.Q_RES(CHIPS)':
 C_PATH='@t6g_mb_lib.t6g(sch_1):page372_i35@pure_quanta.q_res(chips)',
 P_PATH='@t6g_mb_lib.t6g(sch_1):page268_i35@pure_quanta.q_res(chips)',
 PATH='I35',
 DRAWING='@T6G_MB_LIB.T6G(SCH_1):PAGE372',
 WATTAGE='1/16W',
 TOLERANCE='1%',
 MATERIAL='EMPTY',
 PHYS_PAGE='268',
 XY='(-5600,5550)',
 ROT='0',
 VER='2',
 PACK_TYPE='0402LF',
 LOCATION='R2221',
 CDS_LIB='pure_quanta',
 CDS_PART_NAME='Q_RES_0402LF-26.7K,1%,1/16W,EMPTY,CS32672FB03',
 PART_NUMBER='CS32672FB03',
 VALUE='26.7K',
 PRIM_FILE='./archive_libs/logical/q_res/chips/chips.prt';

PART_NAME
 R2222 'Q_RES_0402LF-1K,1%,1/16W,EMPTY,CS21002FB06':;

SECTION_NUMBER 1
 '@T6G_MB_LIB.T6G(SCH_1):PAGE372_I33@PURE_QUANTA.Q_RES(CHIPS)':
 C_PATH='@t6g_mb_lib.t6g(sch_1):page372_i33@pure_quanta.q_res(chips)',
 P_PATH='@t6g_mb_lib.t6g(sch_1):page268_i33@pure_quanta.q_res(chips)',
 PATH='I33',
 DRAWING='@T6G_MB_LIB.T6G(SCH_1):PAGE372',
 WATTAGE='1/16W',
 TOLERANCE='1%',
 MATERIAL='EMPTY',
 PHYS_PAGE='268',
 XY='(-5600,4800)',
 ROT='0',
 VER='2',
 PACK_TYPE='0402LF',
 LOCATION='R2222',
 CDS_LIB='pure_quanta',
 CDS_PART_NAME='Q_RES_0402LF-1K,1%,1/16W,EMPTY,CS21002FB06',
 PART_NUMBER='CS21002FB06',
 VALUE='1K',
 PRIM_FILE='./archive_libs/logical/q_res/chips/chips.prt';

PART_NAME
 R2227 'Q_RES_0402LF-10K,1%,1/16W,EMPTY,CS31002FB08':;

SECTION_NUMBER 1
 '@T6G_MB_LIB.T6G(SCH_1):PAGE372_I29@PURE_QUANTA.Q_RES(CHIPS)':
 C_PATH='@t6g_mb_lib.t6g(sch_1):page372_i29@pure_quanta.q_res(chips)',
 P_PATH='@t6g_mb_lib.t6g(sch_1):page268_i29@pure_quanta.q_res(chips)',
 PATH='I29',
 DRAWING='@T6G_MB_LIB.T6G(SCH_1):PAGE372',
 WATTAGE='1/16W',
 TOLERANCE='1%',
 MATERIAL='EMPTY',
 PHYS_PAGE='268',
 XY='(-6200,4800)',
 ROT='0',
 VER='2',
 PACK_TYPE='0402LF',
 LOCATION='R2227',
 CDS_LIB='pure_quanta',
 CDS_PART_NAME='Q_RES_0402LF-10K,1%,1/16W,EMPTY,CS31002FB08',
 PART_NUMBER='CS31002FB08',
 VALUE='10K',
 PRIM_FILE='./archive_libs/logical/q_res/chips/chips.prt';

PART_NAME
 R2230 'Q_RES_0402LF-10K,1%,1/16W,EMPTY,CS31002FB08':;

SECTION_NUMBER 1
 '@T6G_MB_LIB.T6G(SCH_1):PAGE372_I43@PURE_QUANTA.Q_RES(CHIPS)':
 C_PATH='@t6g_mb_lib.t6g(sch_1):page372_i43@pure_quanta.q_res(chips)',
 P_PATH='@t6g_mb_lib.t6g(sch_1):page268_i43@pure_quanta.q_res(chips)',
 PATH='I43',
 DRAWING='@T6G_MB_LIB.T6G(SCH_1):PAGE372',
 WATTAGE='1/16W',
 TOLERANCE='1%',
 MATERIAL='EMPTY',
 PHYS_PAGE='268',
 XY='(-3275,5525)',
 ROT='0',
 VER='2',
 PACK_TYPE='0402LF',
 LOCATION='R2230',
 CDS_LIB='pure_quanta',
 CDS_PART_NAME='Q_RES_0402LF-10K,1%,1/16W,EMPTY,CS31002FB08',
 PART_NUMBER='CS31002FB08',
 VALUE='10K',
 PRIM_FILE='./archive_libs/logical/q_res/chips/chips.prt';

PART_NAME
 R2233 'Q_RES_0402LF-1K,1%,1/16W,EMPTY,CS21002FB06':;

SECTION_NUMBER 1
 '@T6G_MB_LIB.T6G(SCH_1):PAGE372_I45@PURE_QUANTA.Q_RES(CHIPS)':
 C_PATH='@t6g_mb_lib.t6g(sch_1):page372_i45@pure_quanta.q_res(chips)',
 P_PATH='@t6g_mb_lib.t6g(sch_1):page268_i45@pure_quanta.q_res(chips)',
 PATH='I45',
 DRAWING='@T6G_MB_LIB.T6G(SCH_1):PAGE372',
 WATTAGE='1/16W',
 TOLERANCE='1%',
 MATERIAL='EMPTY',
 PHYS_PAGE='268',
 XY='(-2975,5550)',
 ROT='0',
 VER='2',
 PACK_TYPE='0402LF',
 LOCATION='R2233',
 CDS_LIB='pure_quanta',
 CDS_PART_NAME='Q_RES_0402LF-1K,1%,1/16W,EMPTY,CS21002FB06',
 PART_NUMBER='CS21002FB06',
 VALUE='1K',
 PRIM_FILE='./archive_libs/logical/q_res/chips/chips.prt';

PART_NAME
 R2261 'Q_RES_0402LF-33.2,1%,1/16W,CHIP,CS03322FB03':;

SECTION_NUMBER 1
 '@T6G_MB_LIB.T6G(SCH_1):PAGE80_I284@PURE_QUANTA.Q_RES(CHIPS)':
 C_PATH='@t6g_mb_lib.t6g(sch_1):page80_i284@pure_quanta.q_res(chips)',
 P_PATH='@t6g_mb_lib.t6g(sch_1):page81_i284@pure_quanta.q_res(chips)',
 PATH='I284',
 DRAWING='@T6G_MB_LIB.T6G(SCH_1):PAGE80',
 WATTAGE='1/16W',
 TOLERANCE='1%',
 MATERIAL='CHIP',
 PHYS_PAGE='81',
 XY='(-6725,3175)',
 ROT='0',
 VER='1',
 PACK_TYPE='0402LF',
 LOCATION='R2261',
 CDS_LIB='pure_quanta',
 CDS_PART_NAME='Q_RES_0402LF-33.2,1%,1/16W,CHIP,CS03322FB03',
 PART_NUMBER='CS03322FB03',
 VALUE='33.2',
 PRIM_FILE='./archive_libs/logical/q_res/chips/chips.prt';

PART_NAME
 R2262 'Q_RES_0402LF-33.2,1%,1/16W,CHIP,CS03322FB03':;

SECTION_NUMBER 1
 '@T6G_MB_LIB.T6G(SCH_1):PAGE80_I294@PURE_QUANTA.Q_RES(CHIPS)':
 C_PATH='@t6g_mb_lib.t6g(sch_1):page80_i294@pure_quanta.q_res(chips)',
 P_PATH='@t6g_mb_lib.t6g(sch_1):page81_i294@pure_quanta.q_res(chips)',
 PATH='I294',
 DRAWING='@T6G_MB_LIB.T6G(SCH_1):PAGE80',
 WATTAGE='1/16W',
 TOLERANCE='1%',
 MATERIAL='CHIP',
 PHYS_PAGE='81',
 XY='(-6725,2275)',
 ROT='0',
 VER='1',
 PACK_TYPE='0402LF',
 LOCATION='R2262',
 CDS_LIB='pure_quanta',
 CDS_PART_NAME='Q_RES_0402LF-33.2,1%,1/16W,CHIP,CS03322FB03',
 PART_NUMBER='CS03322FB03',
 VALUE='33.2',
 PRIM_FILE='./archive_libs/logical/q_res/chips/chips.prt';

PART_NAME
 R2268 'Q_RES_0402LF-0,5%,1/16W,CHIP,CS00002JB13':;

SECTION_NUMBER 1
 '@T6G_MB_LIB.T6G(SCH_1):PAGE252_I28@PURE_QUANTA.Q_RES(CHIPS)':
 C_PATH='@t6g_mb_lib.t6g(sch_1):page252_i28@pure_quanta.q_res(chips)',
 P_PATH='@t6g_mb_lib.t6g(sch_1):page250_i28@pure_quanta.q_res(chips)',
 PATH='I28',
 DRAWING='@T6G_MB_LIB.T6G(SCH_1):PAGE252',
 WATTAGE='1/16W',
 TOLERANCE='5%',
 MATERIAL='CHIP',
 PHYS_PAGE='250',
 XY='(-5500,4675)',
 ROT='0',
 VER='1',
 PACK_TYPE='0402LF',
 LOCATION='R2268',
 CDS_LIB='pure_quanta',
 CDS_PART_NAME='Q_RES_0402LF-0,5%,1/16W,CHIP,CS00002JB13',
 PART_NUMBER='CS00002JB13',
 VALUE='0',
 PRIM_FILE='./archive_libs/logical/q_res/chips/chips.prt';

PART_NAME
 R2310 'Q_RES_0402LF-0,5%,1/16W,EMPTY,CS00002JB13':;

SECTION_NUMBER 1
 '@T6G_MB_LIB.T6G(SCH_1):PAGE136_I123@PURE_QUANTA.Q_RES(CHIPS)':
 C_PATH='@t6g_mb_lib.t6g(sch_1):page136_i123@pure_quanta.q_res(chips)',
 P_PATH='@t6g_mb_lib.t6g(sch_1):page159_i123@pure_quanta.q_res(chips)',
 PATH='I123',
 DRAWING='@T6G_MB_LIB.T6G(SCH_1):PAGE136',
 WATTAGE='1/16W',
 TOLERANCE='5%',
 MATERIAL='EMPTY',
 PHYS_PAGE='159',
 XY='(-6100,5325)',
 ROT='0',
 VER='1',
 PACK_TYPE='0402LF',
 LOCATION='R2310',
 CDS_LIB='pure_quanta',
 CDS_PART_NAME='Q_RES_0402LF-0,5%,1/16W,EMPTY,CS00002JB13',
 PART_NUMBER='CS00002JB13',
 VALUE='0',
 PRIM_FILE='./archive_libs/logical/q_res/chips/chips.prt';

PART_NAME
 R2311 'Q_RES_0402LF-0,5%,1/16W,EMPTY,CS00002JB13':;

SECTION_NUMBER 1
 '@T6G_MB_LIB.T6G(SCH_1):PAGE136_I124@PURE_QUANTA.Q_RES(CHIPS)':
 C_PATH='@t6g_mb_lib.t6g(sch_1):page136_i124@pure_quanta.q_res(chips)',
 P_PATH='@t6g_mb_lib.t6g(sch_1):page159_i124@pure_quanta.q_res(chips)',
 PATH='I124',
 DRAWING='@T6G_MB_LIB.T6G(SCH_1):PAGE136',
 WATTAGE='1/16W',
 TOLERANCE='5%',
 MATERIAL='EMPTY',
 PHYS_PAGE='159',
 XY='(-6100,5275)',
 ROT='0',
 VER='1',
 PACK_TYPE='0402LF',
 LOCATION='R2311',
 CDS_LIB='pure_quanta',
 CDS_PART_NAME='Q_RES_0402LF-0,5%,1/16W,EMPTY,CS00002JB13',
 PART_NUMBER='CS00002JB13',
 VALUE='0',
 PRIM_FILE='./archive_libs/logical/q_res/chips/chips.prt';

PART_NAME
 R2316 'Q_RES_0402LF-0,5%,1/16W,CHIP,CS00002JB13':;

SECTION_NUMBER 1
 '@T6G_MB_LIB.T6G(SCH_1):PAGE244_I26@PURE_QUANTA.Q_RES(CHIPS)':
 C_PATH='@t6g_mb_lib.t6g(sch_1):page244_i26@pure_quanta.q_res(chips)',
 P_PATH='@t6g_mb_lib.t6g(sch_1):page189_i26@pure_quanta.q_res(chips)',
 PATH='I26',
 DRAWING='@T6G_MB_LIB.T6G(SCH_1):PAGE244',
 WATTAGE='1/16W',
 TOLERANCE='5%',
 MATERIAL='CHIP',
 PHYS_PAGE='189',
 XY='(-3150,8250)',
 ROT='0',
 VER='1',
 PACK_TYPE='0402LF',
 LOCATION='R2316',
 CDS_LIB='pure_quanta',
 CDS_PART_NAME='Q_RES_0402LF-0,5%,1/16W,CHIP,CS00002JB13',
 PART_NUMBER='CS00002JB13',
 VALUE='0',
 PRIM_FILE='./archive_libs/logical/q_res/chips/chips.prt';

PART_NAME
 R2317 'Q_RES_0402LF-10K,1%,1/16W,CHIP,CS31002FB08':;

SECTION_NUMBER 1
 '@T6G_MB_LIB.T6G(SCH_1):PAGE297_I31@PURE_QUANTA.Q_RES(CHIPS)':
 C_PATH='@t6g_mb_lib.t6g(sch_1):page297_i31@pure_quanta.q_res(chips)',
 P_PATH='@t6g_mb_lib.t6g(sch_1):page145_i31@pure_quanta.q_res(chips)',
 PATH='I31',
 DRAWING='@T6G_MB_LIB.T6G(SCH_1):PAGE297',
 WATTAGE='1/16W',
 TOLERANCE='1%',
 MATERIAL='CHIP',
 PHYS_PAGE='145',
 XY='(-1775,4375)',
 ROT='0',
 VER='2',
 PACK_TYPE='0402LF',
 LOCATION='R2317',
 CDS_LIB='pure_quanta',
 CDS_PART_NAME='Q_RES_0402LF-10K,1%,1/16W,CHIP,CS31002FB08',
 PART_NUMBER='CS31002FB08',
 VALUE='10K',
 PRIM_FILE='./archive_libs/logical/q_res/chips/chips.prt';

PART_NAME
 R2318 'Q_RES_0402LF-0,5%,1/16W,CHIP,CS00002JB13':;

SECTION_NUMBER 1
 '@T6G_MB_LIB.T6G(SCH_1):PAGE27_I288@PURE_QUANTA.Q_RES(CHIPS)':
 C_PATH='@t6g_mb_lib.t6g(sch_1):page27_i288@pure_quanta.q_res(chips)',
 P_PATH='@t6g_mb_lib.t6g(sch_1):page27_i288@pure_quanta.q_res(chips)',
 PATH='I288',
 DRAWING='@T6G_MB_LIB.T6G(SCH_1):PAGE27',
 WATTAGE='1/16W',
 TOLERANCE='5%',
 MATERIAL='CHIP',
 PHYS_PAGE='27',
 XY='(-2375,1375)',
 ROT='0',
 VER='1',
 PACK_TYPE='0402LF',
 LOCATION='R2318',
 CDS_LIB='pure_quanta',
 CDS_PART_NAME='Q_RES_0402LF-0,5%,1/16W,CHIP,CS00002JB13',
 PART_NUMBER='CS00002JB13',
 VALUE='0',
 PRIM_FILE='./archive_libs/logical/q_res/chips/chips.prt';

PART_NAME
 R2343 'Q_RES_0402LF-10K,1%,1/16W,EMPTY,CS31002FB08':;

SECTION_NUMBER 1
 '@T6G_MB_LIB.T6G(SCH_1):PAGE84_I63@PURE_QUANTA.Q_RES(CHIPS)':
 C_PATH='@t6g_mb_lib.t6g(sch_1):page84_i63@pure_quanta.q_res(chips)',
 P_PATH='@t6g_mb_lib.t6g(sch_1):page85_i63@pure_quanta.q_res(chips)',
 PATH='I63',
 DRAWING='@T6G_MB_LIB.T6G(SCH_1):PAGE84',
 WATTAGE='1/16W',
 TOLERANCE='1%',
 MATERIAL='EMPTY',
 PHYS_PAGE='85',
 XY='(-4225,3900)',
 ROT='0',
 VER='2',
 PACK_TYPE='0402LF',
 LOCATION='R2343',
 CDS_LIB='pure_quanta',
 CDS_PART_NAME='Q_RES_0402LF-10K,1%,1/16W,EMPTY,CS31002FB08',
 PART_NUMBER='CS31002FB08',
 VALUE='10K',
 PRIM_FILE='./archive_libs/logical/q_res/chips/chips.prt';

PART_NAME
 R2344 'Q_RES_0402LF-4.7K,5%,1/16W,CHIP,CS24702JB10':;

SECTION_NUMBER 1
 '@T6G_MB_LIB.T6G(SCH_1):PAGE84_I67@PURE_QUANTA.Q_RES(CHIPS)':
 C_PATH='@t6g_mb_lib.t6g(sch_1):page84_i67@pure_quanta.q_res(chips)',
 P_PATH='@t6g_mb_lib.t6g(sch_1):page85_i67@pure_quanta.q_res(chips)',
 PATH='I67',
 DRAWING='@T6G_MB_LIB.T6G(SCH_1):PAGE84',
 WATTAGE='1/16W',
 TOLERANCE='5%',
 MATERIAL='CHIP',
 PHYS_PAGE='85',
 XY='(-3250,4100)',
 ROT='0',
 VER='2',
 PACK_TYPE='0402LF',
 LOCATION='R2344',
 CDS_LIB='pure_quanta',
 CDS_PART_NAME='Q_RES_0402LF-4.7K,5%,1/16W,CHIP,CS24702JB10',
 PART_NUMBER='CS24702JB10',
 VALUE='4.7K',
 PRIM_FILE='./archive_libs/logical/q_res/chips/chips.prt';

PART_NAME
 R2346 'Q_RES_0402LF-100K,1%,1/16W,CHIP,CS41002FB09':;

SECTION_NUMBER 1
 '@T6G_MB_LIB.T6G(SCH_1):PAGE84_I70@PURE_QUANTA.Q_RES(CHIPS)':
 C_PATH='@t6g_mb_lib.t6g(sch_1):page84_i70@pure_quanta.q_res(chips)',
 P_PATH='@t6g_mb_lib.t6g(sch_1):page85_i70@pure_quanta.q_res(chips)',
 PATH='I70',
 DRAWING='@T6G_MB_LIB.T6G(SCH_1):PAGE84',
 WATTAGE='1/16W',
 TOLERANCE='1%',
 MATERIAL='CHIP',
 PHYS_PAGE='85',
 XY='(-2100,4100)',
 ROT='0',
 VER='2',
 PACK_TYPE='0402LF',
 LOCATION='R2346',
 CDS_LIB='pure_quanta',
 CDS_PART_NAME='Q_RES_0402LF-100K,1%,1/16W,CHIP,CS41002FB09',
 PART_NUMBER='CS41002FB09',
 VALUE='100K',
 PRIM_FILE='./archive_libs/logical/q_res/chips/chips.prt';

PART_NAME
 R2356 'Q_RES_0402LF-10K,1%,1/16W,CHIP,CS31002FB08':;

SECTION_NUMBER 1
 '@T6G_MB_LIB.T6G(SCH_1):PAGE244_I25@PURE_QUANTA.Q_RES(CHIPS)':
 C_PATH='@t6g_mb_lib.t6g(sch_1):page244_i25@pure_quanta.q_res(chips)',
 P_PATH='@t6g_mb_lib.t6g(sch_1):page189_i25@pure_quanta.q_res(chips)',
 PATH='I25',
 DRAWING='@T6G_MB_LIB.T6G(SCH_1):PAGE244',
 SEC_TYPE='0402LF',
 WATTAGE='1/16W',
 TOLERANCE='1%',
 MATERIAL='CHIP',
 PHYS_PAGE='189',
 XY='(-3725,8625)',
 ROT='0',
 VER='2',
 PACK_TYPE='0402LF',
 LOCATION='R2356',
 SEC='1',
 CDS_LIB='pure_quanta',
 CDS_PART_NAME='Q_RES_0402LF-10K,1%,1/16W,CHIP,CS31002FB08',
 PART_NUMBER='CS31002FB08',
 VALUE='10K',
 PRIM_FILE='./archive_libs/logical/q_res/chips/chips.prt';

PART_NAME
 R2410 'Q_RES_0402LF-33.2,1%,1/16W,CHIP,CS03322FB03':;

SECTION_NUMBER 1
 '@T6G_MB_LIB.T6G(SCH_1):PAGE346_I65@PURE_QUANTA.Q_RES(CHIPS)':
 C_PATH='@t6g_mb_lib.t6g(sch_1):page346_i65@pure_quanta.q_res(chips)',
 P_PATH='@t6g_mb_lib.t6g(sch_1):page148_i65@pure_quanta.q_res(chips)',
 PATH='I65',
 DRAWING='@T6G_MB_LIB.T6G(SCH_1):PAGE346',
 WATTAGE='1/16W',
 TOLERANCE='1%',
 MATERIAL='CHIP',
 PHYS_PAGE='148',
 XY='(2800,3425)',
 ROT='0',
 VER='1',
 PACK_TYPE='0402LF',
 LOCATION='R2410',
 CDS_LIB='pure_quanta',
 CDS_PART_NAME='Q_RES_0402LF-33.2,1%,1/16W,CHIP,CS03322FB03',
 PART_NUMBER='CS03322FB03',
 VALUE='33.2',
 PRIM_FILE='./archive_libs/logical/q_res/chips/chips.prt';

PART_NAME
 R2411 'Q_RES_0402LF-33.2,1%,1/16W,CHIP,CS03322FB03':;

SECTION_NUMBER 1
 '@T6G_MB_LIB.T6G(SCH_1):PAGE346_I66@PURE_QUANTA.Q_RES(CHIPS)':
 C_PATH='@t6g_mb_lib.t6g(sch_1):page346_i66@pure_quanta.q_res(chips)',
 P_PATH='@t6g_mb_lib.t6g(sch_1):page148_i66@pure_quanta.q_res(chips)',
 PATH='I66',
 DRAWING='@T6G_MB_LIB.T6G(SCH_1):PAGE346',
 WATTAGE='1/16W',
 TOLERANCE='1%',
 MATERIAL='CHIP',
 PHYS_PAGE='148',
 XY='(2800,3375)',
 ROT='0',
 VER='1',
 PACK_TYPE='0402LF',
 LOCATION='R2411',
 CDS_LIB='pure_quanta',
 CDS_PART_NAME='Q_RES_0402LF-33.2,1%,1/16W,CHIP,CS03322FB03',
 PART_NUMBER='CS03322FB03',
 VALUE='33.2',
 PRIM_FILE='./archive_libs/logical/q_res/chips/chips.prt';

PART_NAME
 R2413 'Q_RES_0402LF-33.2,1%,1/16W,CHIP,CS03322FB03':;

SECTION_NUMBER 1
 '@T6G_MB_LIB.T6G(SCH_1):PAGE348_I86@PURE_QUANTA.Q_RES(CHIPS)':
 C_PATH='@t6g_mb_lib.t6g(sch_1):page348_i86@pure_quanta.q_res(chips)',
 P_PATH='@t6g_mb_lib.t6g(sch_1):page150_i86@pure_quanta.q_res(chips)',
 PATH='I86',
 DRAWING='@T6G_MB_LIB.T6G(SCH_1):PAGE348',
 WATTAGE='1/16W',
 TOLERANCE='1%',
 MATERIAL='CHIP',
 PHYS_PAGE='150',
 XY='(-14950,7075)',
 ROT='0',
 VER='1',
 PACK_TYPE='0402LF',
 LOCATION='R2413',
 CDS_LIB='pure_quanta',
 CDS_PART_NAME='Q_RES_0402LF-33.2,1%,1/16W,CHIP,CS03322FB03',
 PART_NUMBER='CS03322FB03',
 VALUE='33.2',
 PRIM_FILE='./archive_libs/logical/q_res/chips/chips.prt';

PART_NAME
 R2414 'Q_RES_0402LF-33.2,1%,1/16W,CHIP,CS03322FB03':;

SECTION_NUMBER 1
 '@T6G_MB_LIB.T6G(SCH_1):PAGE348_I85@PURE_QUANTA.Q_RES(CHIPS)':
 C_PATH='@t6g_mb_lib.t6g(sch_1):page348_i85@pure_quanta.q_res(chips)',
 P_PATH='@t6g_mb_lib.t6g(sch_1):page150_i85@pure_quanta.q_res(chips)',
 PATH='I85',
 DRAWING='@T6G_MB_LIB.T6G(SCH_1):PAGE348',
 WATTAGE='1/16W',
 TOLERANCE='1%',
 MATERIAL='CHIP',
 PHYS_PAGE='150',
 XY='(-14950,7025)',
 ROT='0',
 VER='1',
 PACK_TYPE='0402LF',
 LOCATION='R2414',
 CDS_LIB='pure_quanta',
 CDS_PART_NAME='Q_RES_0402LF-33.2,1%,1/16W,CHIP,CS03322FB03',
 PART_NUMBER='CS03322FB03',
 VALUE='33.2',
 PRIM_FILE='./archive_libs/logical/q_res/chips/chips.prt';

PART_NAME
 R2415 'Q_RES_0402LF-33.2,1%,1/16W,CHIP,CS03322FB03':;

SECTION_NUMBER 1
 '@T6G_MB_LIB.T6G(SCH_1):PAGE348_I60@PURE_QUANTA.Q_RES(CHIPS)':
 C_PATH='@t6g_mb_lib.t6g(sch_1):page348_i60@pure_quanta.q_res(chips)',
 P_PATH='@t6g_mb_lib.t6g(sch_1):page150_i60@pure_quanta.q_res(chips)',
 PATH='I60',
 DRAWING='@T6G_MB_LIB.T6G(SCH_1):PAGE348',
 WATTAGE='1/16W',
 TOLERANCE='1%',
 MATERIAL='CHIP',
 PHYS_PAGE='150',
 XY='(-14950,6725)',
 ROT='0',
 VER='1',
 PACK_TYPE='0402LF',
 LOCATION='R2415',
 CDS_LIB='pure_quanta',
 CDS_PART_NAME='Q_RES_0402LF-33.2,1%,1/16W,CHIP,CS03322FB03',
 PART_NUMBER='CS03322FB03',
 VALUE='33.2',
 PRIM_FILE='./archive_libs/logical/q_res/chips/chips.prt';

PART_NAME
 R2416 'Q_RES_0402LF-33.2,1%,1/16W,CHIP,CS03322FB03':;

SECTION_NUMBER 1
 '@T6G_MB_LIB.T6G(SCH_1):PAGE348_I33@PURE_QUANTA.Q_RES(CHIPS)':
 C_PATH='@t6g_mb_lib.t6g(sch_1):page348_i33@pure_quanta.q_res(chips)',
 P_PATH='@t6g_mb_lib.t6g(sch_1):page150_i33@pure_quanta.q_res(chips)',
 PATH='I33',
 DRAWING='@T6G_MB_LIB.T6G(SCH_1):PAGE348',
 WATTAGE='1/16W',
 TOLERANCE='1%',
 MATERIAL='CHIP',
 PHYS_PAGE='150',
 XY='(-14950,6675)',
 ROT='0',
 VER='1',
 PACK_TYPE='0402LF',
 LOCATION='R2416',
 CDS_LIB='pure_quanta',
 CDS_PART_NAME='Q_RES_0402LF-33.2,1%,1/16W,CHIP,CS03322FB03',
 PART_NUMBER='CS03322FB03',
 VALUE='33.2',
 PRIM_FILE='./archive_libs/logical/q_res/chips/chips.prt';

PART_NAME
 R2417 'Q_RES_0402LF-33.2,1%,1/16W,CHIP,CS03322FB03':;

SECTION_NUMBER 1
 '@T6G_MB_LIB.T6G(SCH_1):PAGE348_I35@PURE_QUANTA.Q_RES(CHIPS)':
 C_PATH='@t6g_mb_lib.t6g(sch_1):page348_i35@pure_quanta.q_res(chips)',
 P_PATH='@t6g_mb_lib.t6g(sch_1):page150_i35@pure_quanta.q_res(chips)',
 PATH='I35',
 DRAWING='@T6G_MB_LIB.T6G(SCH_1):PAGE348',
 WATTAGE='1/16W',
 TOLERANCE='1%',
 MATERIAL='CHIP',
 PHYS_PAGE='150',
 XY='(-14950,6625)',
 ROT='0',
 VER='1',
 PACK_TYPE='0402LF',
 LOCATION='R2417',
 CDS_LIB='pure_quanta',
 CDS_PART_NAME='Q_RES_0402LF-33.2,1%,1/16W,CHIP,CS03322FB03',
 PART_NUMBER='CS03322FB03',
 VALUE='33.2',
 PRIM_FILE='./archive_libs/logical/q_res/chips/chips.prt';

PART_NAME
 R2418 'Q_RES_0402LF-33.2,1%,1/16W,CHIP,CS03322FB03':;

SECTION_NUMBER 1
 '@T6G_MB_LIB.T6G(SCH_1):PAGE348_I34@PURE_QUANTA.Q_RES(CHIPS)':
 C_PATH='@t6g_mb_lib.t6g(sch_1):page348_i34@pure_quanta.q_res(chips)',
 P_PATH='@t6g_mb_lib.t6g(sch_1):page150_i34@pure_quanta.q_res(chips)',
 PATH='I34',
 DRAWING='@T6G_MB_LIB.T6G(SCH_1):PAGE348',
 WATTAGE='1/16W',
 TOLERANCE='1%',
 MATERIAL='CHIP',
 PHYS_PAGE='150',
 XY='(-14950,6575)',
 ROT='0',
 VER='1',
 PACK_TYPE='0402LF',
 LOCATION='R2418',
 CDS_LIB='pure_quanta',
 CDS_PART_NAME='Q_RES_0402LF-33.2,1%,1/16W,CHIP,CS03322FB03',
 PART_NUMBER='CS03322FB03',
 VALUE='33.2',
 PRIM_FILE='./archive_libs/logical/q_res/chips/chips.prt';

PART_NAME
 R2419 'Q_RES_0402LF-33.2,1%,1/16W,CHIP,CS03322FB03':;

SECTION_NUMBER 1
 '@T6G_MB_LIB.T6G(SCH_1):PAGE348_I104@PURE_QUANTA.Q_RES(CHIPS)':
 C_PATH='@t6g_mb_lib.t6g(sch_1):page348_i104@pure_quanta.q_res(chips)',
 P_PATH='@t6g_mb_lib.t6g(sch_1):page150_i104@pure_quanta.q_res(chips)',
 PATH='I104',
 DRAWING='@T6G_MB_LIB.T6G(SCH_1):PAGE348',
 WATTAGE='1/16W',
 TOLERANCE='1%',
 MATERIAL='CHIP',
 PHYS_PAGE='150',
 XY='(-14925,8575)',
 ROT='0',
 VER='1',
 PACK_TYPE='0402LF',
 LOCATION='R2419',
 CDS_LIB='pure_quanta',
 CDS_PART_NAME='Q_RES_0402LF-33.2,1%,1/16W,CHIP,CS03322FB03',
 PART_NUMBER='CS03322FB03',
 VALUE='33.2',
 PRIM_FILE='./archive_libs/logical/q_res/chips/chips.prt';

PART_NAME
 R2420 'Q_RES_0402LF-33.2,1%,1/16W,CHIP,CS03322FB03':;

SECTION_NUMBER 1
 '@T6G_MB_LIB.T6G(SCH_1):PAGE348_I105@PURE_QUANTA.Q_RES(CHIPS)':
 C_PATH='@t6g_mb_lib.t6g(sch_1):page348_i105@pure_quanta.q_res(chips)',
 P_PATH='@t6g_mb_lib.t6g(sch_1):page150_i105@pure_quanta.q_res(chips)',
 PATH='I105',
 DRAWING='@T6G_MB_LIB.T6G(SCH_1):PAGE348',
 WATTAGE='1/16W',
 TOLERANCE='1%',
 MATERIAL='CHIP',
 PHYS_PAGE='150',
 XY='(-14925,8525)',
 ROT='0',
 VER='1',
 PACK_TYPE='0402LF',
 LOCATION='R2420',
 CDS_LIB='pure_quanta',
 CDS_PART_NAME='Q_RES_0402LF-33.2,1%,1/16W,CHIP,CS03322FB03',
 PART_NUMBER='CS03322FB03',
 VALUE='33.2',
 PRIM_FILE='./archive_libs/logical/q_res/chips/chips.prt';

PART_NAME
 R2421 'Q_RES_0402LF-33.2,1%,1/16W,CHIP,CS03322FB03':;

SECTION_NUMBER 1
 '@T6G_MB_LIB.T6G(SCH_1):PAGE348_I98@PURE_QUANTA.Q_RES(CHIPS)':
 C_PATH='@t6g_mb_lib.t6g(sch_1):page348_i98@pure_quanta.q_res(chips)',
 P_PATH='@t6g_mb_lib.t6g(sch_1):page150_i98@pure_quanta.q_res(chips)',
 PATH='I98',
 DRAWING='@T6G_MB_LIB.T6G(SCH_1):PAGE348',
 WATTAGE='1/16W',
 TOLERANCE='1%',
 MATERIAL='CHIP',
 PHYS_PAGE='150',
 XY='(-14925,8475)',
 ROT='0',
 VER='1',
 PACK_TYPE='0402LF',
 LOCATION='R2421',
 CDS_LIB='pure_quanta',
 CDS_PART_NAME='Q_RES_0402LF-33.2,1%,1/16W,CHIP,CS03322FB03',
 PART_NUMBER='CS03322FB03',
 VALUE='33.2',
 PRIM_FILE='./archive_libs/logical/q_res/chips/chips.prt';

PART_NAME
 R2422 'Q_RES_0402LF-33.2,1%,1/16W,CHIP,CS03322FB03':;

SECTION_NUMBER 1
 '@T6G_MB_LIB.T6G(SCH_1):PAGE348_I101@PURE_QUANTA.Q_RES(CHIPS)':
 C_PATH='@t6g_mb_lib.t6g(sch_1):page348_i101@pure_quanta.q_res(chips)',
 P_PATH='@t6g_mb_lib.t6g(sch_1):page150_i101@pure_quanta.q_res(chips)',
 PATH='I101',
 DRAWING='@T6G_MB_LIB.T6G(SCH_1):PAGE348',
 WATTAGE='1/16W',
 TOLERANCE='1%',
 MATERIAL='CHIP',
 PHYS_PAGE='150',
 XY='(-14925,8425)',
 ROT='0',
 VER='1',
 PACK_TYPE='0402LF',
 LOCATION='R2422',
 CDS_LIB='pure_quanta',
 CDS_PART_NAME='Q_RES_0402LF-33.2,1%,1/16W,CHIP,CS03322FB03',
 PART_NUMBER='CS03322FB03',
 VALUE='33.2',
 PRIM_FILE='./archive_libs/logical/q_res/chips/chips.prt';

PART_NAME
 R2423 'Q_RES_0402LF-33.2,1%,1/16W,CHIP,CS03322FB03':;

SECTION_NUMBER 1
 '@T6G_MB_LIB.T6G(SCH_1):PAGE348_I196@PURE_QUANTA.Q_RES(CHIPS)':
 C_PATH='@t6g_mb_lib.t6g(sch_1):page348_i196@pure_quanta.q_res(chips)',
 P_PATH='@t6g_mb_lib.t6g(sch_1):page150_i196@pure_quanta.q_res(chips)',
 PATH='I196',
 DRAWING='@T6G_MB_LIB.T6G(SCH_1):PAGE348',
 WATTAGE='1/16W',
 TOLERANCE='1%',
 MATERIAL='CHIP',
 PHYS_PAGE='150',
 XY='(-14925,7475)',
 ROT='0',
 VER='1',
 PACK_TYPE='0402LF',
 LOCATION='R2423',
 CDS_LIB='pure_quanta',
 CDS_PART_NAME='Q_RES_0402LF-33.2,1%,1/16W,CHIP,CS03322FB03',
 PART_NUMBER='CS03322FB03',
 VALUE='33.2',
 PRIM_FILE='./archive_libs/logical/q_res/chips/chips.prt';

PART_NAME
 R2424 'Q_RES_0402LF-33.2,1%,1/16W,CHIP,CS03322FB03':;

SECTION_NUMBER 1
 '@T6G_MB_LIB.T6G(SCH_1):PAGE348_I195@PURE_QUANTA.Q_RES(CHIPS)':
 C_PATH='@t6g_mb_lib.t6g(sch_1):page348_i195@pure_quanta.q_res(chips)',
 P_PATH='@t6g_mb_lib.t6g(sch_1):page150_i195@pure_quanta.q_res(chips)',
 PATH='I195',
 DRAWING='@T6G_MB_LIB.T6G(SCH_1):PAGE348',
 WATTAGE='1/16W',
 TOLERANCE='1%',
 MATERIAL='CHIP',
 PHYS_PAGE='150',
 XY='(-14925,7425)',
 ROT='0',
 VER='1',
 PACK_TYPE='0402LF',
 LOCATION='R2424',
 CDS_LIB='pure_quanta',
 CDS_PART_NAME='Q_RES_0402LF-33.2,1%,1/16W,CHIP,CS03322FB03',
 PART_NUMBER='CS03322FB03',
 VALUE='33.2',
 PRIM_FILE='./archive_libs/logical/q_res/chips/chips.prt';

PART_NAME
 R2425 'Q_RES_0402LF-33.2,1%,1/16W,CHIP,CS03322FB03':;

SECTION_NUMBER 1
 '@T6G_MB_LIB.T6G(SCH_1):PAGE348_I97@PURE_QUANTA.Q_RES(CHIPS)':
 C_PATH='@t6g_mb_lib.t6g(sch_1):page348_i97@pure_quanta.q_res(chips)',
 P_PATH='@t6g_mb_lib.t6g(sch_1):page150_i97@pure_quanta.q_res(chips)',
 PATH='I97',
 DRAWING='@T6G_MB_LIB.T6G(SCH_1):PAGE348',
 WATTAGE='1/16W',
 TOLERANCE='1%',
 MATERIAL='CHIP',
 PHYS_PAGE='150',
 XY='(-14925,8175)',
 ROT='0',
 VER='1',
 PACK_TYPE='0402LF',
 LOCATION='R2425',
 CDS_LIB='pure_quanta',
 CDS_PART_NAME='Q_RES_0402LF-33.2,1%,1/16W,CHIP,CS03322FB03',
 PART_NUMBER='CS03322FB03',
 VALUE='33.2',
 PRIM_FILE='./archive_libs/logical/q_res/chips/chips.prt';

PART_NAME
 R2426 'Q_RES_0402LF-100,1%,1/16W,EMPTY,CS11002FB07':;

SECTION_NUMBER 1
 '@T6G_MB_LIB.T6G(SCH_1):PAGE297_I75@PURE_QUANTA.Q_RES(CHIPS)':
 C_PATH='@t6g_mb_lib.t6g(sch_1):page297_i75@pure_quanta.q_res(chips)',
 P_PATH='@t6g_mb_lib.t6g(sch_1):page145_i75@pure_quanta.q_res(chips)',
 PATH='I75',
 DRAWING='@T6G_MB_LIB.T6G(SCH_1):PAGE297',
 WATTAGE='1/16W',
 TOLERANCE='1%',
 MATERIAL='EMPTY',
 PHYS_PAGE='145',
 XY='(4000,3700)',
 ROT='0',
 VER='2',
 PACK_TYPE='0402LF',
 LOCATION='R2426',
 CDS_LIB='pure_quanta',
 CDS_PART_NAME='Q_RES_0402LF-100,1%,1/16W,EMPTY,CS11002FB07',
 PART_NUMBER='CS11002FB07',
 VALUE='100',
 PRIM_FILE='./archive_libs/logical/q_res/chips/chips.prt';

PART_NAME
 R2473 'Q_RES_0402LF-0,5%,1/16W,CHIP,CS00002JB13':;

SECTION_NUMBER 1
 '@T6G_MB_LIB.T6G(SCH_1):PAGE336_I164@PURE_QUANTA.Q_RES(CHIPS)':
 C_PATH='@t6g_mb_lib.t6g(sch_1):page336_i164@pure_quanta.q_res(chips)',
 P_PATH='@t6g_mb_lib.t6g(sch_1):page132_i164@pure_quanta.q_res(chips)',
 PATH='I164',
 DRAWING='@T6G_MB_LIB.T6G(SCH_1):PAGE336',
 WATTAGE='1/16W',
 TOLERANCE='5%',
 MATERIAL='CHIP',
 PHYS_PAGE='132',
 XY='(-425,4000)',
 ROT='0',
 VER='1',
 PACK_TYPE='0402LF',
 LOCATION='R2473',
 CDS_LIB='pure_quanta',
 CDS_PART_NAME='Q_RES_0402LF-0,5%,1/16W,CHIP,CS00002JB13',
 PART_NUMBER='CS00002JB13',
 VALUE='0',
 PRIM_FILE='./archive_libs/logical/q_res/chips/chips.prt';

PART_NAME
 R2474 'Q_RES_0402LF-0,5%,1/16W,EMPTY,CS00002JB13':;

SECTION_NUMBER 1
 '@T6G_MB_LIB.T6G(SCH_1):PAGE336_I165@PURE_QUANTA.Q_RES(CHIPS)':
 C_PATH='@t6g_mb_lib.t6g(sch_1):page336_i165@pure_quanta.q_res(chips)',
 P_PATH='@t6g_mb_lib.t6g(sch_1):page132_i165@pure_quanta.q_res(chips)',
 PATH='I165',
 DRAWING='@T6G_MB_LIB.T6G(SCH_1):PAGE336',
 WATTAGE='1/16W',
 TOLERANCE='5%',
 MATERIAL='EMPTY',
 PHYS_PAGE='132',
 XY='(-525,3475)',
 ROT='0',
 VER='1',
 PACK_TYPE='0402LF',
 LOCATION='R2474',
 CDS_LIB='pure_quanta',
 CDS_PART_NAME='Q_RES_0402LF-0,5%,1/16W,EMPTY,CS00002JB13',
 PART_NUMBER='CS00002JB13',
 VALUE='0',
 PRIM_FILE='./archive_libs/logical/q_res/chips/chips.prt';

PART_NAME
 R2476 'Q_RES_0402LF-200K,1%,1/16W,EMPTY,CS42002FB05':;

SECTION_NUMBER 1
 '@T6G_MB_LIB.T6G(SCH_1):PAGE346_I70@PURE_QUANTA.Q_RES(CHIPS)':
 C_PATH='@t6g_mb_lib.t6g(sch_1):page346_i70@pure_quanta.q_res(chips)',
 P_PATH='@t6g_mb_lib.t6g(sch_1):page148_i70@pure_quanta.q_res(chips)',
 PATH='I70',
 DRAWING='@T6G_MB_LIB.T6G(SCH_1):PAGE346',
 WATTAGE='1/16W',
 TOLERANCE='1%',
 MATERIAL='EMPTY',
 PHYS_PAGE='148',
 XY='(2300,3100)',
 ROT='0',
 VER='1',
 PACK_TYPE='0402LF',
 LOCATION='R2476',
 CDS_LIB='pure_quanta',
 CDS_PART_NAME='Q_RES_0402LF-200K,1%,1/16W,EMPTY,CS42002FB05',
 PART_NUMBER='CS42002FB05',
 VALUE='200K',
 PRIM_FILE='./archive_libs/logical/q_res/chips/chips.prt';

PART_NAME
 R2487 'Q_RES_0402LF-4.7K,1%,1/16W,EMPTY,CS24702FB06':;

SECTION_NUMBER 1
 '@T6G_MB_LIB.T6G(SCH_1):PAGE337_I56@PURE_QUANTA.Q_RES(CHIPS)':
 C_PATH='@t6g_mb_lib.t6g(sch_1):page337_i56@pure_quanta.q_res(chips)',
 P_PATH='@t6g_mb_lib.t6g(sch_1):page133_i56@pure_quanta.q_res(chips)',
 PATH='I56',
 DRAWING='@T6G_MB_LIB.T6G(SCH_1):PAGE337',
 WATTAGE='1/16W',
 TOLERANCE='1%',
 MATERIAL='EMPTY',
 PHYS_PAGE='133',
 XY='(-3775,4600)',
 ROT='0',
 VER='2',
 PACK_TYPE='0402LF',
 LOCATION='R2487',
 CDS_LIB='pure_quanta',
 CDS_PART_NAME='Q_RES_0402LF-4.7K,1%,1/16W,EMPTY,CS24702FB06',
 PART_NUMBER='CS24702FB06',
 VALUE='4.7K',
 PRIM_FILE='./archive_libs/logical/q_res/chips/chips.prt';

PART_NAME
 R2488 'Q_RES_0402LF-4.7K,1%,1/16W,CHIP,CS24702FB06':;

SECTION_NUMBER 1
 '@T6G_MB_LIB.T6G(SCH_1):PAGE337_I35@PURE_QUANTA.Q_RES(CHIPS)':
 C_PATH='@t6g_mb_lib.t6g(sch_1):page337_i35@pure_quanta.q_res(chips)',
 P_PATH='@t6g_mb_lib.t6g(sch_1):page133_i35@pure_quanta.q_res(chips)',
 PATH='I35',
 DRAWING='@T6G_MB_LIB.T6G(SCH_1):PAGE337',
 WATTAGE='1/16W',
 TOLERANCE='1%',
 MATERIAL='CHIP',
 PHYS_PAGE='133',
 XY='(-7050,4700)',
 ROT='0',
 VER='2',
 PACK_TYPE='0402LF',
 LOCATION='R2488',
 CDS_LIB='pure_quanta',
 CDS_PART_NAME='Q_RES_0402LF-4.7K,1%,1/16W,CHIP,CS24702FB06',
 PART_NUMBER='CS24702FB06',
 VALUE='4.7K',
 PRIM_FILE='./archive_libs/logical/q_res/chips/chips.prt';

PART_NAME
 R2489 'Q_RES_0402LF-33.2,1%,1/16W,CHIP,CS03322FB03':;

SECTION_NUMBER 1
 '@T6G_MB_LIB.T6G(SCH_1):PAGE337_I50@PURE_QUANTA.Q_RES(CHIPS)':
 C_PATH='@t6g_mb_lib.t6g(sch_1):page337_i50@pure_quanta.q_res(chips)',
 P_PATH='@t6g_mb_lib.t6g(sch_1):page133_i50@pure_quanta.q_res(chips)',
 PATH='I50',
 DRAWING='@T6G_MB_LIB.T6G(SCH_1):PAGE337',
 WATTAGE='1/16W',
 TOLERANCE='1%',
 MATERIAL='CHIP',
 PHYS_PAGE='133',
 XY='(-3475,4150)',
 ROT='0',
 VER='1',
 PACK_TYPE='0402LF',
 LOCATION='R2489',
 CDS_LIB='pure_quanta',
 CDS_PART_NAME='Q_RES_0402LF-33.2,1%,1/16W,CHIP,CS03322FB03',
 PART_NUMBER='CS03322FB03',
 VALUE='33.2',
 PRIM_FILE='./archive_libs/logical/q_res/chips/chips.prt';

PART_NAME
 R2528 'Q_RES_0402LF-100K,1%,1/16W,CHIP,CS41002FB09':;

SECTION_NUMBER 1
 '@T6G_MB_LIB.T6G(SCH_1):PAGE365_I8@PURE_QUANTA.Q_RES(CHIPS)':
 C_PATH='@t6g_mb_lib.t6g(sch_1):page365_i8@pure_quanta.q_res(chips)',
 P_PATH='@t6g_mb_lib.t6g(sch_1):page242_i8@pure_quanta.q_res(chips)',
 PATH='I8',
 DRAWING='@T6G_MB_LIB.T6G(SCH_1):PAGE365',
 WATTAGE='1/16W',
 TOLERANCE='1%',
 MATERIAL='CHIP',
 PHYS_PAGE='242',
 XY='(11650,3850)',
 ROT='0',
 VER='2',
 PACK_TYPE='0402LF',
 LOCATION='R2528',
 CDS_LIB='pure_quanta',
 CDS_PART_NAME='Q_RES_0402LF-100K,1%,1/16W,CHIP,CS41002FB09',
 PART_NUMBER='CS41002FB09',
 VALUE='100K',
 PRIM_FILE='./archive_libs/logical/q_res/chips/chips.prt';

PART_NAME
 R2529 'Q_RES_0402LF-0,5%,1/16W,CHIP,CS00002JB13':;

SECTION_NUMBER 1
 '@T6G_MB_LIB.T6G(SCH_1):PAGE365_I7@PURE_QUANTA.Q_RES(CHIPS)':
 C_PATH='@t6g_mb_lib.t6g(sch_1):page365_i7@pure_quanta.q_res(chips)',
 P_PATH='@t6g_mb_lib.t6g(sch_1):page242_i7@pure_quanta.q_res(chips)',
 PATH='I7',
 DRAWING='@T6G_MB_LIB.T6G(SCH_1):PAGE365',
 WATTAGE='1/16W',
 TOLERANCE='5%',
 MATERIAL='CHIP',
 PHYS_PAGE='242',
 XY='(12575,3450)',
 ROT='0',
 VER='1',
 PACK_TYPE='0402LF',
 LOCATION='R2529',
 CDS_LIB='pure_quanta',
 CDS_PART_NAME='Q_RES_0402LF-0,5%,1/16W,CHIP,CS00002JB13',
 PART_NUMBER='CS00002JB13',
 VALUE='0',
 PRIM_FILE='./archive_libs/logical/q_res/chips/chips.prt';

PART_NAME
 R2530 'Q_RES_0402LF-4.7K,5%,1/16W,CHIP,CS24702JB10':;

SECTION_NUMBER 1
 '@T6G_MB_LIB.T6G(SCH_1):PAGE365_I10@PURE_QUANTA.Q_RES(CHIPS)':
 C_PATH='@t6g_mb_lib.t6g(sch_1):page365_i10@pure_quanta.q_res(chips)',
 P_PATH='@t6g_mb_lib.t6g(sch_1):page242_i10@pure_quanta.q_res(chips)',
 PATH='I10',
 DRAWING='@T6G_MB_LIB.T6G(SCH_1):PAGE365',
 WATTAGE='1/16W',
 TOLERANCE='5%',
 MATERIAL='CHIP',
 PHYS_PAGE='242',
 XY='(14600,4050)',
 ROT='0',
 VER='2',
 PACK_TYPE='0402LF',
 LOCATION='R2530',
 CDS_LIB='pure_quanta',
 CDS_PART_NAME='Q_RES_0402LF-4.7K,5%,1/16W,CHIP,CS24702JB10',
 PART_NUMBER='CS24702JB10',
 VALUE='4.7K',
 PRIM_FILE='./archive_libs/logical/q_res/chips/chips.prt';

PART_NAME
 R2531 'Q_RES_0402LF-0,5%,1/16W,CHIP,CS00002JB13':;

SECTION_NUMBER 1
 '@T6G_MB_LIB.T6G(SCH_1):PAGE365_I3@PURE_QUANTA.Q_RES(CHIPS)':
 C_PATH='@t6g_mb_lib.t6g(sch_1):page365_i3@pure_quanta.q_res(chips)',
 P_PATH='@t6g_mb_lib.t6g(sch_1):page242_i3@pure_quanta.q_res(chips)',
 PATH='I3',
 DRAWING='@T6G_MB_LIB.T6G(SCH_1):PAGE365',
 WATTAGE='1/16W',
 TOLERANCE='5%',
 MATERIAL='CHIP',
 PHYS_PAGE='242',
 XY='(10325,3125)',
 ROT='0',
 VER='1',
 PACK_TYPE='0402LF',
 LOCATION='R2531',
 CDS_LIB='pure_quanta',
 CDS_PART_NAME='Q_RES_0402LF-0,5%,1/16W,CHIP,CS00002JB13',
 PART_NUMBER='CS00002JB13',
 VALUE='0',
 PRIM_FILE='./archive_libs/logical/q_res/chips/chips.prt';

PART_NAME
 R2565 'Q_RES_0402LF-0,5%,1/16W,CHIP,CS00002JB13':;

SECTION_NUMBER 1
 '@T6G_MB_LIB.T6G(SCH_1):PAGE252_I67@PURE_QUANTA.Q_RES(CHIPS)':
 C_PATH='@t6g_mb_lib.t6g(sch_1):page252_i67@pure_quanta.q_res(chips)',
 P_PATH='@t6g_mb_lib.t6g(sch_1):page250_i67@pure_quanta.q_res(chips)',
 PATH='I67',
 DRAWING='@T6G_MB_LIB.T6G(SCH_1):PAGE252',
 WATTAGE='1/16W',
 TOLERANCE='5%',
 MATERIAL='CHIP',
 PHYS_PAGE='250',
 XY='(-2600,4425)',
 ROT='0',
 VER='1',
 PACK_TYPE='0402LF',
 LOCATION='R2565',
 CDS_LIB='pure_quanta',
 CDS_PART_NAME='Q_RES_0402LF-0,5%,1/16W,CHIP,CS00002JB13',
 PART_NUMBER='CS00002JB13',
 VALUE='0',
 PRIM_FILE='./archive_libs/logical/q_res/chips/chips.prt';

PART_NAME
 R2566 'Q_RES_0402LF-0,5%,1/16W,CHIP,CS00002JB13':;

SECTION_NUMBER 1
 '@T6G_MB_LIB.T6G(SCH_1):PAGE252_I72@PURE_QUANTA.Q_RES(CHIPS)':
 C_PATH='@t6g_mb_lib.t6g(sch_1):page252_i72@pure_quanta.q_res(chips)',
 P_PATH='@t6g_mb_lib.t6g(sch_1):page250_i72@pure_quanta.q_res(chips)',
 PATH='I72',
 DRAWING='@T6G_MB_LIB.T6G(SCH_1):PAGE252',
 WATTAGE='1/16W',
 TOLERANCE='5%',
 MATERIAL='CHIP',
 PHYS_PAGE='250',
 XY='(-2600,4475)',
 ROT='0',
 VER='1',
 PACK_TYPE='0402LF',
 LOCATION='R2566',
 CDS_LIB='pure_quanta',
 CDS_PART_NAME='Q_RES_0402LF-0,5%,1/16W,CHIP,CS00002JB13',
 PART_NUMBER='CS00002JB13',
 VALUE='0',
 PRIM_FILE='./archive_libs/logical/q_res/chips/chips.prt';

PART_NAME
 R2585 'Q_RES_0402LF-31.6K,1%,1/16W,CHIP,CS33162FB02':;

SECTION_NUMBER 1
 '@T6G_MB_LIB.T6G(SCH_1):PAGE372_I13@PURE_QUANTA.Q_RES(CHIPS)':
 C_PATH='@t6g_mb_lib.t6g(sch_1):page372_i13@pure_quanta.q_res(chips)',
 P_PATH='@t6g_mb_lib.t6g(sch_1):page268_i13@pure_quanta.q_res(chips)',
 PATH='I13',
 DRAWING='@T6G_MB_LIB.T6G(SCH_1):PAGE372',
 WATTAGE='1/16W',
 TOLERANCE='1%',
 MATERIAL='CHIP',
 PHYS_PAGE='268',
 XY='(-6525,900)',
 ROT='0',
 VER='2',
 PACK_TYPE='0402LF',
 LOCATION='R2585',
 CDS_LIB='pure_quanta',
 CDS_PART_NAME='Q_RES_0402LF-31.6K,1%,1/16W,CHIP,CS33162FB02',
 PART_NUMBER='CS33162FB02',
 VALUE='31.6K',
 PRIM_FILE='./archive_libs/logical/q_res/chips/chips.prt';

PART_NAME
 R2586 'Q_RES_0402LF-0,5%,1/16W,CHIP,CS00002JB13':
 ROOM='HSC BOM1';

SECTION_NUMBER 1
 '@T6G_MB_LIB.T6G(SCH_1):PAGE267_I54@PURE_QUANTA.Q_RES(CHIPS)':
 C_PATH='@t6g_mb_lib.t6g(sch_1):page267_i54@pure_quanta.q_res(chips)',
 P_PATH='@t6g_mb_lib.t6g(sch_1):page262_i54@pure_quanta.q_res(chips)',
 PATH='I54',
 DRAWING='@T6G_MB_LIB.T6G(SCH_1):PAGE267',
 WATTAGE='1/16W',
 TOLERANCE='5%',
 MATERIAL='CHIP',
 PHYS_PAGE='262',
 XY='(-13100,2650)',
 ROT='0',
 VER='1',
 PACK_TYPE='0402LF',
 LOCATION='R2586',
 CDS_LIB='pure_quanta',
 CDS_PART_NAME='Q_RES_0402LF-0,5%,1/16W,CHIP,CS00002JB13',
 ROOM='HSC BOM1',
 PART_NUMBER='CS00002JB13',
 VALUE='0',
 PRIM_FILE='./archive_libs/logical/q_res/chips/chips.prt';

PART_NAME
 R2587 'Q_RES_0402LF-1K,1%,1/16W,CHIP,CS21002FB06':
 ROOM='HSC BOM1';

SECTION_NUMBER 1
 '@T6G_MB_LIB.T6G(SCH_1):PAGE267_I99@PURE_QUANTA.Q_RES(CHIPS)':
 C_PATH='@t6g_mb_lib.t6g(sch_1):page267_i99@pure_quanta.q_res(chips)',
 P_PATH='@t6g_mb_lib.t6g(sch_1):page262_i99@pure_quanta.q_res(chips)',
 PATH='I99',
 DRAWING='@T6G_MB_LIB.T6G(SCH_1):PAGE267',
 WATTAGE='1/16W',
 TOLERANCE='1%',
 MATERIAL='CHIP',
 PHYS_PAGE='262',
 XY='(-8000,3900)',
 ROT='1',
 VER='1',
 PACK_TYPE='0402LF',
 LOCATION='R2587',
 CDS_LIB='pure_quanta',
 CDS_PART_NAME='Q_RES_0402LF-1K,1%,1/16W,CHIP,CS21002FB06',
 ROOM='HSC BOM1',
 PART_NUMBER='CS21002FB06',
 VALUE='1K',
 PRIM_FILE='./archive_libs/logical/q_res/chips/chips.prt';

PART_NAME
 R2588 'Q_RES_0402LF-22,1%,1/16W,CHIP,CS02202FB02':
 ROOM='HSC BOM1';

SECTION_NUMBER 1
 '@T6G_MB_LIB.T6G(SCH_1):PAGE267_I79@PURE_QUANTA.Q_RES(CHIPS)':
 C_PATH='@t6g_mb_lib.t6g(sch_1):page267_i79@pure_quanta.q_res(chips)',
 P_PATH='@t6g_mb_lib.t6g(sch_1):page262_i79@pure_quanta.q_res(chips)',
 PATH='I79',
 DRAWING='@T6G_MB_LIB.T6G(SCH_1):PAGE267',
 WATTAGE='1/16W',
 TOLERANCE='1%',
 MATERIAL='CHIP',
 PHYS_PAGE='262',
 XY='(-8950,3575)',
 ROT='0',
 VER='1',
 PACK_TYPE='0402LF',
 LOCATION='R2588',
 CDS_LIB='pure_quanta',
 CDS_PART_NAME='Q_RES_0402LF-22,1%,1/16W,CHIP,CS02202FB02',
 ROOM='HSC BOM1',
 PART_NUMBER='CS02202FB02',
 VALUE='22',
 PRIM_FILE='./archive_libs/logical/q_res/chips/chips.prt';

PART_NAME
 R2624 'Q_RES_0402LF-49.9,1%,1/16W,CHIP,CS04992FB07':
 ROOM='HSC BOM2';

SECTION_NUMBER 1
 '@T6G_MB_LIB.T6G(SCH_1):PAGE371_I2@PURE_QUANTA.Q_RES(CHIPS)':
 C_PATH='@t6g_mb_lib.t6g(sch_1):page371_i2@pure_quanta.q_res(chips)',
 P_PATH='@t6g_mb_lib.t6g(sch_1):page267_i2@pure_quanta.q_res(chips)',
 PATH='I2',
 DRAWING='@T6G_MB_LIB.T6G(SCH_1):PAGE371',
 WATTAGE='1/16W',
 TOLERANCE='1%',
 MATERIAL='CHIP',
 PHYS_PAGE='267',
 XY='(-5300,1775)',
 ROT='0',
 VER='1',
 PACK_TYPE='0402LF',
 LOCATION='R2624',
 CDS_LIB='pure_quanta',
 CDS_PART_NAME='Q_RES_0402LF-49.9,1%,1/16W,CHIP,CS04992FB07',
 ROOM='HSC BOM2',
 PART_NUMBER='CS04992FB07',
 VALUE='49.9',
 PRIM_FILE='./archive_libs/logical/q_res/chips/chips.prt';

PART_NAME
 R2625 'Q_RES_0402LF-49.9,1%,1/16W,CHIP,CS04992FB07':
 ROOM='HSC BOM2';

SECTION_NUMBER 1
 '@T6G_MB_LIB.T6G(SCH_1):PAGE371_I3@PURE_QUANTA.Q_RES(CHIPS)':
 C_PATH='@t6g_mb_lib.t6g(sch_1):page371_i3@pure_quanta.q_res(chips)',
 P_PATH='@t6g_mb_lib.t6g(sch_1):page267_i3@pure_quanta.q_res(chips)',
 PATH='I3',
 DRAWING='@T6G_MB_LIB.T6G(SCH_1):PAGE371',
 WATTAGE='1/16W',
 TOLERANCE='1%',
 MATERIAL='CHIP',
 PHYS_PAGE='267',
 XY='(-5275,2125)',
 ROT='0',
 VER='1',
 PACK_TYPE='0402LF',
 LOCATION='R2625',
 CDS_LIB='pure_quanta',
 CDS_PART_NAME='Q_RES_0402LF-49.9,1%,1/16W,CHIP,CS04992FB07',
 ROOM='HSC BOM2',
 PART_NUMBER='CS04992FB07',
 VALUE='49.9',
 PRIM_FILE='./archive_libs/logical/q_res/chips/chips.prt';

PART_NAME
 R2626 'Q_RES_0402LF-0,5%,1/16W,CHIP,CS00002JB13':
 ROOM='HSC BOM2';

SECTION_NUMBER 1
 '@T6G_MB_LIB.T6G(SCH_1):PAGE371_I40@PURE_QUANTA.Q_RES(CHIPS)':
 C_PATH='@t6g_mb_lib.t6g(sch_1):page371_i40@pure_quanta.q_res(chips)',
 P_PATH='@t6g_mb_lib.t6g(sch_1):page267_i40@pure_quanta.q_res(chips)',
 PATH='I40',
 DRAWING='@T6G_MB_LIB.T6G(SCH_1):PAGE371',
 WATTAGE='1/16W',
 TOLERANCE='5%',
 MATERIAL='CHIP',
 PHYS_PAGE='267',
 XY='(-2500,2225)',
 ROT='0',
 VER='1',
 PACK_TYPE='0402LF',
 LOCATION='R2626',
 CDS_LIB='pure_quanta',
 CDS_PART_NAME='Q_RES_0402LF-0,5%,1/16W,CHIP,CS00002JB13',
 ROOM='HSC BOM2',
 PART_NUMBER='CS00002JB13',
 VALUE='0',
 PRIM_FILE='./archive_libs/logical/q_res/chips/chips.prt';

PART_NAME
 R2627 'Q_RES_0402LF-0,5%,1/16W,CHIP,CS00002JB13':
 ROOM='HSC BOM2';

SECTION_NUMBER 1
 '@T6G_MB_LIB.T6G(SCH_1):PAGE371_I39@PURE_QUANTA.Q_RES(CHIPS)':
 C_PATH='@t6g_mb_lib.t6g(sch_1):page371_i39@pure_quanta.q_res(chips)',
 P_PATH='@t6g_mb_lib.t6g(sch_1):page267_i39@pure_quanta.q_res(chips)',
 PATH='I39',
 DRAWING='@T6G_MB_LIB.T6G(SCH_1):PAGE371',
 WATTAGE='1/16W',
 TOLERANCE='5%',
 MATERIAL='CHIP',
 PHYS_PAGE='267',
 XY='(-2500,2125)',
 ROT='0',
 VER='1',
 PACK_TYPE='0402LF',
 LOCATION='R2627',
 CDS_LIB='pure_quanta',
 CDS_PART_NAME='Q_RES_0402LF-0,5%,1/16W,CHIP,CS00002JB13',
 ROOM='HSC BOM2',
 PART_NUMBER='CS00002JB13',
 VALUE='0',
 PRIM_FILE='./archive_libs/logical/q_res/chips/chips.prt';

PART_NAME
 R2628 'Q_RES_0402LF-0,5%,1/16W,CHIP,CS00002JB13':
 ROOM='HSC BOM2';

SECTION_NUMBER 1
 '@T6G_MB_LIB.T6G(SCH_1):PAGE371_I10@PURE_QUANTA.Q_RES(CHIPS)':
 C_PATH='@t6g_mb_lib.t6g(sch_1):page371_i10@pure_quanta.q_res(chips)',
 P_PATH='@t6g_mb_lib.t6g(sch_1):page267_i10@pure_quanta.q_res(chips)',
 PATH='I10',
 DRAWING='@T6G_MB_LIB.T6G(SCH_1):PAGE371',
 WATTAGE='1/16W',
 TOLERANCE='5%',
 MATERIAL='CHIP',
 PHYS_PAGE='267',
 XY='(-2500,2025)',
 ROT='0',
 VER='1',
 PACK_TYPE='0402LF',
 LOCATION='R2628',
 CDS_LIB='pure_quanta',
 CDS_PART_NAME='Q_RES_0402LF-0,5%,1/16W,CHIP,CS00002JB13',
 ROOM='HSC BOM2',
 PART_NUMBER='CS00002JB13',
 VALUE='0',
 PRIM_FILE='./archive_libs/logical/q_res/chips/chips.prt';

PART_NAME
 R2656 'Q_RES_0402LF-100,1%,1/16W,EMPTY,CS11002FB07':;

SECTION_NUMBER 1
 '@T6G_MB_LIB.T6G(SCH_1):PAGE330_I69@PURE_QUANTA.Q_RES(CHIPS)':
 C_PATH='@t6g_mb_lib.t6g(sch_1):page330_i69@pure_quanta.q_res(chips)',
 P_PATH='@t6g_mb_lib.t6g(sch_1):page123_i69@pure_quanta.q_res(chips)',
 PATH='I69',
 DRAWING='@T6G_MB_LIB.T6G(SCH_1):PAGE330',
 WATTAGE='1/16W',
 TOLERANCE='1%',
 MATERIAL='EMPTY',
 PHYS_PAGE='123',
 XY='(675,4175)',
 ROT='0',
 VER='1',
 PACK_TYPE='0402LF',
 LOCATION='R2656',
 CDS_LIB='pure_quanta',
 CDS_PART_NAME='Q_RES_0402LF-100,1%,1/16W,EMPTY,CS11002FB07',
 PART_NUMBER='CS11002FB07',
 VALUE='100',
 PRIM_FILE='./archive_libs/logical/q_res/chips/chips.prt';

PART_NAME
 R2659 'Q_RES_0402LF-0,5%,1/16W,CHIP,CS00002JB13':;

SECTION_NUMBER 1
 '@T6G_MB_LIB.T6G(SCH_1):PAGE28_I152@PURE_QUANTA.Q_RES(CHIPS)':
 C_PATH='@t6g_mb_lib.t6g(sch_1):page28_i152@pure_quanta.q_res(chips)',
 P_PATH='@t6g_mb_lib.t6g(sch_1):page28_i152@pure_quanta.q_res(chips)',
 PATH='I152',
 DRAWING='@T6G_MB_LIB.T6G(SCH_1):PAGE28',
 WATTAGE='1/16W',
 TOLERANCE='5%',
 MATERIAL='CHIP',
 PHYS_PAGE='28',
 XY='(-2000,11075)',
 ROT='0',
 VER='1',
 PACK_TYPE='0402LF',
 LOCATION='R2659',
 CDS_LIB='pure_quanta',
 CDS_PART_NAME='Q_RES_0402LF-0,5%,1/16W,CHIP,CS00002JB13',
 PART_NUMBER='CS00002JB13',
 VALUE='0',
 PRIM_FILE='./archive_libs/logical/q_res/chips/chips.prt';

PART_NAME
 R2660 'Q_RES_0402LF-0,5%,1/16W,CHIP,CS00002JB13':;

SECTION_NUMBER 1
 '@T6G_MB_LIB.T6G(SCH_1):PAGE28_I151@PURE_QUANTA.Q_RES(CHIPS)':
 C_PATH='@t6g_mb_lib.t6g(sch_1):page28_i151@pure_quanta.q_res(chips)',
 P_PATH='@t6g_mb_lib.t6g(sch_1):page28_i151@pure_quanta.q_res(chips)',
 PATH='I151',
 DRAWING='@T6G_MB_LIB.T6G(SCH_1):PAGE28',
 WATTAGE='1/16W',
 TOLERANCE='5%',
 MATERIAL='CHIP',
 PHYS_PAGE='28',
 XY='(-2000,11025)',
 ROT='0',
 VER='1',
 PACK_TYPE='0402LF',
 LOCATION='R2660',
 CDS_LIB='pure_quanta',
 CDS_PART_NAME='Q_RES_0402LF-0,5%,1/16W,CHIP,CS00002JB13',
 PART_NUMBER='CS00002JB13',
 VALUE='0',
 PRIM_FILE='./archive_libs/logical/q_res/chips/chips.prt';

PART_NAME
 R2663 'Q_RES_0402LF-33.2,1%,1/16W,CHIP,CS03322FB03':;

SECTION_NUMBER 1
 '@T6G_MB_LIB.T6G(SCH_1):PAGE80_I271@PURE_QUANTA.Q_RES(CHIPS)':
 C_PATH='@t6g_mb_lib.t6g(sch_1):page80_i271@pure_quanta.q_res(chips)',
 P_PATH='@t6g_mb_lib.t6g(sch_1):page81_i271@pure_quanta.q_res(chips)',
 PATH='I271',
 DRAWING='@T6G_MB_LIB.T6G(SCH_1):PAGE80',
 WATTAGE='1/16W',
 TOLERANCE='1%',
 MATERIAL='CHIP',
 PHYS_PAGE='81',
 XY='(-2300,1575)',
 ROT='0',
 VER='1',
 PACK_TYPE='0402LF',
 LOCATION='R2663',
 CDS_LIB='pure_quanta',
 CDS_PART_NAME='Q_RES_0402LF-33.2,1%,1/16W,CHIP,CS03322FB03',
 PART_NUMBER='CS03322FB03',
 VALUE='33.2',
 PRIM_FILE='./archive_libs/logical/q_res/chips/chips.prt';

PART_NAME
 R2664 'Q_RES_0402LF-33.2,1%,1/16W,CHIP,CS03322FB03':;

SECTION_NUMBER 1
 '@T6G_MB_LIB.T6G(SCH_1):PAGE80_I272@PURE_QUANTA.Q_RES(CHIPS)':
 C_PATH='@t6g_mb_lib.t6g(sch_1):page80_i272@pure_quanta.q_res(chips)',
 P_PATH='@t6g_mb_lib.t6g(sch_1):page81_i272@pure_quanta.q_res(chips)',
 PATH='I272',
 DRAWING='@T6G_MB_LIB.T6G(SCH_1):PAGE80',
 WATTAGE='1/16W',
 TOLERANCE='1%',
 MATERIAL='CHIP',
 PHYS_PAGE='81',
 XY='(-2300,1525)',
 ROT='0',
 VER='1',
 PACK_TYPE='0402LF',
 LOCATION='R2664',
 CDS_LIB='pure_quanta',
 CDS_PART_NAME='Q_RES_0402LF-33.2,1%,1/16W,CHIP,CS03322FB03',
 PART_NUMBER='CS03322FB03',
 VALUE='33.2',
 PRIM_FILE='./archive_libs/logical/q_res/chips/chips.prt';

PART_NAME
 R2666 'Q_RES_0402LF-10K,1%,1/16W,CHIP,CS31002FB08':;

SECTION_NUMBER 1
 '@T6G_MB_LIB.T6G(SCH_1):PAGE249_I8@PURE_QUANTA.Q_RES(CHIPS)':
 C_PATH='@t6g_mb_lib.t6g(sch_1):page249_i8@pure_quanta.q_res(chips)',
 P_PATH='@t6g_mb_lib.t6g(sch_1):page248_i8@pure_quanta.q_res(chips)',
 PATH='I8',
 DRAWING='@T6G_MB_LIB.T6G(SCH_1):PAGE249',
 WATTAGE='1/16W',
 TOLERANCE='1%',
 MATERIAL='CHIP',
 PHYS_PAGE='248',
 XY='(-6475,875)',
 ROT='0',
 VER='2',
 PACK_TYPE='0402LF',
 LOCATION='R2666',
 CDS_LIB='pure_quanta',
 CDS_PART_NAME='Q_RES_0402LF-10K,1%,1/16W,CHIP,CS31002FB08',
 PART_NUMBER='CS31002FB08',
 VALUE='10K',
 PRIM_FILE='./archive_libs/logical/q_res/chips/chips.prt';

PART_NAME
 R2667 'Q_RES_0402LF-2.2K,5%,1/16W,CHIP,CS22202JB07':;

SECTION_NUMBER 1
 '@T6G_MB_LIB.T6G(SCH_1):PAGE249_I54@PURE_QUANTA.Q_RES(CHIPS)':
 C_PATH='@t6g_mb_lib.t6g(sch_1):page249_i54@pure_quanta.q_res(chips)',
 P_PATH='@t6g_mb_lib.t6g(sch_1):page248_i54@pure_quanta.q_res(chips)',
 PATH='I54',
 DRAWING='@T6G_MB_LIB.T6G(SCH_1):PAGE249',
 WATTAGE='1/16W',
 TOLERANCE='5%',
 MATERIAL='CHIP',
 PHYS_PAGE='248',
 XY='(-4800,5700)',
 ROT='0',
 VER='2',
 PACK_TYPE='0402LF',
 LOCATION='R2667',
 CDS_LIB='pure_quanta',
 CDS_PART_NAME='Q_RES_0402LF-2.2K,5%,1/16W,CHIP,CS22202JB07',
 PART_NUMBER='CS22202JB07',
 VALUE='2.2K',
 PRIM_FILE='./archive_libs/logical/q_res/chips/chips.prt';

PART_NAME
 R2668 'Q_RES_0402LF-4.7K,5%,1/16W,EMPTY,CS24702JB10':;

SECTION_NUMBER 1
 '@T6G_MB_LIB.T6G(SCH_1):PAGE249_I62@PURE_QUANTA.Q_RES(CHIPS)':
 C_PATH='@t6g_mb_lib.t6g(sch_1):page249_i62@pure_quanta.q_res(chips)',
 P_PATH='@t6g_mb_lib.t6g(sch_1):page248_i62@pure_quanta.q_res(chips)',
 PATH='I62',
 DRAWING='@T6G_MB_LIB.T6G(SCH_1):PAGE249',
 WATTAGE='1/16W',
 TOLERANCE='5%',
 MATERIAL='EMPTY',
 PHYS_PAGE='248',
 XY='(-2350,1600)',
 ROT='0',
 VER='2',
 PACK_TYPE='0402LF',
 LOCATION='R2668',
 CDS_LIB='pure_quanta',
 CDS_PART_NAME='Q_RES_0402LF-4.7K,5%,1/16W,EMPTY,CS24702JB10',
 PART_NUMBER='CS24702JB10',
 VALUE='4.7K',
 PRIM_FILE='./archive_libs/logical/q_res/chips/chips.prt';

PART_NAME
 R2669 'Q_RES_0402LF-2.2K,5%,1/16W,CHIP,CS22202JB07':;

SECTION_NUMBER 1
 '@T6G_MB_LIB.T6G(SCH_1):PAGE249_I57@PURE_QUANTA.Q_RES(CHIPS)':
 C_PATH='@t6g_mb_lib.t6g(sch_1):page249_i57@pure_quanta.q_res(chips)',
 P_PATH='@t6g_mb_lib.t6g(sch_1):page248_i57@pure_quanta.q_res(chips)',
 PATH='I57',
 DRAWING='@T6G_MB_LIB.T6G(SCH_1):PAGE249',
 WATTAGE='1/16W',
 TOLERANCE='5%',
 MATERIAL='CHIP',
 PHYS_PAGE='248',
 XY='(-4550,5700)',
 ROT='0',
 VER='2',
 PACK_TYPE='0402LF',
 LOCATION='R2669',
 CDS_LIB='pure_quanta',
 CDS_PART_NAME='Q_RES_0402LF-2.2K,5%,1/16W,CHIP,CS22202JB07',
 PART_NUMBER='CS22202JB07',
 VALUE='2.2K',
 PRIM_FILE='./archive_libs/logical/q_res/chips/chips.prt';

PART_NAME
 R2670 'Q_RES_0402LF-4.7K,5%,1/16W,EMPTY,CS24702JB10':;

SECTION_NUMBER 1
 '@T6G_MB_LIB.T6G(SCH_1):PAGE249_I63@PURE_QUANTA.Q_RES(CHIPS)':
 C_PATH='@t6g_mb_lib.t6g(sch_1):page249_i63@pure_quanta.q_res(chips)',
 P_PATH='@t6g_mb_lib.t6g(sch_1):page248_i63@pure_quanta.q_res(chips)',
 PATH='I63',
 DRAWING='@T6G_MB_LIB.T6G(SCH_1):PAGE249',
 WATTAGE='1/16W',
 TOLERANCE='5%',
 MATERIAL='EMPTY',
 PHYS_PAGE='248',
 XY='(-2100,1600)',
 ROT='0',
 VER='2',
 PACK_TYPE='0402LF',
 LOCATION='R2670',
 CDS_LIB='pure_quanta',
 CDS_PART_NAME='Q_RES_0402LF-4.7K,5%,1/16W,EMPTY,CS24702JB10',
 PART_NUMBER='CS24702JB10',
 VALUE='4.7K',
 PRIM_FILE='./archive_libs/logical/q_res/chips/chips.prt';

PART_NAME
 R2671 'Q_RES_0402LF-33.2,1%,1/16W,CHIP,CS03322FB03':;

SECTION_NUMBER 1
 '@T6G_MB_LIB.T6G(SCH_1):PAGE249_I58@PURE_QUANTA.Q_RES(CHIPS)':
 C_PATH='@t6g_mb_lib.t6g(sch_1):page249_i58@pure_quanta.q_res(chips)',
 P_PATH='@t6g_mb_lib.t6g(sch_1):page248_i58@pure_quanta.q_res(chips)',
 PATH='I58',
 DRAWING='@T6G_MB_LIB.T6G(SCH_1):PAGE249',
 WATTAGE='1/16W',
 TOLERANCE='1%',
 MATERIAL='CHIP',
 PHYS_PAGE='248',
 XY='(-4250,5375)',
 ROT='0',
 VER='1',
 PACK_TYPE='0402LF',
 LOCATION='R2671',
 CDS_LIB='pure_quanta',
 CDS_PART_NAME='Q_RES_0402LF-33.2,1%,1/16W,CHIP,CS03322FB03',
 PART_NUMBER='CS03322FB03',
 VALUE='33.2',
 PRIM_FILE='./archive_libs/logical/q_res/chips/chips.prt';

PART_NAME
 R2672 'Q_RES_0402LF-33.2,1%,1/16W,CHIP,CS03322FB03':;

SECTION_NUMBER 1
 '@T6G_MB_LIB.T6G(SCH_1):PAGE249_I56@PURE_QUANTA.Q_RES(CHIPS)':
 C_PATH='@t6g_mb_lib.t6g(sch_1):page249_i56@pure_quanta.q_res(chips)',
 P_PATH='@t6g_mb_lib.t6g(sch_1):page248_i56@pure_quanta.q_res(chips)',
 PATH='I56',
 DRAWING='@T6G_MB_LIB.T6G(SCH_1):PAGE249',
 WATTAGE='1/16W',
 TOLERANCE='1%',
 MATERIAL='CHIP',
 PHYS_PAGE='248',
 XY='(-4250,5275)',
 ROT='0',
 VER='1',
 PACK_TYPE='0402LF',
 LOCATION='R2672',
 CDS_LIB='pure_quanta',
 CDS_PART_NAME='Q_RES_0402LF-33.2,1%,1/16W,CHIP,CS03322FB03',
 PART_NUMBER='CS03322FB03',
 VALUE='33.2',
 PRIM_FILE='./archive_libs/logical/q_res/chips/chips.prt';

PART_NAME
 R2674 'Q_RES_0402LF-27,5%,1/16W,CHIP,CS02702JB02':;

SECTION_NUMBER 1
 '@T6G_MB_LIB.T6G(SCH_1):PAGE249_I86@PURE_QUANTA.Q_RES(CHIPS)':
 C_PATH='@t6g_mb_lib.t6g(sch_1):page249_i86@pure_quanta.q_res(chips)',
 P_PATH='@t6g_mb_lib.t6g(sch_1):page248_i86@pure_quanta.q_res(chips)',
 PATH='I86',
 DRAWING='@T6G_MB_LIB.T6G(SCH_1):PAGE249',
 WATTAGE='1/16W',
 TOLERANCE='5%',
 MATERIAL='CHIP',
 PHYS_PAGE='248',
 XY='(-1800,1125)',
 ROT='0',
 VER='1',
 PACK_TYPE='0402LF',
 LOCATION='R2674',
 CDS_LIB='pure_quanta',
 CDS_PART_NAME='Q_RES_0402LF-27,5%,1/16W,CHIP,CS02702JB02',
 PART_NUMBER='CS02702JB02',
 VALUE='27',
 PRIM_FILE='./archive_libs/logical/q_res/chips/chips.prt';

PART_NAME
 R2675 'Q_RES_0402LF-33.2,1%,1/16W,CHIP,CS03322FB03':;

SECTION_NUMBER 1
 '@T6G_MB_LIB.T6G(SCH_1):PAGE249_I69@PURE_QUANTA.Q_RES(CHIPS)':
 C_PATH='@t6g_mb_lib.t6g(sch_1):page249_i69@pure_quanta.q_res(chips)',
 P_PATH='@t6g_mb_lib.t6g(sch_1):page248_i69@pure_quanta.q_res(chips)',
 PATH='I69',
 DRAWING='@T6G_MB_LIB.T6G(SCH_1):PAGE249',
 WATTAGE='1/16W',
 TOLERANCE='1%',
 MATERIAL='CHIP',
 PHYS_PAGE='248',
 XY='(-1800,1225)',
 ROT='0',
 VER='1',
 PACK_TYPE='0402LF',
 LOCATION='R2675',
 CDS_LIB='pure_quanta',
 CDS_PART_NAME='Q_RES_0402LF-33.2,1%,1/16W,CHIP,CS03322FB03',
 PART_NUMBER='CS03322FB03',
 VALUE='33.2',
 PRIM_FILE='./archive_libs/logical/q_res/chips/chips.prt';

PART_NAME
 R2676 'Q_RES_0402LF-0,5%,1/16W,CHIP,CS00002JB13':;

SECTION_NUMBER 1
 '@T6G_MB_LIB.T6G(SCH_1):PAGE249_I26@PURE_QUANTA.Q_RES(CHIPS)':
 C_PATH='@t6g_mb_lib.t6g(sch_1):page249_i26@pure_quanta.q_res(chips)',
 P_PATH='@t6g_mb_lib.t6g(sch_1):page248_i26@pure_quanta.q_res(chips)',
 PATH='I26',
 DRAWING='@T6G_MB_LIB.T6G(SCH_1):PAGE249',
 WATTAGE='1/16W',
 TOLERANCE='5%',
 MATERIAL='CHIP',
 PHYS_PAGE='248',
 XY='(-5700,1325)',
 ROT='0',
 VER='1',
 PACK_TYPE='0402LF',
 LOCATION='R2676',
 CDS_LIB='pure_quanta',
 CDS_PART_NAME='Q_RES_0402LF-0,5%,1/16W,CHIP,CS00002JB13',
 PART_NUMBER='CS00002JB13',
 VALUE='0',
 PRIM_FILE='./archive_libs/logical/q_res/chips/chips.prt';

PART_NAME
 R2693 'Q_RES_0402LF-1K,1%,1/16W,EMPTY,CS21002FB06':;

SECTION_NUMBER 1
 '@T6G_MB_LIB.T6G(SCH_1):PAGE246_I3@PURE_QUANTA.Q_RES(CHIPS)':
 C_PATH='@t6g_mb_lib.t6g(sch_1):page246_i3@pure_quanta.q_res(chips)',
 P_PATH='@t6g_mb_lib.t6g(sch_1):page245_i3@pure_quanta.q_res(chips)',
 PATH='I3',
 DRAWING='@T6G_MB_LIB.T6G(SCH_1):PAGE246',
 WATTAGE='1/16W',
 TOLERANCE='1%',
 MATERIAL='EMPTY',
 PHYS_PAGE='245',
 XY='(-7175,3125)',
 ROT='0',
 VER='2',
 PACK_TYPE='0402LF',
 LOCATION='R2693',
 CDS_LIB='pure_quanta',
 CDS_PART_NAME='Q_RES_0402LF-1K,1%,1/16W,EMPTY,CS21002FB06',
 PART_NUMBER='CS21002FB06',
 VALUE='1K',
 PRIM_FILE='./archive_libs/logical/q_res/chips/chips.prt';

PART_NAME
 R2694 'Q_RES_0402LF-1K,1%,1/16W,CHIP,CS21002FB06':;

SECTION_NUMBER 1
 '@T6G_MB_LIB.T6G(SCH_1):PAGE246_I2@PURE_QUANTA.Q_RES(CHIPS)':
 C_PATH='@t6g_mb_lib.t6g(sch_1):page246_i2@pure_quanta.q_res(chips)',
 P_PATH='@t6g_mb_lib.t6g(sch_1):page245_i2@pure_quanta.q_res(chips)',
 PATH='I2',
 DRAWING='@T6G_MB_LIB.T6G(SCH_1):PAGE246',
 WATTAGE='1/16W',
 TOLERANCE='1%',
 MATERIAL='CHIP',
 PHYS_PAGE='245',
 XY='(-7175,2525)',
 ROT='0',
 VER='2',
 PACK_TYPE='0402LF',
 LOCATION='R2694',
 CDS_LIB='pure_quanta',
 CDS_PART_NAME='Q_RES_0402LF-1K,1%,1/16W,CHIP,CS21002FB06',
 PART_NUMBER='CS21002FB06',
 VALUE='1K',
 PRIM_FILE='./archive_libs/logical/q_res/chips/chips.prt';

PART_NAME
 R2695 'Q_RES_0402LF-1K,1%,1/16W,EMPTY,CS21002FB06':;

SECTION_NUMBER 1
 '@T6G_MB_LIB.T6G(SCH_1):PAGE246_I7@PURE_QUANTA.Q_RES(CHIPS)':
 C_PATH='@t6g_mb_lib.t6g(sch_1):page246_i7@pure_quanta.q_res(chips)',
 P_PATH='@t6g_mb_lib.t6g(sch_1):page245_i7@pure_quanta.q_res(chips)',
 PATH='I7',
 DRAWING='@T6G_MB_LIB.T6G(SCH_1):PAGE246',
 WATTAGE='1/16W',
 TOLERANCE='1%',
 MATERIAL='EMPTY',
 PHYS_PAGE='245',
 XY='(-6925,3125)',
 ROT='0',
 VER='2',
 PACK_TYPE='0402LF',
 LOCATION='R2695',
 CDS_LIB='pure_quanta',
 CDS_PART_NAME='Q_RES_0402LF-1K,1%,1/16W,EMPTY,CS21002FB06',
 PART_NUMBER='CS21002FB06',
 VALUE='1K',
 PRIM_FILE='./archive_libs/logical/q_res/chips/chips.prt';

PART_NAME
 R2696 'Q_RES_0402LF-1K,1%,1/16W,CHIP,CS21002FB06':;

SECTION_NUMBER 1
 '@T6G_MB_LIB.T6G(SCH_1):PAGE246_I6@PURE_QUANTA.Q_RES(CHIPS)':
 C_PATH='@t6g_mb_lib.t6g(sch_1):page246_i6@pure_quanta.q_res(chips)',
 P_PATH='@t6g_mb_lib.t6g(sch_1):page245_i6@pure_quanta.q_res(chips)',
 PATH='I6',
 DRAWING='@T6G_MB_LIB.T6G(SCH_1):PAGE246',
 WATTAGE='1/16W',
 TOLERANCE='1%',
 MATERIAL='CHIP',
 PHYS_PAGE='245',
 XY='(-6925,2525)',
 ROT='0',
 VER='2',
 PACK_TYPE='0402LF',
 LOCATION='R2696',
 CDS_LIB='pure_quanta',
 CDS_PART_NAME='Q_RES_0402LF-1K,1%,1/16W,CHIP,CS21002FB06',
 PART_NUMBER='CS21002FB06',
 VALUE='1K',
 PRIM_FILE='./archive_libs/logical/q_res/chips/chips.prt';

PART_NAME
 R2703 'Q_RES_0402LF-0,5%,1/16W,CHIP,CS00002JB13':;

SECTION_NUMBER 1
 '@T6G_MB_LIB.T6G(SCH_1):PAGE252_I71@PURE_QUANTA.Q_RES(CHIPS)':
 C_PATH='@t6g_mb_lib.t6g(sch_1):page252_i71@pure_quanta.q_res(chips)',
 P_PATH='@t6g_mb_lib.t6g(sch_1):page250_i71@pure_quanta.q_res(chips)',
 PATH='I71',
 DRAWING='@T6G_MB_LIB.T6G(SCH_1):PAGE252',
 WATTAGE='1/16W',
 TOLERANCE='5%',
 MATERIAL='CHIP',
 PHYS_PAGE='250',
 XY='(-2600,4525)',
 ROT='0',
 VER='1',
 PACK_TYPE='0402LF',
 LOCATION='R2703',
 CDS_LIB='pure_quanta',
 CDS_PART_NAME='Q_RES_0402LF-0,5%,1/16W,CHIP,CS00002JB13',
 PART_NUMBER='CS00002JB13',
 VALUE='0',
 PRIM_FILE='./archive_libs/logical/q_res/chips/chips.prt';

PART_NAME
 R2704 'Q_RES_0402LF-0,5%,1/16W,CHIP,CS00002JB13':;

SECTION_NUMBER 1
 '@T6G_MB_LIB.T6G(SCH_1):PAGE252_I70@PURE_QUANTA.Q_RES(CHIPS)':
 C_PATH='@t6g_mb_lib.t6g(sch_1):page252_i70@pure_quanta.q_res(chips)',
 P_PATH='@t6g_mb_lib.t6g(sch_1):page250_i70@pure_quanta.q_res(chips)',
 PATH='I70',
 DRAWING='@T6G_MB_LIB.T6G(SCH_1):PAGE252',
 WATTAGE='1/16W',
 TOLERANCE='5%',
 MATERIAL='CHIP',
 PHYS_PAGE='250',
 XY='(-2600,4575)',
 ROT='0',
 VER='1',
 PACK_TYPE='0402LF',
 LOCATION='R2704',
 CDS_LIB='pure_quanta',
 CDS_PART_NAME='Q_RES_0402LF-0,5%,1/16W,CHIP,CS00002JB13',
 PART_NUMBER='CS00002JB13',
 VALUE='0',
 PRIM_FILE='./archive_libs/logical/q_res/chips/chips.prt';

PART_NAME
 R2705 'Q_RES_0402LF-0,5%,1/16W,EMPTY,CS00002JB13':;

SECTION_NUMBER 1
 '@T6G_MB_LIB.T6G(SCH_1):PAGE249_I47@PURE_QUANTA.Q_RES(CHIPS)':
 C_PATH='@t6g_mb_lib.t6g(sch_1):page249_i47@pure_quanta.q_res(chips)',
 P_PATH='@t6g_mb_lib.t6g(sch_1):page248_i47@pure_quanta.q_res(chips)',
 PATH='I47',
 DRAWING='@T6G_MB_LIB.T6G(SCH_1):PAGE249',
 WATTAGE='1/16W',
 TOLERANCE='5%',
 MATERIAL='EMPTY',
 PHYS_PAGE='248',
 XY='(-6300,4925)',
 ROT='0',
 VER='1',
 PACK_TYPE='0402LF',
 LOCATION='R2705',
 CDS_LIB='pure_quanta',
 CDS_PART_NAME='Q_RES_0402LF-0,5%,1/16W,EMPTY,CS00002JB13',
 PART_NUMBER='CS00002JB13',
 VALUE='0',
 PRIM_FILE='./archive_libs/logical/q_res/chips/chips.prt';

PART_NAME
 R2706 'Q_RES_0402LF-0,5%,1/16W,CHIP,CS00002JB13':;

SECTION_NUMBER 1
 '@T6G_MB_LIB.T6G(SCH_1):PAGE249_I27@PURE_QUANTA.Q_RES(CHIPS)':
 C_PATH='@t6g_mb_lib.t6g(sch_1):page249_i27@pure_quanta.q_res(chips)',
 P_PATH='@t6g_mb_lib.t6g(sch_1):page248_i27@pure_quanta.q_res(chips)',
 PATH='I27',
 DRAWING='@T6G_MB_LIB.T6G(SCH_1):PAGE249',
 WATTAGE='1/16W',
 TOLERANCE='5%',
 MATERIAL='CHIP',
 PHYS_PAGE='248',
 XY='(-3975,475)',
 ROT='0',
 VER='1',
 PACK_TYPE='0402LF',
 LOCATION='R2706',
 CDS_LIB='pure_quanta',
 CDS_PART_NAME='Q_RES_0402LF-0,5%,1/16W,CHIP,CS00002JB13',
 PART_NUMBER='CS00002JB13',
 VALUE='0',
 PRIM_FILE='./archive_libs/logical/q_res/chips/chips.prt';

PART_NAME
 R2707 'Q_RES_0402LF-0,5%,1/16W,CHIP,CS00002JB13':;

SECTION_NUMBER 1
 '@T6G_MB_LIB.T6G(SCH_1):PAGE249_I45@PURE_QUANTA.Q_RES(CHIPS)':
 C_PATH='@t6g_mb_lib.t6g(sch_1):page249_i45@pure_quanta.q_res(chips)',
 P_PATH='@t6g_mb_lib.t6g(sch_1):page248_i45@pure_quanta.q_res(chips)',
 PATH='I45',
 DRAWING='@T6G_MB_LIB.T6G(SCH_1):PAGE249',
 WATTAGE='1/16W',
 TOLERANCE='5%',
 MATERIAL='CHIP',
 PHYS_PAGE='248',
 XY='(-7775,5475)',
 ROT='0',
 VER='1',
 PACK_TYPE='0402LF',
 LOCATION='R2707',
 CDS_LIB='pure_quanta',
 CDS_PART_NAME='Q_RES_0402LF-0,5%,1/16W,CHIP,CS00002JB13',
 PART_NUMBER='CS00002JB13',
 VALUE='0',
 PRIM_FILE='./archive_libs/logical/q_res/chips/chips.prt';

PART_NAME
 R2724 'Q_RES_0402LF-0,5%,1/16W,EMPTY,CS00002JB13':;

SECTION_NUMBER 1
 '@T6G_MB_LIB.T6G(SCH_1):PAGE249_I48@PURE_QUANTA.Q_RES(CHIPS)':
 C_PATH='@t6g_mb_lib.t6g(sch_1):page249_i48@pure_quanta.q_res(chips)',
 P_PATH='@t6g_mb_lib.t6g(sch_1):page248_i48@pure_quanta.q_res(chips)',
 PATH='I48',
 DRAWING='@T6G_MB_LIB.T6G(SCH_1):PAGE249',
 WATTAGE='1/16W',
 TOLERANCE='5%',
 MATERIAL='EMPTY',
 PHYS_PAGE='248',
 XY='(-6300,4850)',
 ROT='0',
 VER='1',
 PACK_TYPE='0402LF',
 LOCATION='R2724',
 CDS_LIB='pure_quanta',
 CDS_PART_NAME='Q_RES_0402LF-0,5%,1/16W,EMPTY,CS00002JB13',
 PART_NUMBER='CS00002JB13',
 VALUE='0',
 PRIM_FILE='./archive_libs/logical/q_res/chips/chips.prt';

PART_NAME
 R2725 'Q_RES_0402LF-0,5%,1/16W,CHIP,CS00002JB13':;

SECTION_NUMBER 1
 '@T6G_MB_LIB.T6G(SCH_1):PAGE249_I28@PURE_QUANTA.Q_RES(CHIPS)':
 C_PATH='@t6g_mb_lib.t6g(sch_1):page249_i28@pure_quanta.q_res(chips)',
 P_PATH='@t6g_mb_lib.t6g(sch_1):page248_i28@pure_quanta.q_res(chips)',
 PATH='I28',
 DRAWING='@T6G_MB_LIB.T6G(SCH_1):PAGE249',
 WATTAGE='1/16W',
 TOLERANCE='5%',
 MATERIAL='CHIP',
 PHYS_PAGE='248',
 XY='(-3975,400)',
 ROT='0',
 VER='1',
 PACK_TYPE='0402LF',
 LOCATION='R2725',
 CDS_LIB='pure_quanta',
 CDS_PART_NAME='Q_RES_0402LF-0,5%,1/16W,CHIP,CS00002JB13',
 PART_NUMBER='CS00002JB13',
 VALUE='0',
 PRIM_FILE='./archive_libs/logical/q_res/chips/chips.prt';

PART_NAME
 R2786 'Q_RES_0402LF-0,5%,1/16W,CHIP,CS00002JB13':
 ROOM='USB2 BOM1';

SECTION_NUMBER 1
 '@T6G_MB_LIB.T6G(SCH_1):PAGE358_I79@PURE_QUANTA.Q_RES(CHIPS)':
 C_PATH='@t6g_mb_lib.t6g(sch_1):page358_i79@pure_quanta.q_res(chips)',
 P_PATH='@t6g_mb_lib.t6g(sch_1):page234_i79@pure_quanta.q_res(chips)',
 PATH='I79',
 DRAWING='@T6G_MB_LIB.T6G(SCH_1):PAGE358',
 WATTAGE='1/16W',
 TOLERANCE='5%',
 MATERIAL='CHIP',
 PHYS_PAGE='234',
 XY='(-2175,225)',
 ROT='0',
 VER='1',
 PACK_TYPE='0402LF',
 LOCATION='R2786',
 CDS_LIB='pure_quanta',
 CDS_PART_NAME='Q_RES_0402LF-0,5%,1/16W,CHIP,CS00002JB13',
 ROOM='USB2 BOM1',
 PART_NUMBER='CS00002JB13',
 VALUE='0',
 PRIM_FILE='./archive_libs/logical/q_res/chips/chips.prt';

PART_NAME
 R2787 'Q_RES_0402LF-0,5%,1/16W,CHIP,CS00002JB13':
 ROOM='USB2 BOM1';

SECTION_NUMBER 1
 '@T6G_MB_LIB.T6G(SCH_1):PAGE358_I78@PURE_QUANTA.Q_RES(CHIPS)':
 C_PATH='@t6g_mb_lib.t6g(sch_1):page358_i78@pure_quanta.q_res(chips)',
 P_PATH='@t6g_mb_lib.t6g(sch_1):page234_i78@pure_quanta.q_res(chips)',
 PATH='I78',
 DRAWING='@T6G_MB_LIB.T6G(SCH_1):PAGE358',
 WATTAGE='1/16W',
 TOLERANCE='5%',
 MATERIAL='CHIP',
 PHYS_PAGE='234',
 XY='(-2175,175)',
 ROT='0',
 VER='1',
 PACK_TYPE='0402LF',
 LOCATION='R2787',
 CDS_LIB='pure_quanta',
 CDS_PART_NAME='Q_RES_0402LF-0,5%,1/16W,CHIP,CS00002JB13',
 ROOM='USB2 BOM1',
 PART_NUMBER='CS00002JB13',
 VALUE='0',
 PRIM_FILE='./archive_libs/logical/q_res/chips/chips.prt';

PART_NAME
 R2788 'Q_RES_0402LF-0,5%,1/16W,EMPTY,CS00002JB13':
 ROOM='USB2 BOM2';

SECTION_NUMBER 1
 '@T6G_MB_LIB.T6G(SCH_1):PAGE358_I99@PURE_QUANTA.Q_RES(CHIPS)':
 C_PATH='@t6g_mb_lib.t6g(sch_1):page358_i99@pure_quanta.q_res(chips)',
 P_PATH='@t6g_mb_lib.t6g(sch_1):page234_i99@pure_quanta.q_res(chips)',
 PATH='I99',
 DRAWING='@T6G_MB_LIB.T6G(SCH_1):PAGE358',
 WATTAGE='1/16W',
 TOLERANCE='5%',
 MATERIAL='EMPTY',
 PHYS_PAGE='234',
 XY='(-2025,375)',
 ROT='0',
 VER='2',
 PACK_TYPE='0402LF',
 LOCATION='R2788',
 CDS_LIB='pure_quanta',
 CDS_PART_NAME='Q_RES_0402LF-0,5%,1/16W,EMPTY,CS00002JB13',
 ROOM='USB2 BOM2',
 PART_NUMBER='CS00002JB13',
 VALUE='0',
 PRIM_FILE='./archive_libs/logical/q_res/chips/chips.prt';

PART_NAME
 R2789 'Q_RES_0402LF-0,5%,1/16W,EMPTY,CS00002JB13':
 ROOM='USB2 BOM2';

SECTION_NUMBER 1
 '@T6G_MB_LIB.T6G(SCH_1):PAGE358_I98@PURE_QUANTA.Q_RES(CHIPS)':
 C_PATH='@t6g_mb_lib.t6g(sch_1):page358_i98@pure_quanta.q_res(chips)',
 P_PATH='@t6g_mb_lib.t6g(sch_1):page234_i98@pure_quanta.q_res(chips)',
 PATH='I98',
 DRAWING='@T6G_MB_LIB.T6G(SCH_1):PAGE358',
 WATTAGE='1/16W',
 TOLERANCE='5%',
 MATERIAL='EMPTY',
 PHYS_PAGE='234',
 XY='(-1950,375)',
 ROT='0',
 VER='2',
 PACK_TYPE='0402LF',
 LOCATION='R2789',
 CDS_LIB='pure_quanta',
 CDS_PART_NAME='Q_RES_0402LF-0,5%,1/16W,EMPTY,CS00002JB13',
 ROOM='USB2 BOM2',
 PART_NUMBER='CS00002JB13',
 VALUE='0',
 PRIM_FILE='./archive_libs/logical/q_res/chips/chips.prt';

PART_NAME
 R2790 'Q_RES_0402LF-0,5%,1/16W,EMPTY,CS00002JB13':
 ROOM='USB2 BOM2';

SECTION_NUMBER 1
 '@T6G_MB_LIB.T6G(SCH_1):PAGE358_I96@PURE_QUANTA.Q_RES(CHIPS)':
 C_PATH='@t6g_mb_lib.t6g(sch_1):page358_i96@pure_quanta.q_res(chips)',
 P_PATH='@t6g_mb_lib.t6g(sch_1):page234_i96@pure_quanta.q_res(chips)',
 PATH='I96',
 DRAWING='@T6G_MB_LIB.T6G(SCH_1):PAGE358',
 WATTAGE='1/16W',
 TOLERANCE='5%',
 MATERIAL='EMPTY',
 PHYS_PAGE='234',
 XY='(2725,3650)',
 ROT='0',
 VER='2',
 PACK_TYPE='0402LF',
 LOCATION='R2790',
 CDS_LIB='pure_quanta',
 CDS_PART_NAME='Q_RES_0402LF-0,5%,1/16W,EMPTY,CS00002JB13',
 ROOM='USB2 BOM2',
 PART_NUMBER='CS00002JB13',
 VALUE='0',
 PRIM_FILE='./archive_libs/logical/q_res/chips/chips.prt';

PART_NAME
 R2791 'Q_RES_0402LF-0,5%,1/16W,EMPTY,CS00002JB13':
 ROOM='USB2 BOM2';

SECTION_NUMBER 1
 '@T6G_MB_LIB.T6G(SCH_1):PAGE358_I97@PURE_QUANTA.Q_RES(CHIPS)':
 C_PATH='@t6g_mb_lib.t6g(sch_1):page358_i97@pure_quanta.q_res(chips)',
 P_PATH='@t6g_mb_lib.t6g(sch_1):page234_i97@pure_quanta.q_res(chips)',
 PATH='I97',
 DRAWING='@T6G_MB_LIB.T6G(SCH_1):PAGE358',
 WATTAGE='1/16W',
 TOLERANCE='5%',
 MATERIAL='EMPTY',
 PHYS_PAGE='234',
 XY='(2825,3650)',
 ROT='0',
 VER='2',
 PACK_TYPE='0402LF',
 LOCATION='R2791',
 CDS_LIB='pure_quanta',
 CDS_PART_NAME='Q_RES_0402LF-0,5%,1/16W,EMPTY,CS00002JB13',
 ROOM='USB2 BOM2',
 PART_NUMBER='CS00002JB13',
 VALUE='0',
 PRIM_FILE='./archive_libs/logical/q_res/chips/chips.prt';

PART_NAME
 R2793 'Q_RES_0402LF-0,5%,1/16W,CHIP,CS00002JB13':;

SECTION_NUMBER 1
 '@T6G_MB_LIB.T6G(SCH_1):PAGE363_I394@PURE_QUANTA.Q_RES(CHIPS)':
 C_PATH='@t6g_mb_lib.t6g(sch_1):page363_i394@pure_quanta.q_res(chips)',
 P_PATH='@t6g_mb_lib.t6g(sch_1):page240_i394@pure_quanta.q_res(chips)',
 PATH='I394',
 DRAWING='@T6G_MB_LIB.T6G(SCH_1):PAGE363',
 WATTAGE='1/16W',
 TOLERANCE='5%',
 MATERIAL='CHIP',
 PHYS_PAGE='240',
 XY='(-6875,-2650)',
 ROT='0',
 VER='1',
 PACK_TYPE='0402LF',
 LOCATION='R2793',
 CDS_LIB='pure_quanta',
 CDS_PART_NAME='Q_RES_0402LF-0,5%,1/16W,CHIP,CS00002JB13',
 PART_NUMBER='CS00002JB13',
 VALUE='0',
 PRIM_FILE='./archive_libs/logical/q_res/chips/chips.prt';

PART_NAME
 R2794 'Q_RES_0402LF-4.7K,5%,1/16W,CHIP,CS24702JB10':;

SECTION_NUMBER 1
 '@T6G_MB_LIB.T6G(SCH_1):PAGE363_I396@PURE_QUANTA.Q_RES(CHIPS)':
 C_PATH='@t6g_mb_lib.t6g(sch_1):page363_i396@pure_quanta.q_res(chips)',
 P_PATH='@t6g_mb_lib.t6g(sch_1):page240_i396@pure_quanta.q_res(chips)',
 PATH='I396',
 DRAWING='@T6G_MB_LIB.T6G(SCH_1):PAGE363',
 WATTAGE='1/16W',
 TOLERANCE='5%',
 MATERIAL='CHIP',
 PHYS_PAGE='240',
 XY='(-5975,-2050)',
 ROT='0',
 VER='2',
 PACK_TYPE='0402LF',
 LOCATION='R2794',
 CDS_LIB='pure_quanta',
 CDS_PART_NAME='Q_RES_0402LF-4.7K,5%,1/16W,CHIP,CS24702JB10',
 PART_NUMBER='CS24702JB10',
 VALUE='4.7K',
 PRIM_FILE='./archive_libs/logical/q_res/chips/chips.prt';

PART_NAME
 R2796 'Q_RES_0402LF-0,5%,1/16W,CHIP,CS00002JB13':;

SECTION_NUMBER 1
 '@T6G_MB_LIB.T6G(SCH_1):PAGE363_I420@PURE_QUANTA.Q_RES(CHIPS)':
 C_PATH='@t6g_mb_lib.t6g(sch_1):page363_i420@pure_quanta.q_res(chips)',
 P_PATH='@t6g_mb_lib.t6g(sch_1):page240_i420@pure_quanta.q_res(chips)',
 PATH='I420',
 DRAWING='@T6G_MB_LIB.T6G(SCH_1):PAGE363',
 WATTAGE='1/16W',
 TOLERANCE='5%',
 MATERIAL='CHIP',
 PHYS_PAGE='240',
 XY='(-4650,-3250)',
 ROT='0',
 VER='1',
 PACK_TYPE='0402LF',
 LOCATION='R2796',
 CDS_LIB='pure_quanta',
 CDS_PART_NAME='Q_RES_0402LF-0,5%,1/16W,CHIP,CS00002JB13',
 PART_NUMBER='CS00002JB13',
 VALUE='0',
 PRIM_FILE='./archive_libs/logical/q_res/chips/chips.prt';

PART_NAME
 R2800 'Q_RES_0402LF-0,5%,1/16W,EMPTY,CS00002JB13':;

SECTION_NUMBER 1
 '@T6G_MB_LIB.T6G(SCH_1):PAGE363_I429@PURE_QUANTA.Q_RES(CHIPS)':
 C_PATH='@t6g_mb_lib.t6g(sch_1):page363_i429@pure_quanta.q_res(chips)',
 P_PATH='@t6g_mb_lib.t6g(sch_1):page240_i429@pure_quanta.q_res(chips)',
 PATH='I429',
 DRAWING='@T6G_MB_LIB.T6G(SCH_1):PAGE363',
 WATTAGE='1/16W',
 TOLERANCE='5%',
 MATERIAL='EMPTY',
 PHYS_PAGE='240',
 XY='(-3125,-3800)',
 ROT='0',
 VER='1',
 PACK_TYPE='0402LF',
 LOCATION='R2800',
 CDS_LIB='pure_quanta',
 CDS_PART_NAME='Q_RES_0402LF-0,5%,1/16W,EMPTY,CS00002JB13',
 PART_NUMBER='CS00002JB13',
 VALUE='0',
 PRIM_FILE='./archive_libs/logical/q_res/chips/chips.prt';

PART_NAME
 R2801 'Q_RES_0402LF-0,5%,1/16W,EMPTY,CS00002JB13':;

SECTION_NUMBER 1
 '@T6G_MB_LIB.T6G(SCH_1):PAGE363_I430@PURE_QUANTA.Q_RES(CHIPS)':
 C_PATH='@t6g_mb_lib.t6g(sch_1):page363_i430@pure_quanta.q_res(chips)',
 P_PATH='@t6g_mb_lib.t6g(sch_1):page240_i430@pure_quanta.q_res(chips)',
 PATH='I430',
 DRAWING='@T6G_MB_LIB.T6G(SCH_1):PAGE363',
 WATTAGE='1/16W',
 TOLERANCE='5%',
 MATERIAL='EMPTY',
 PHYS_PAGE='240',
 XY='(-3125,-3875)',
 ROT='0',
 VER='1',
 PACK_TYPE='0402LF',
 LOCATION='R2801',
 CDS_LIB='pure_quanta',
 CDS_PART_NAME='Q_RES_0402LF-0,5%,1/16W,EMPTY,CS00002JB13',
 PART_NUMBER='CS00002JB13',
 VALUE='0',
 PRIM_FILE='./archive_libs/logical/q_res/chips/chips.prt';

PART_NAME
 R2802 'Q_RES_0402LF-0,5%,1/16W,CHIP,CS00002JB13':;

SECTION_NUMBER 1
 '@T6G_MB_LIB.T6G(SCH_1):PAGE363_I387@PURE_QUANTA.Q_RES(CHIPS)':
 C_PATH='@t6g_mb_lib.t6g(sch_1):page363_i387@pure_quanta.q_res(chips)',
 P_PATH='@t6g_mb_lib.t6g(sch_1):page240_i387@pure_quanta.q_res(chips)',
 PATH='I387',
 DRAWING='@T6G_MB_LIB.T6G(SCH_1):PAGE363',
 WATTAGE='1/16W',
 TOLERANCE='5%',
 MATERIAL='CHIP',
 PHYS_PAGE='240',
 XY='(-2150,725)',
 ROT='0',
 VER='1',
 PACK_TYPE='0402LF',
 LOCATION='R2802',
 CDS_LIB='pure_quanta',
 CDS_PART_NAME='Q_RES_0402LF-0,5%,1/16W,CHIP,CS00002JB13',
 PART_NUMBER='CS00002JB13',
 VALUE='0',
 PRIM_FILE='./archive_libs/logical/q_res/chips/chips.prt';

PART_NAME
 R2803 'Q_RES_0402LF-0,5%,1/16W,CHIP,CS00002JB13':;

SECTION_NUMBER 1
 '@T6G_MB_LIB.T6G(SCH_1):PAGE363_I388@PURE_QUANTA.Q_RES(CHIPS)':
 C_PATH='@t6g_mb_lib.t6g(sch_1):page363_i388@pure_quanta.q_res(chips)',
 P_PATH='@t6g_mb_lib.t6g(sch_1):page240_i388@pure_quanta.q_res(chips)',
 PATH='I388',
 DRAWING='@T6G_MB_LIB.T6G(SCH_1):PAGE363',
 WATTAGE='1/16W',
 TOLERANCE='5%',
 MATERIAL='CHIP',
 PHYS_PAGE='240',
 XY='(-2150,675)',
 ROT='0',
 VER='1',
 PACK_TYPE='0402LF',
 LOCATION='R2803',
 CDS_LIB='pure_quanta',
 CDS_PART_NAME='Q_RES_0402LF-0,5%,1/16W,CHIP,CS00002JB13',
 PART_NUMBER='CS00002JB13',
 VALUE='0',
 PRIM_FILE='./archive_libs/logical/q_res/chips/chips.prt';

PART_NAME
 R2805 'Q_RES_0402LF-4.7K,5%,1/16W,EMPTY,CS24702JB10':;

SECTION_NUMBER 1
 '@T6G_MB_LIB.T6G(SCH_1):PAGE363_I436@PURE_QUANTA.Q_RES(CHIPS)':
 C_PATH='@t6g_mb_lib.t6g(sch_1):page363_i436@pure_quanta.q_res(chips)',
 P_PATH='@t6g_mb_lib.t6g(sch_1):page240_i436@pure_quanta.q_res(chips)',
 PATH='I436',
 DRAWING='@T6G_MB_LIB.T6G(SCH_1):PAGE363',
 WATTAGE='1/16W',
 TOLERANCE='5%',
 MATERIAL='EMPTY',
 PHYS_PAGE='240',
 XY='(-1800,-2900)',
 ROT='0',
 VER='2',
 PACK_TYPE='0402LF',
 LOCATION='R2805',
 CDS_LIB='pure_quanta',
 CDS_PART_NAME='Q_RES_0402LF-4.7K,5%,1/16W,EMPTY,CS24702JB10',
 PART_NUMBER='CS24702JB10',
 VALUE='4.7K',
 PRIM_FILE='./archive_libs/logical/q_res/chips/chips.prt';

PART_NAME
 R2807 'Q_RES_0402LF-4.7K,5%,1/16W,EMPTY,CS24702JB10':;

SECTION_NUMBER 1
 '@T6G_MB_LIB.T6G(SCH_1):PAGE363_I438@PURE_QUANTA.Q_RES(CHIPS)':
 C_PATH='@t6g_mb_lib.t6g(sch_1):page363_i438@pure_quanta.q_res(chips)',
 P_PATH='@t6g_mb_lib.t6g(sch_1):page240_i438@pure_quanta.q_res(chips)',
 PATH='I438',
 DRAWING='@T6G_MB_LIB.T6G(SCH_1):PAGE363',
 WATTAGE='1/16W',
 TOLERANCE='5%',
 MATERIAL='EMPTY',
 PHYS_PAGE='240',
 XY='(-1550,-2925)',
 ROT='0',
 VER='2',
 PACK_TYPE='0402LF',
 LOCATION='R2807',
 CDS_LIB='pure_quanta',
 CDS_PART_NAME='Q_RES_0402LF-4.7K,5%,1/16W,EMPTY,CS24702JB10',
 PART_NUMBER='CS24702JB10',
 VALUE='4.7K',
 PRIM_FILE='./archive_libs/logical/q_res/chips/chips.prt';

PART_NAME
 R2811 'Q_RES_0402LF-33.2,1%,1/16W,CHIP,CS03322FB03':;

SECTION_NUMBER 1
 '@T6G_MB_LIB.T6G(SCH_1):PAGE363_I425@PURE_QUANTA.Q_RES(CHIPS)':
 C_PATH='@t6g_mb_lib.t6g(sch_1):page363_i425@pure_quanta.q_res(chips)',
 P_PATH='@t6g_mb_lib.t6g(sch_1):page240_i425@pure_quanta.q_res(chips)',
 PATH='I425',
 DRAWING='@T6G_MB_LIB.T6G(SCH_1):PAGE363',
 WATTAGE='1/16W',
 TOLERANCE='1%',
 MATERIAL='CHIP',
 PHYS_PAGE='240',
 XY='(-1075,-3350)',
 ROT='0',
 VER='1',
 PACK_TYPE='0402LF',
 LOCATION='R2811',
 CDS_LIB='pure_quanta',
 CDS_PART_NAME='Q_RES_0402LF-33.2,1%,1/16W,CHIP,CS03322FB03',
 PART_NUMBER='CS03322FB03',
 VALUE='33.2',
 PRIM_FILE='./archive_libs/logical/q_res/chips/chips.prt';

PART_NAME
 R2812 'Q_RES_0402LF-33.2,1%,1/16W,CHIP,CS03322FB03':;

SECTION_NUMBER 1
 '@T6G_MB_LIB.T6G(SCH_1):PAGE363_I426@PURE_QUANTA.Q_RES(CHIPS)':
 C_PATH='@t6g_mb_lib.t6g(sch_1):page363_i426@pure_quanta.q_res(chips)',
 P_PATH='@t6g_mb_lib.t6g(sch_1):page240_i426@pure_quanta.q_res(chips)',
 PATH='I426',
 DRAWING='@T6G_MB_LIB.T6G(SCH_1):PAGE363',
 WATTAGE='1/16W',
 TOLERANCE='1%',
 MATERIAL='CHIP',
 PHYS_PAGE='240',
 XY='(-1075,-3450)',
 ROT='0',
 VER='1',
 PACK_TYPE='0402LF',
 LOCATION='R2812',
 CDS_LIB='pure_quanta',
 CDS_PART_NAME='Q_RES_0402LF-33.2,1%,1/16W,CHIP,CS03322FB03',
 PART_NUMBER='CS03322FB03',
 VALUE='33.2',
 PRIM_FILE='./archive_libs/logical/q_res/chips/chips.prt';

PART_NAME
 R2815 'Q_RES_0402LF-100K,1%,1/16W,EMPTY,CS41002FB09':;

SECTION_NUMBER 1
 '@T6G_MB_LIB.T6G(SCH_1):PAGE256_I68@PURE_QUANTA.Q_RES(CHIPS)':
 C_PATH='@t6g_mb_lib.t6g(sch_1):page256_i68@pure_quanta.q_res(chips)',
 P_PATH='@t6g_mb_lib.t6g(sch_1):page130_i68@pure_quanta.q_res(chips)',
 PATH='I68',
 DRAWING='@T6G_MB_LIB.T6G(SCH_1):PAGE256',
 WATTAGE='1/16W',
 TOLERANCE='1%',
 MATERIAL='EMPTY',
 PHYS_PAGE='130',
 XY='(0,3275)',
 ROT='0',
 VER='2',
 PACK_TYPE='0402LF',
 LOCATION='R2815',
 CDS_LIB='pure_quanta',
 CDS_PART_NAME='Q_RES_0402LF-100K,1%,1/16W,EMPTY,CS41002FB09',
 PART_NUMBER='CS41002FB09',
 VALUE='100K',
 PRIM_FILE='./archive_libs/logical/q_res/chips/chips.prt';

PART_NAME
 R2820 'Q_RES_0402LF-4.7K,5%,1/16W,EMPTY,CS24702JB10':;

SECTION_NUMBER 1
 '@T6G_MB_LIB.T6G(SCH_1):PAGE256_I78@PURE_QUANTA.Q_RES(CHIPS)':
 C_PATH='@t6g_mb_lib.t6g(sch_1):page256_i78@pure_quanta.q_res(chips)',
 P_PATH='@t6g_mb_lib.t6g(sch_1):page130_i78@pure_quanta.q_res(chips)',
 PATH='I78',
 DRAWING='@T6G_MB_LIB.T6G(SCH_1):PAGE256',
 WATTAGE='1/16W',
 TOLERANCE='5%',
 MATERIAL='EMPTY',
 PHYS_PAGE='130',
 XY='(2500,3225)',
 ROT='0',
 VER='2',
 PACK_TYPE='0402LF',
 LOCATION='R2820',
 CDS_LIB='pure_quanta',
 CDS_PART_NAME='Q_RES_0402LF-4.7K,5%,1/16W,EMPTY,CS24702JB10',
 PART_NUMBER='CS24702JB10',
 VALUE='4.7K',
 PRIM_FILE='./archive_libs/logical/q_res/chips/chips.prt';

PART_NAME
 R2828 'Q_RES_0402LF-100K,1%,1/16W,CHIP,CS41002FB09':;

SECTION_NUMBER 1
 '@T6G_MB_LIB.T6G(SCH_1):PAGE333_I66@PURE_QUANTA.Q_RES(CHIPS)':
 C_PATH='@t6g_mb_lib.t6g(sch_1):page333_i66@pure_quanta.q_res(chips)',
 P_PATH='@t6g_mb_lib.t6g(sch_1):page127_i66@pure_quanta.q_res(chips)',
 PATH='I66',
 DRAWING='@T6G_MB_LIB.T6G(SCH_1):PAGE333',
 WATTAGE='1/16W',
 TOLERANCE='1%',
 MATERIAL='CHIP',
 PHYS_PAGE='127',
 XY='(-4675,6225)',
 ROT='0',
 VER='2',
 PACK_TYPE='0402LF',
 LOCATION='R2828',
 CDS_LIB='pure_quanta',
 CDS_PART_NAME='Q_RES_0402LF-100K,1%,1/16W,CHIP,CS41002FB09',
 PART_NUMBER='CS41002FB09',
 VALUE='100K',
 PRIM_FILE='./archive_libs/logical/q_res/chips/chips.prt';

PART_NAME
 R2829 'Q_RES_0402LF-100K,1%,1/16W,EMPTY,CS41002FB09':;

SECTION_NUMBER 1
 '@T6G_MB_LIB.T6G(SCH_1):PAGE333_I58@PURE_QUANTA.Q_RES(CHIPS)':
 C_PATH='@t6g_mb_lib.t6g(sch_1):page333_i58@pure_quanta.q_res(chips)',
 P_PATH='@t6g_mb_lib.t6g(sch_1):page127_i58@pure_quanta.q_res(chips)',
 PATH='I58',
 DRAWING='@T6G_MB_LIB.T6G(SCH_1):PAGE333',
 WATTAGE='1/16W',
 TOLERANCE='1%',
 MATERIAL='EMPTY',
 PHYS_PAGE='127',
 XY='(-4650,5750)',
 ROT='0',
 VER='2',
 PACK_TYPE='0402LF',
 LOCATION='R2829',
 CDS_LIB='pure_quanta',
 CDS_PART_NAME='Q_RES_0402LF-100K,1%,1/16W,EMPTY,CS41002FB09',
 PART_NUMBER='CS41002FB09',
 VALUE='100K',
 PRIM_FILE='./archive_libs/logical/q_res/chips/chips.prt';

PART_NAME
 R2830 'Q_RES_0402LF-100K,1%,1/16W,CHIP,CS41002FB09':;

SECTION_NUMBER 1
 '@T6G_MB_LIB.T6G(SCH_1):PAGE333_I68@PURE_QUANTA.Q_RES(CHIPS)':
 C_PATH='@t6g_mb_lib.t6g(sch_1):page333_i68@pure_quanta.q_res(chips)',
 P_PATH='@t6g_mb_lib.t6g(sch_1):page127_i68@pure_quanta.q_res(chips)',
 PATH='I68',
 DRAWING='@T6G_MB_LIB.T6G(SCH_1):PAGE333',
 WATTAGE='1/16W',
 TOLERANCE='1%',
 MATERIAL='CHIP',
 PHYS_PAGE='127',
 XY='(-4700,7625)',
 ROT='0',
 VER='2',
 PACK_TYPE='0402LF',
 LOCATION='R2830',
 CDS_LIB='pure_quanta',
 CDS_PART_NAME='Q_RES_0402LF-100K,1%,1/16W,CHIP,CS41002FB09',
 PART_NUMBER='CS41002FB09',
 VALUE='100K',
 PRIM_FILE='./archive_libs/logical/q_res/chips/chips.prt';

PART_NAME
 R2831 'Q_RES_0402LF-100K,1%,1/16W,EMPTY,CS41002FB09':;

SECTION_NUMBER 1
 '@T6G_MB_LIB.T6G(SCH_1):PAGE333_I56@PURE_QUANTA.Q_RES(CHIPS)':
 C_PATH='@t6g_mb_lib.t6g(sch_1):page333_i56@pure_quanta.q_res(chips)',
 P_PATH='@t6g_mb_lib.t6g(sch_1):page127_i56@pure_quanta.q_res(chips)',
 PATH='I56',
 DRAWING='@T6G_MB_LIB.T6G(SCH_1):PAGE333',
 WATTAGE='1/16W',
 TOLERANCE='1%',
 MATERIAL='EMPTY',
 PHYS_PAGE='127',
 XY='(-4675,7150)',
 ROT='0',
 VER='2',
 PACK_TYPE='0402LF',
 LOCATION='R2831',
 CDS_LIB='pure_quanta',
 CDS_PART_NAME='Q_RES_0402LF-100K,1%,1/16W,EMPTY,CS41002FB09',
 PART_NUMBER='CS41002FB09',
 VALUE='100K',
 PRIM_FILE='./archive_libs/logical/q_res/chips/chips.prt';

PART_NAME
 R2832 'Q_RES_0402LF-100K,1%,1/16W,CHIP,CS41002FB09':;

SECTION_NUMBER 1
 '@T6G_MB_LIB.T6G(SCH_1):PAGE333_I67@PURE_QUANTA.Q_RES(CHIPS)':
 C_PATH='@t6g_mb_lib.t6g(sch_1):page333_i67@pure_quanta.q_res(chips)',
 P_PATH='@t6g_mb_lib.t6g(sch_1):page127_i67@pure_quanta.q_res(chips)',
 PATH='I67',
 DRAWING='@T6G_MB_LIB.T6G(SCH_1):PAGE333',
 WATTAGE='1/16W',
 TOLERANCE='1%',
 MATERIAL='CHIP',
 PHYS_PAGE='127',
 XY='(-4625,4875)',
 ROT='0',
 VER='2',
 PACK_TYPE='0402LF',
 LOCATION='R2832',
 CDS_LIB='pure_quanta',
 CDS_PART_NAME='Q_RES_0402LF-100K,1%,1/16W,CHIP,CS41002FB09',
 PART_NUMBER='CS41002FB09',
 VALUE='100K',
 PRIM_FILE='./archive_libs/logical/q_res/chips/chips.prt';

PART_NAME
 R2833 'Q_RES_0402LF-100K,1%,1/16W,EMPTY,CS41002FB09':;

SECTION_NUMBER 1
 '@T6G_MB_LIB.T6G(SCH_1):PAGE333_I60@PURE_QUANTA.Q_RES(CHIPS)':
 C_PATH='@t6g_mb_lib.t6g(sch_1):page333_i60@pure_quanta.q_res(chips)',
 P_PATH='@t6g_mb_lib.t6g(sch_1):page127_i60@pure_quanta.q_res(chips)',
 PATH='I60',
 DRAWING='@T6G_MB_LIB.T6G(SCH_1):PAGE333',
 WATTAGE='1/16W',
 TOLERANCE='1%',
 MATERIAL='EMPTY',
 PHYS_PAGE='127',
 XY='(-4600,4400)',
 ROT='0',
 VER='2',
 PACK_TYPE='0402LF',
 LOCATION='R2833',
 CDS_LIB='pure_quanta',
 CDS_PART_NAME='Q_RES_0402LF-100K,1%,1/16W,EMPTY,CS41002FB09',
 PART_NUMBER='CS41002FB09',
 VALUE='100K',
 PRIM_FILE='./archive_libs/logical/q_res/chips/chips.prt';

PART_NAME
 R2834 'Q_RES_0402LF-4.7K,5%,1/16W,CHIP,CS24702JB10':;

SECTION_NUMBER 1
 '@T6G_MB_LIB.T6G(SCH_1):PAGE333_I18@PURE_QUANTA.Q_RES(CHIPS)':
 C_PATH='@t6g_mb_lib.t6g(sch_1):page333_i18@pure_quanta.q_res(chips)',
 P_PATH='@t6g_mb_lib.t6g(sch_1):page127_i18@pure_quanta.q_res(chips)',
 PATH='I18',
 DRAWING='@T6G_MB_LIB.T6G(SCH_1):PAGE333',
 WATTAGE='1/16W',
 TOLERANCE='5%',
 MATERIAL='CHIP',
 PHYS_PAGE='127',
 XY='(-3475,6450)',
 ROT='0',
 VER='2',
 PACK_TYPE='0402LF',
 LOCATION='R2834',
 CDS_LIB='pure_quanta',
 CDS_PART_NAME='Q_RES_0402LF-4.7K,5%,1/16W,CHIP,CS24702JB10',
 PART_NUMBER='CS24702JB10',
 VALUE='4.7K',
 PRIM_FILE='./archive_libs/logical/q_res/chips/chips.prt';

PART_NAME
 R2835 'Q_RES_0402LF-4.7K,5%,1/16W,CHIP,CS24702JB10':;

SECTION_NUMBER 1
 '@T6G_MB_LIB.T6G(SCH_1):PAGE333_I14@PURE_QUANTA.Q_RES(CHIPS)':
 C_PATH='@t6g_mb_lib.t6g(sch_1):page333_i14@pure_quanta.q_res(chips)',
 P_PATH='@t6g_mb_lib.t6g(sch_1):page127_i14@pure_quanta.q_res(chips)',
 PATH='I14',
 DRAWING='@T6G_MB_LIB.T6G(SCH_1):PAGE333',
 WATTAGE='1/16W',
 TOLERANCE='5%',
 MATERIAL='CHIP',
 PHYS_PAGE='127',
 XY='(-3525,8000)',
 ROT='0',
 VER='2',
 PACK_TYPE='0402LF',
 LOCATION='R2835',
 CDS_LIB='pure_quanta',
 CDS_PART_NAME='Q_RES_0402LF-4.7K,5%,1/16W,CHIP,CS24702JB10',
 PART_NUMBER='CS24702JB10',
 VALUE='4.7K',
 PRIM_FILE='./archive_libs/logical/q_res/chips/chips.prt';

PART_NAME
 R2836 'Q_RES_0402LF-4.7K,5%,1/16W,CHIP,CS24702JB10':;

SECTION_NUMBER 1
 '@T6G_MB_LIB.T6G(SCH_1):PAGE333_I19@PURE_QUANTA.Q_RES(CHIPS)':
 C_PATH='@t6g_mb_lib.t6g(sch_1):page333_i19@pure_quanta.q_res(chips)',
 P_PATH='@t6g_mb_lib.t6g(sch_1):page127_i19@pure_quanta.q_res(chips)',
 PATH='I19',
 DRAWING='@T6G_MB_LIB.T6G(SCH_1):PAGE333',
 WATTAGE='1/16W',
 TOLERANCE='5%',
 MATERIAL='CHIP',
 PHYS_PAGE='127',
 XY='(-3450,5100)',
 ROT='0',
 VER='2',
 PACK_TYPE='0402LF',
 LOCATION='R2836',
 CDS_LIB='pure_quanta',
 CDS_PART_NAME='Q_RES_0402LF-4.7K,5%,1/16W,CHIP,CS24702JB10',
 PART_NUMBER='CS24702JB10',
 VALUE='4.7K',
 PRIM_FILE='./archive_libs/logical/q_res/chips/chips.prt';

PART_NAME
 R2837 'Q_RES_0402LF-100K,1%,1/16W,EMPTY,CS41002FB09':;

SECTION_NUMBER 1
 '@T6G_MB_LIB.T6G(SCH_1):PAGE333_I80@PURE_QUANTA.Q_RES(CHIPS)':
 C_PATH='@t6g_mb_lib.t6g(sch_1):page333_i80@pure_quanta.q_res(chips)',
 P_PATH='@t6g_mb_lib.t6g(sch_1):page127_i80@pure_quanta.q_res(chips)',
 PATH='I80',
 DRAWING='@T6G_MB_LIB.T6G(SCH_1):PAGE333',
 WATTAGE='1/16W',
 TOLERANCE='1%',
 MATERIAL='EMPTY',
 PHYS_PAGE='127',
 XY='(-150,7700)',
 ROT='0',
 VER='2',
 PACK_TYPE='0402LF',
 LOCATION='R2837',
 CDS_LIB='pure_quanta',
 CDS_PART_NAME='Q_RES_0402LF-100K,1%,1/16W,EMPTY,CS41002FB09',
 PART_NUMBER='CS41002FB09',
 VALUE='100K',
 PRIM_FILE='./archive_libs/logical/q_res/chips/chips.prt';

PART_NAME
 R2838 'Q_RES_0402LF-100K,1%,1/16W,CHIP,CS41002FB09':;

SECTION_NUMBER 1
 '@T6G_MB_LIB.T6G(SCH_1):PAGE333_I62@PURE_QUANTA.Q_RES(CHIPS)':
 C_PATH='@t6g_mb_lib.t6g(sch_1):page333_i62@pure_quanta.q_res(chips)',
 P_PATH='@t6g_mb_lib.t6g(sch_1):page127_i62@pure_quanta.q_res(chips)',
 PATH='I62',
 DRAWING='@T6G_MB_LIB.T6G(SCH_1):PAGE333',
 WATTAGE='1/16W',
 TOLERANCE='1%',
 MATERIAL='CHIP',
 PHYS_PAGE='127',
 XY='(-125,7275)',
 ROT='0',
 VER='2',
 PACK_TYPE='0402LF',
 LOCATION='R2838',
 CDS_LIB='pure_quanta',
 CDS_PART_NAME='Q_RES_0402LF-100K,1%,1/16W,CHIP,CS41002FB09',
 PART_NUMBER='CS41002FB09',
 VALUE='100K',
 PRIM_FILE='./archive_libs/logical/q_res/chips/chips.prt';

PART_NAME
 R2841 'Q_RES_0402LF-4.7K,5%,1/16W,CHIP,CS24702JB10':;

SECTION_NUMBER 1
 '@T6G_MB_LIB.T6G(SCH_1):PAGE333_I24@PURE_QUANTA.Q_RES(CHIPS)':
 C_PATH='@t6g_mb_lib.t6g(sch_1):page333_i24@pure_quanta.q_res(chips)',
 P_PATH='@t6g_mb_lib.t6g(sch_1):page127_i24@pure_quanta.q_res(chips)',
 PATH='I24',
 DRAWING='@T6G_MB_LIB.T6G(SCH_1):PAGE333',
 WATTAGE='1/16W',
 TOLERANCE='5%',
 MATERIAL='CHIP',
 PHYS_PAGE='127',
 XY='(1100,7925)',
 ROT='0',
 VER='2',
 PACK_TYPE='0402LF',
 LOCATION='R2841',
 CDS_LIB='pure_quanta',
 CDS_PART_NAME='Q_RES_0402LF-4.7K,5%,1/16W,CHIP,CS24702JB10',
 PART_NUMBER='CS24702JB10',
 VALUE='4.7K',
 PRIM_FILE='./archive_libs/logical/q_res/chips/chips.prt';

PART_NAME
 R2842 'Q_RES_0402LF-4.7K,5%,1/16W,CHIP,CS24702JB10':;

SECTION_NUMBER 1
 '@T6G_MB_LIB.T6G(SCH_1):PAGE333_I30@PURE_QUANTA.Q_RES(CHIPS)':
 C_PATH='@t6g_mb_lib.t6g(sch_1):page333_i30@pure_quanta.q_res(chips)',
 P_PATH='@t6g_mb_lib.t6g(sch_1):page127_i30@pure_quanta.q_res(chips)',
 PATH='I30',
 DRAWING='@T6G_MB_LIB.T6G(SCH_1):PAGE333',
 WATTAGE='1/16W',
 TOLERANCE='5%',
 MATERIAL='CHIP',
 PHYS_PAGE='127',
 XY='(1100,6625)',
 ROT='0',
 VER='2',
 PACK_TYPE='0402LF',
 LOCATION='R2842',
 CDS_LIB='pure_quanta',
 CDS_PART_NAME='Q_RES_0402LF-4.7K,5%,1/16W,CHIP,CS24702JB10',
 PART_NUMBER='CS24702JB10',
 VALUE='4.7K',
 PRIM_FILE='./archive_libs/logical/q_res/chips/chips.prt';

PART_NAME
 R2843 'Q_RES_0402LF-4.7K,1%,1/16W,CHIP,CS24702FB06':;

SECTION_NUMBER 1
 '@T6G_MB_LIB.T6G(SCH_1):PAGE369_I20@PURE_QUANTA.Q_RES(CHIPS)':
 C_PATH='@t6g_mb_lib.t6g(sch_1):page369_i20@pure_quanta.q_res(chips)',
 P_PATH='@t6g_mb_lib.t6g(sch_1):page257_i20@pure_quanta.q_res(chips)',
 PATH='I20',
 DRAWING='@T6G_MB_LIB.T6G(SCH_1):PAGE369',
 WATTAGE='1/16W',
 TOLERANCE='1%',
 MATERIAL='CHIP',
 PHYS_PAGE='257',
 XY='(-8900,4425)',
 ROT='0',
 VER='2',
 PACK_TYPE='0402LF',
 LOCATION='R2843',
 CDS_LIB='pure_quanta',
 CDS_PART_NAME='Q_RES_0402LF-4.7K,1%,1/16W,CHIP,CS24702FB06',
 PART_NUMBER='CS24702FB06',
 VALUE='4.7K',
 PRIM_FILE='./archive_libs/logical/q_res/chips/chips.prt';

PART_NAME
 R2844 'Q_RES_0402LF-33.2,1%,1/16W,CHIP,CS03322FB03':;

SECTION_NUMBER 1
 '@T6G_MB_LIB.T6G(SCH_1):PAGE80_I263@PURE_QUANTA.Q_RES(CHIPS)':
 C_PATH='@t6g_mb_lib.t6g(sch_1):page80_i263@pure_quanta.q_res(chips)',
 P_PATH='@t6g_mb_lib.t6g(sch_1):page81_i263@pure_quanta.q_res(chips)',
 PATH='I263',
 DRAWING='@T6G_MB_LIB.T6G(SCH_1):PAGE80',
 WATTAGE='1/16W',
 TOLERANCE='1%',
 MATERIAL='CHIP',
 PHYS_PAGE='81',
 XY='(-2300,1775)',
 ROT='0',
 VER='1',
 PACK_TYPE='0402LF',
 LOCATION='R2844',
 CDS_LIB='pure_quanta',
 CDS_PART_NAME='Q_RES_0402LF-33.2,1%,1/16W,CHIP,CS03322FB03',
 PART_NUMBER='CS03322FB03',
 VALUE='33.2',
 PRIM_FILE='./archive_libs/logical/q_res/chips/chips.prt';

PART_NAME
 R2845 'Q_RES_0402LF-33.2,1%,1/16W,CHIP,CS03322FB03':;

SECTION_NUMBER 1
 '@T6G_MB_LIB.T6G(SCH_1):PAGE80_I293@PURE_QUANTA.Q_RES(CHIPS)':
 C_PATH='@t6g_mb_lib.t6g(sch_1):page80_i293@pure_quanta.q_res(chips)',
 P_PATH='@t6g_mb_lib.t6g(sch_1):page81_i293@pure_quanta.q_res(chips)',
 PATH='I293',
 DRAWING='@T6G_MB_LIB.T6G(SCH_1):PAGE80',
 WATTAGE='1/16W',
 TOLERANCE='1%',
 MATERIAL='CHIP',
 PHYS_PAGE='81',
 XY='(-6725,2525)',
 ROT='0',
 VER='1',
 PACK_TYPE='0402LF',
 LOCATION='R2845',
 CDS_LIB='pure_quanta',
 CDS_PART_NAME='Q_RES_0402LF-33.2,1%,1/16W,CHIP,CS03322FB03',
 PART_NUMBER='CS03322FB03',
 VALUE='33.2',
 PRIM_FILE='./archive_libs/logical/q_res/chips/chips.prt';

PART_NAME
 R2846 'Q_RES_0402LF-33.2,1%,1/16W,CHIP,CS03322FB03':;

SECTION_NUMBER 1
 '@T6G_MB_LIB.T6G(SCH_1):PAGE80_I262@PURE_QUANTA.Q_RES(CHIPS)':
 C_PATH='@t6g_mb_lib.t6g(sch_1):page80_i262@pure_quanta.q_res(chips)',
 P_PATH='@t6g_mb_lib.t6g(sch_1):page81_i262@pure_quanta.q_res(chips)',
 PATH='I262',
 DRAWING='@T6G_MB_LIB.T6G(SCH_1):PAGE80',
 WATTAGE='1/16W',
 TOLERANCE='1%',
 MATERIAL='CHIP',
 PHYS_PAGE='81',
 XY='(-2300,1875)',
 ROT='0',
 VER='1',
 PACK_TYPE='0402LF',
 LOCATION='R2846',
 CDS_LIB='pure_quanta',
 CDS_PART_NAME='Q_RES_0402LF-33.2,1%,1/16W,CHIP,CS03322FB03',
 PART_NUMBER='CS03322FB03',
 VALUE='33.2',
 PRIM_FILE='./archive_libs/logical/q_res/chips/chips.prt';

PART_NAME
 R2847 'Q_RES_0402LF-33.2,1%,1/16W,CHIP,CS03322FB03':;

SECTION_NUMBER 1
 '@T6G_MB_LIB.T6G(SCH_1):PAGE80_I266@PURE_QUANTA.Q_RES(CHIPS)':
 C_PATH='@t6g_mb_lib.t6g(sch_1):page80_i266@pure_quanta.q_res(chips)',
 P_PATH='@t6g_mb_lib.t6g(sch_1):page81_i266@pure_quanta.q_res(chips)',
 PATH='I266',
 DRAWING='@T6G_MB_LIB.T6G(SCH_1):PAGE80',
 WATTAGE='1/16W',
 TOLERANCE='1%',
 MATERIAL='CHIP',
 PHYS_PAGE='81',
 XY='(-2300,1825)',
 ROT='0',
 VER='1',
 PACK_TYPE='0402LF',
 LOCATION='R2847',
 CDS_LIB='pure_quanta',
 CDS_PART_NAME='Q_RES_0402LF-33.2,1%,1/16W,CHIP,CS03322FB03',
 PART_NUMBER='CS03322FB03',
 VALUE='33.2',
 PRIM_FILE='./archive_libs/logical/q_res/chips/chips.prt';

PART_NAME
 R2848 'Q_RES_0402LF-0,5%,1/16W,CHIP,CS00002JB13':;

SECTION_NUMBER 1
 '@T6G_MB_LIB.T6G(SCH_1):PAGE246_I59@PURE_QUANTA.Q_RES(CHIPS)':
 C_PATH='@t6g_mb_lib.t6g(sch_1):page246_i59@pure_quanta.q_res(chips)',
 P_PATH='@t6g_mb_lib.t6g(sch_1):page245_i59@pure_quanta.q_res(chips)',
 PATH='I59',
 DRAWING='@T6G_MB_LIB.T6G(SCH_1):PAGE246',
 WATTAGE='1/16W',
 TOLERANCE='5%',
 MATERIAL='CHIP',
 PHYS_PAGE='245',
 XY='(-3525,3475)',
 ROT='0',
 VER='1',
 PACK_TYPE='0402LF',
 LOCATION='R2848',
 CDS_LIB='pure_quanta',
 CDS_PART_NAME='Q_RES_0402LF-0,5%,1/16W,CHIP,CS00002JB13',
 PART_NUMBER='CS00002JB13',
 VALUE='0',
 PRIM_FILE='./archive_libs/logical/q_res/chips/chips.prt';

PART_NAME
 R2893 'Q_RES_0402LF-0,5%,1/16W,EMPTY,CS00002JB13':;

SECTION_NUMBER 1
 '@T6G_MB_LIB.T6G(SCH_1):PAGE249_I68@PURE_QUANTA.Q_RES(CHIPS)':
 C_PATH='@t6g_mb_lib.t6g(sch_1):page249_i68@pure_quanta.q_res(chips)',
 P_PATH='@t6g_mb_lib.t6g(sch_1):page248_i68@pure_quanta.q_res(chips)',
 PATH='I68',
 DRAWING='@T6G_MB_LIB.T6G(SCH_1):PAGE249',
 WATTAGE='1/16W',
 TOLERANCE='5%',
 MATERIAL='EMPTY',
 PHYS_PAGE='248',
 XY='(-3925,3550)',
 ROT='0',
 VER='1',
 PACK_TYPE='0402LF',
 LOCATION='R2893',
 CDS_LIB='pure_quanta',
 CDS_PART_NAME='Q_RES_0402LF-0,5%,1/16W,EMPTY,CS00002JB13',
 PART_NUMBER='CS00002JB13',
 VALUE='0',
 PRIM_FILE='./archive_libs/logical/q_res/chips/chips.prt';

PART_NAME
 R2894 'Q_RES_0402LF-0,5%,1/16W,EMPTY,CS00002JB13':;

SECTION_NUMBER 1
 '@T6G_MB_LIB.T6G(SCH_1):PAGE249_I67@PURE_QUANTA.Q_RES(CHIPS)':
 C_PATH='@t6g_mb_lib.t6g(sch_1):page249_i67@pure_quanta.q_res(chips)',
 P_PATH='@t6g_mb_lib.t6g(sch_1):page248_i67@pure_quanta.q_res(chips)',
 PATH='I67',
 DRAWING='@T6G_MB_LIB.T6G(SCH_1):PAGE249',
 WATTAGE='1/16W',
 TOLERANCE='5%',
 MATERIAL='EMPTY',
 PHYS_PAGE='248',
 XY='(-3925,3475)',
 ROT='0',
 VER='1',
 PACK_TYPE='0402LF',
 LOCATION='R2894',
 CDS_LIB='pure_quanta',
 CDS_PART_NAME='Q_RES_0402LF-0,5%,1/16W,EMPTY,CS00002JB13',
 PART_NUMBER='CS00002JB13',
 VALUE='0',
 PRIM_FILE='./archive_libs/logical/q_res/chips/chips.prt';

PART_NAME
 R2897 'Q_RES_0402LF-33.2,1%,1/16W,CHIP,CS03322FB03':;

SECTION_NUMBER 1
 '@T6G_MB_LIB.T6G(SCH_1):PAGE249_I74@PURE_QUANTA.Q_RES(CHIPS)':
 C_PATH='@t6g_mb_lib.t6g(sch_1):page249_i74@pure_quanta.q_res(chips)',
 P_PATH='@t6g_mb_lib.t6g(sch_1):page248_i74@pure_quanta.q_res(chips)',
 PATH='I74',
 DRAWING='@T6G_MB_LIB.T6G(SCH_1):PAGE249',
 WATTAGE='1/16W',
 TOLERANCE='1%',
 MATERIAL='CHIP',
 PHYS_PAGE='248',
 XY='(-1875,4000)',
 ROT='0',
 VER='1',
 PACK_TYPE='0402LF',
 LOCATION='R2897',
 CDS_LIB='pure_quanta',
 CDS_PART_NAME='Q_RES_0402LF-33.2,1%,1/16W,CHIP,CS03322FB03',
 PART_NUMBER='CS03322FB03',
 VALUE='33.2',
 PRIM_FILE='./archive_libs/logical/q_res/chips/chips.prt';

PART_NAME
 R2898 'Q_RES_0402LF-33.2,1%,1/16W,CHIP,CS03322FB03':;

SECTION_NUMBER 1
 '@T6G_MB_LIB.T6G(SCH_1):PAGE249_I73@PURE_QUANTA.Q_RES(CHIPS)':
 C_PATH='@t6g_mb_lib.t6g(sch_1):page249_i73@pure_quanta.q_res(chips)',
 P_PATH='@t6g_mb_lib.t6g(sch_1):page248_i73@pure_quanta.q_res(chips)',
 PATH='I73',
 DRAWING='@T6G_MB_LIB.T6G(SCH_1):PAGE249',
 WATTAGE='1/16W',
 TOLERANCE='1%',
 MATERIAL='CHIP',
 PHYS_PAGE='248',
 XY='(-1875,3900)',
 ROT='0',
 VER='1',
 PACK_TYPE='0402LF',
 LOCATION='R2898',
 CDS_LIB='pure_quanta',
 CDS_PART_NAME='Q_RES_0402LF-33.2,1%,1/16W,CHIP,CS03322FB03',
 PART_NUMBER='CS03322FB03',
 VALUE='33.2',
 PRIM_FILE='./archive_libs/logical/q_res/chips/chips.prt';

PART_NAME
 R2899 'Q_RES_0402LF-0,5%,1/16W,CHIP,CS00002JB13':;

SECTION_NUMBER 1
 '@T6G_MB_LIB.T6G(SCH_1):PAGE249_I50@PURE_QUANTA.Q_RES(CHIPS)':
 C_PATH='@t6g_mb_lib.t6g(sch_1):page249_i50@pure_quanta.q_res(chips)',
 P_PATH='@t6g_mb_lib.t6g(sch_1):page248_i50@pure_quanta.q_res(chips)',
 PATH='I50',
 DRAWING='@T6G_MB_LIB.T6G(SCH_1):PAGE249',
 WATTAGE='1/16W',
 TOLERANCE='5%',
 MATERIAL='CHIP',
 PHYS_PAGE='248',
 XY='(-5750,4100)',
 ROT='0',
 VER='1',
 PACK_TYPE='0402LF',
 LOCATION='R2899',
 CDS_LIB='pure_quanta',
 CDS_PART_NAME='Q_RES_0402LF-0,5%,1/16W,CHIP,CS00002JB13',
 PART_NUMBER='CS00002JB13',
 VALUE='0',
 PRIM_FILE='./archive_libs/logical/q_res/chips/chips.prt';

PART_NAME
 R2900 'Q_RES_0402LF-2K,1%,1/16W,CHIP,CS22002FB07':;

SECTION_NUMBER 1
 '@T6G_MB_LIB.T6G(SCH_1):PAGE369_I160@PURE_QUANTA.Q_RES(CHIPS)':
 C_PATH='@t6g_mb_lib.t6g(sch_1):page369_i160@pure_quanta.q_res(chips)',
 P_PATH='@t6g_mb_lib.t6g(sch_1):page257_i160@pure_quanta.q_res(chips)',
 PATH='I160',
 DRAWING='@T6G_MB_LIB.T6G(SCH_1):PAGE369',
 WATTAGE='1/16W',
 TOLERANCE='1%',
 MATERIAL='CHIP',
 PHYS_PAGE='257',
 XY='(-3475,5525)',
 ROT='0',
 VER='1',
 PACK_TYPE='0402LF',
 LOCATION='R2900',
 CDS_LIB='pure_quanta',
 CDS_PART_NAME='Q_RES_0402LF-2K,1%,1/16W,CHIP,CS22002FB07',
 PART_NUMBER='CS22002FB07',
 VALUE='2K',
 PRIM_FILE='./archive_libs/logical/q_res/chips/chips.prt';

PART_NAME
 R2905 'Q_RES_0402LF-0,5%,1/16W,CHIP,CS00002JB13':;

SECTION_NUMBER 1
 '@T6G_MB_LIB.T6G(SCH_1):PAGE363_I441@PURE_QUANTA.Q_RES(CHIPS)':
 C_PATH='@t6g_mb_lib.t6g(sch_1):page363_i441@pure_quanta.q_res(chips)',
 P_PATH='@t6g_mb_lib.t6g(sch_1):page240_i441@pure_quanta.q_res(chips)',
 PATH='I441',
 DRAWING='@T6G_MB_LIB.T6G(SCH_1):PAGE363',
 WATTAGE='1/16W',
 TOLERANCE='5%',
 MATERIAL='CHIP',
 PHYS_PAGE='240',
 XY='(-5750,675)',
 ROT='0',
 VER='1',
 PACK_TYPE='0402LF',
 LOCATION='R2905',
 CDS_LIB='pure_quanta',
 CDS_PART_NAME='Q_RES_0402LF-0,5%,1/16W,CHIP,CS00002JB13',
 PART_NUMBER='CS00002JB13',
 VALUE='0',
 PRIM_FILE='./archive_libs/logical/q_res/chips/chips.prt';

PART_NAME
 R2906 'Q_RES_0402LF-0,5%,1/16W,CHIP,CS00002JB13':;

SECTION_NUMBER 1
 '@T6G_MB_LIB.T6G(SCH_1):PAGE363_I440@PURE_QUANTA.Q_RES(CHIPS)':
 C_PATH='@t6g_mb_lib.t6g(sch_1):page363_i440@pure_quanta.q_res(chips)',
 P_PATH='@t6g_mb_lib.t6g(sch_1):page240_i440@pure_quanta.q_res(chips)',
 PATH='I440',
 DRAWING='@T6G_MB_LIB.T6G(SCH_1):PAGE363',
 WATTAGE='1/16W',
 TOLERANCE='5%',
 MATERIAL='CHIP',
 PHYS_PAGE='240',
 XY='(-2150,625)',
 ROT='0',
 VER='1',
 PACK_TYPE='0402LF',
 LOCATION='R2906',
 CDS_LIB='pure_quanta',
 CDS_PART_NAME='Q_RES_0402LF-0,5%,1/16W,CHIP,CS00002JB13',
 PART_NUMBER='CS00002JB13',
 VALUE='0',
 PRIM_FILE='./archive_libs/logical/q_res/chips/chips.prt';

PART_NAME
 R2907 'Q_RES_0402LF-5.11K,1%,1/16W,CHIP,CS25112FB04':;

SECTION_NUMBER 1
 '@T6G_MB_LIB.T6G(SCH_1):PAGE369_I28@PURE_QUANTA.Q_RES(CHIPS)':
 C_PATH='@t6g_mb_lib.t6g(sch_1):page369_i28@pure_quanta.q_res(chips)',
 P_PATH='@t6g_mb_lib.t6g(sch_1):page257_i28@pure_quanta.q_res(chips)',
 PATH='I28',
 DRAWING='@T6G_MB_LIB.T6G(SCH_1):PAGE369',
 WATTAGE='1/16W',
 TOLERANCE='1%',
 MATERIAL='CHIP',
 PHYS_PAGE='257',
 XY='(-8900,6225)',
 ROT='0',
 VER='2',
 PACK_TYPE='0402LF',
 LOCATION='R2907',
 CDS_LIB='pure_quanta',
 CDS_PART_NAME='Q_RES_0402LF-5.11K,1%,1/16W,CHIP,CS25112FB04',
 PART_NUMBER='CS25112FB04',
 VALUE='5.11K',
 PRIM_FILE='./archive_libs/logical/q_res/chips/chips.prt';

PART_NAME
 R2908 'Q_RES_0402LF-5.11K,1%,1/16W,CHIP,CS25112FB04':;

SECTION_NUMBER 1
 '@T6G_MB_LIB.T6G(SCH_1):PAGE369_I21@PURE_QUANTA.Q_RES(CHIPS)':
 C_PATH='@t6g_mb_lib.t6g(sch_1):page369_i21@pure_quanta.q_res(chips)',
 P_PATH='@t6g_mb_lib.t6g(sch_1):page257_i21@pure_quanta.q_res(chips)',
 PATH='I21',
 DRAWING='@T6G_MB_LIB.T6G(SCH_1):PAGE369',
 WATTAGE='1/16W',
 TOLERANCE='1%',
 MATERIAL='CHIP',
 PHYS_PAGE='257',
 XY='(-8900,4900)',
 ROT='0',
 VER='2',
 PACK_TYPE='0402LF',
 LOCATION='R2908',
 CDS_LIB='pure_quanta',
 CDS_PART_NAME='Q_RES_0402LF-5.11K,1%,1/16W,CHIP,CS25112FB04',
 PART_NUMBER='CS25112FB04',
 VALUE='5.11K',
 PRIM_FILE='./archive_libs/logical/q_res/chips/chips.prt';

PART_NAME
 R2909 'Q_RES_0402LF-4.7K,5%,1/16W,CHIP,CS24702JB10':;

SECTION_NUMBER 1
 '@T6G_MB_LIB.T6G(SCH_1):PAGE256_I198@PURE_QUANTA.Q_RES(CHIPS)':
 C_PATH='@t6g_mb_lib.t6g(sch_1):page256_i198@pure_quanta.q_res(chips)',
 P_PATH='@t6g_mb_lib.t6g(sch_1):page130_i198@pure_quanta.q_res(chips)',
 PATH='I198',
 DRAWING='@T6G_MB_LIB.T6G(SCH_1):PAGE256',
 WATTAGE='1/16W',
 TOLERANCE='5%',
 MATERIAL='CHIP',
 PHYS_PAGE='130',
 XY='(0,2150)',
 ROT='0',
 VER='2',
 PACK_TYPE='0402LF',
 LOCATION='R2909',
 CDS_LIB='pure_quanta',
 CDS_PART_NAME='Q_RES_0402LF-4.7K,5%,1/16W,CHIP,CS24702JB10',
 PART_NUMBER='CS24702JB10',
 VALUE='4.7K',
 PRIM_FILE='./archive_libs/logical/q_res/chips/chips.prt';

PART_NAME
 R2910 'Q_RES_0402LF-100K,1%,1/16W,EMPTY,CS41002FB09':;

SECTION_NUMBER 1
 '@T6G_MB_LIB.T6G(SCH_1):PAGE334_I187@PURE_QUANTA.Q_RES(CHIPS)':
 C_PATH='@t6g_mb_lib.t6g(sch_1):page334_i187@pure_quanta.q_res(chips)',
 P_PATH='@t6g_mb_lib.t6g(sch_1):page128_i187@pure_quanta.q_res(chips)',
 PATH='I187',
 DRAWING='@T6G_MB_LIB.T6G(SCH_1):PAGE334',
 WATTAGE='1/16W',
 TOLERANCE='1%',
 MATERIAL='EMPTY',
 PHYS_PAGE='128',
 XY='(-7800,-125)',
 ROT='0',
 VER='2',
 PACK_TYPE='0402LF',
 LOCATION='R2910',
 CDS_LIB='pure_quanta',
 CDS_PART_NAME='Q_RES_0402LF-100K,1%,1/16W,EMPTY,CS41002FB09',
 PART_NUMBER='CS41002FB09',
 VALUE='100K',
 PRIM_FILE='./archive_libs/logical/q_res/chips/chips.prt';

PART_NAME
 R2911 'Q_RES_0402LF-4.7K,5%,1/16W,EMPTY,CS24702JB10':;

SECTION_NUMBER 1
 '@T6G_MB_LIB.T6G(SCH_1):PAGE256_I153@PURE_QUANTA.Q_RES(CHIPS)':
 C_PATH='@t6g_mb_lib.t6g(sch_1):page256_i153@pure_quanta.q_res(chips)',
 P_PATH='@t6g_mb_lib.t6g(sch_1):page130_i153@pure_quanta.q_res(chips)',
 PATH='I153',
 DRAWING='@T6G_MB_LIB.T6G(SCH_1):PAGE256',
 WATTAGE='1/16W',
 TOLERANCE='5%',
 MATERIAL='EMPTY',
 PHYS_PAGE='130',
 XY='(2600,2050)',
 ROT='0',
 VER='2',
 PACK_TYPE='0402LF',
 LOCATION='R2911',
 CDS_LIB='pure_quanta',
 CDS_PART_NAME='Q_RES_0402LF-4.7K,5%,1/16W,EMPTY,CS24702JB10',
 PART_NUMBER='CS24702JB10',
 VALUE='4.7K',
 PRIM_FILE='./archive_libs/logical/q_res/chips/chips.prt';

PART_NAME
 R2912 'Q_RES_0402LF-4.7K,5%,1/16W,EMPTY,CS24702JB10':;

SECTION_NUMBER 1
 '@T6G_MB_LIB.T6G(SCH_1):PAGE256_I147@PURE_QUANTA.Q_RES(CHIPS)':
 C_PATH='@t6g_mb_lib.t6g(sch_1):page256_i147@pure_quanta.q_res(chips)',
 P_PATH='@t6g_mb_lib.t6g(sch_1):page130_i147@pure_quanta.q_res(chips)',
 PATH='I147',
 DRAWING='@T6G_MB_LIB.T6G(SCH_1):PAGE256',
 WATTAGE='1/16W',
 TOLERANCE='5%',
 MATERIAL='EMPTY',
 PHYS_PAGE='130',
 XY='(2575,850)',
 ROT='0',
 VER='2',
 PACK_TYPE='0402LF',
 LOCATION='R2912',
 CDS_LIB='pure_quanta',
 CDS_PART_NAME='Q_RES_0402LF-4.7K,5%,1/16W,EMPTY,CS24702JB10',
 PART_NUMBER='CS24702JB10',
 VALUE='4.7K',
 PRIM_FILE='./archive_libs/logical/q_res/chips/chips.prt';

PART_NAME
 R2914 'Q_RES_0402LF-4.7K,5%,1/16W,EMPTY,CS24702JB10':;

SECTION_NUMBER 1
 '@T6G_MB_LIB.T6G(SCH_1):PAGE334_I192@PURE_QUANTA.Q_RES(CHIPS)':
 C_PATH='@t6g_mb_lib.t6g(sch_1):page334_i192@pure_quanta.q_res(chips)',
 P_PATH='@t6g_mb_lib.t6g(sch_1):page128_i192@pure_quanta.q_res(chips)',
 PATH='I192',
 DRAWING='@T6G_MB_LIB.T6G(SCH_1):PAGE334',
 WATTAGE='1/16W',
 TOLERANCE='5%',
 MATERIAL='EMPTY',
 PHYS_PAGE='128',
 XY='(-4150,-300)',
 ROT='0',
 VER='2',
 PACK_TYPE='0402LF',
 LOCATION='R2914',
 CDS_LIB='pure_quanta',
 CDS_PART_NAME='Q_RES_0402LF-4.7K,5%,1/16W,EMPTY,CS24702JB10',
 PART_NUMBER='CS24702JB10',
 VALUE='4.7K',
 PRIM_FILE='./archive_libs/logical/q_res/chips/chips.prt';

PART_NAME
 R2915 'Q_RES_0402LF-4.7K,5%,1/16W,CHIP,CS24702JB10':;

SECTION_NUMBER 1
 '@T6G_MB_LIB.T6G(SCH_1):PAGE256_I92@PURE_QUANTA.Q_RES(CHIPS)':
 C_PATH='@t6g_mb_lib.t6g(sch_1):page256_i92@pure_quanta.q_res(chips)',
 P_PATH='@t6g_mb_lib.t6g(sch_1):page130_i92@pure_quanta.q_res(chips)',
 PATH='I92',
 DRAWING='@T6G_MB_LIB.T6G(SCH_1):PAGE256',
 WATTAGE='1/16W',
 TOLERANCE='5%',
 MATERIAL='CHIP',
 PHYS_PAGE='130',
 XY='(25,2800)',
 ROT='0',
 VER='2',
 PACK_TYPE='0402LF',
 LOCATION='R2915',
 CDS_LIB='pure_quanta',
 CDS_PART_NAME='Q_RES_0402LF-4.7K,5%,1/16W,CHIP,CS24702JB10',
 PART_NUMBER='CS24702JB10',
 VALUE='4.7K',
 PRIM_FILE='./archive_libs/logical/q_res/chips/chips.prt';

PART_NAME
 R2916 'Q_RES_0402LF-4.7K,5%,1/16W,EMPTY,CS24702JB10':;

SECTION_NUMBER 1
 '@T6G_MB_LIB.T6G(SCH_1):PAGE256_I93@PURE_QUANTA.Q_RES(CHIPS)':
 C_PATH='@t6g_mb_lib.t6g(sch_1):page256_i93@pure_quanta.q_res(chips)',
 P_PATH='@t6g_mb_lib.t6g(sch_1):page130_i93@pure_quanta.q_res(chips)',
 PATH='I93',
 DRAWING='@T6G_MB_LIB.T6G(SCH_1):PAGE256',
 WATTAGE='1/16W',
 TOLERANCE='5%',
 MATERIAL='EMPTY',
 PHYS_PAGE='130',
 XY='(25,1675)',
 ROT='0',
 VER='2',
 PACK_TYPE='0402LF',
 LOCATION='R2916',
 CDS_LIB='pure_quanta',
 CDS_PART_NAME='Q_RES_0402LF-4.7K,5%,1/16W,EMPTY,CS24702JB10',
 PART_NUMBER='CS24702JB10',
 VALUE='4.7K',
 PRIM_FILE='./archive_libs/logical/q_res/chips/chips.prt';

PART_NAME
 R2917 'Q_RES_0402LF-49.9,1%,1/16W,CHIP,CS04992FB07':;

SECTION_NUMBER 1
 '@T6G_MB_LIB.T6G(SCH_1):PAGE256_I154@PURE_QUANTA.Q_RES(CHIPS)':
 C_PATH='@t6g_mb_lib.t6g(sch_1):page256_i154@pure_quanta.q_res(chips)',
 P_PATH='@t6g_mb_lib.t6g(sch_1):page130_i154@pure_quanta.q_res(chips)',
 PATH='I154',
 DRAWING='@T6G_MB_LIB.T6G(SCH_1):PAGE256',
 WATTAGE='1/16W',
 TOLERANCE='1%',
 MATERIAL='CHIP',
 PHYS_PAGE='130',
 XY='(2850,3000)',
 ROT='0',
 VER='1',
 PACK_TYPE='0402LF',
 LOCATION='R2917',
 CDS_LIB='pure_quanta',
 CDS_PART_NAME='Q_RES_0402LF-49.9,1%,1/16W,CHIP,CS04992FB07',
 PART_NUMBER='CS04992FB07',
 VALUE='49.9',
 PRIM_FILE='./archive_libs/logical/q_res/chips/chips.prt';

PART_NAME
 R2918 'Q_RES_0402LF-4.7K,5%,1/16W,CHIP,CS24702JB10':;

SECTION_NUMBER 1
 '@T6G_MB_LIB.T6G(SCH_1):PAGE334_I188@PURE_QUANTA.Q_RES(CHIPS)':
 C_PATH='@t6g_mb_lib.t6g(sch_1):page334_i188@pure_quanta.q_res(chips)',
 P_PATH='@t6g_mb_lib.t6g(sch_1):page128_i188@pure_quanta.q_res(chips)',
 PATH='I188',
 DRAWING='@T6G_MB_LIB.T6G(SCH_1):PAGE334',
 WATTAGE='1/16W',
 TOLERANCE='5%',
 MATERIAL='CHIP',
 PHYS_PAGE='128',
 XY='(-7775,-600)',
 ROT='0',
 VER='2',
 PACK_TYPE='0402LF',
 LOCATION='R2918',
 CDS_LIB='pure_quanta',
 CDS_PART_NAME='Q_RES_0402LF-4.7K,5%,1/16W,CHIP,CS24702JB10',
 PART_NUMBER='CS24702JB10',
 VALUE='4.7K',
 PRIM_FILE='./archive_libs/logical/q_res/chips/chips.prt';

PART_NAME
 R2919 'Q_RES_0402LF-100K,1%,1/16W,CHIP,CS41002FB09':;

SECTION_NUMBER 1
 '@T6G_MB_LIB.T6G(SCH_1):PAGE333_I91@PURE_QUANTA.Q_RES(CHIPS)':
 C_PATH='@t6g_mb_lib.t6g(sch_1):page333_i91@pure_quanta.q_res(chips)',
 P_PATH='@t6g_mb_lib.t6g(sch_1):page127_i91@pure_quanta.q_res(chips)',
 PATH='I91',
 DRAWING='@T6G_MB_LIB.T6G(SCH_1):PAGE333',
 WATTAGE='1/16W',
 TOLERANCE='1%',
 MATERIAL='CHIP',
 PHYS_PAGE='127',
 XY='(-2475,6725)',
 ROT='0',
 VER='2',
 PACK_TYPE='0402LF',
 LOCATION='R2919',
 CDS_LIB='pure_quanta',
 CDS_PART_NAME='Q_RES_0402LF-100K,1%,1/16W,CHIP,CS41002FB09',
 PART_NUMBER='CS41002FB09',
 VALUE='100K',
 PRIM_FILE='./archive_libs/logical/q_res/chips/chips.prt';

PART_NAME
 R2920 'Q_RES_0402LF-100K,1%,1/16W,CHIP,CS41002FB09':;

SECTION_NUMBER 1
 '@T6G_MB_LIB.T6G(SCH_1):PAGE333_I177@PURE_QUANTA.Q_RES(CHIPS)':
 C_PATH='@t6g_mb_lib.t6g(sch_1):page333_i177@pure_quanta.q_res(chips)',
 P_PATH='@t6g_mb_lib.t6g(sch_1):page127_i177@pure_quanta.q_res(chips)',
 PATH='I177',
 DRAWING='@T6G_MB_LIB.T6G(SCH_1):PAGE333',
 WATTAGE='1/16W',
 TOLERANCE='1%',
 MATERIAL='CHIP',
 PHYS_PAGE='127',
 XY='(-2375,8125)',
 ROT='2',
 VER='2',
 PACK_TYPE='0402LF',
 LOCATION='R2920',
 CDS_LIB='pure_quanta',
 CDS_PART_NAME='Q_RES_0402LF-100K,1%,1/16W,CHIP,CS41002FB09',
 PART_NUMBER='CS41002FB09',
 VALUE='100K',
 PRIM_FILE='./archive_libs/logical/q_res/chips/chips.prt';

PART_NAME
 R2921 'Q_RES_0402LF-10K,1%,1/16W,EMPTY,CS31002FB08':;

SECTION_NUMBER 1
 '@T6G_MB_LIB.T6G(SCH_1):PAGE246_I35@PURE_QUANTA.Q_RES(CHIPS)':
 C_PATH='@t6g_mb_lib.t6g(sch_1):page246_i35@pure_quanta.q_res(chips)',
 P_PATH='@t6g_mb_lib.t6g(sch_1):page245_i35@pure_quanta.q_res(chips)',
 PATH='I35',
 DRAWING='@T6G_MB_LIB.T6G(SCH_1):PAGE246',
 WATTAGE='1/16W',
 TOLERANCE='1%',
 MATERIAL='EMPTY',
 PHYS_PAGE='245',
 XY='(-6575,5650)',
 ROT='2',
 VER='2',
 PACK_TYPE='0402LF',
 LOCATION='R2921',
 CDS_LIB='pure_quanta',
 CDS_PART_NAME='Q_RES_0402LF-10K,1%,1/16W,EMPTY,CS31002FB08',
 PART_NUMBER='CS31002FB08',
 VALUE='10K',
 PRIM_FILE='./archive_libs/logical/q_res/chips/chips.prt';

PART_NAME
 R2922 'Q_RES_0402LF-0,5%,1/16W,CHIP,CS00002JB13':;

SECTION_NUMBER 1
 '@T6G_MB_LIB.T6G(SCH_1):PAGE246_I31@PURE_QUANTA.Q_RES(CHIPS)':
 C_PATH='@t6g_mb_lib.t6g(sch_1):page246_i31@pure_quanta.q_res(chips)',
 P_PATH='@t6g_mb_lib.t6g(sch_1):page245_i31@pure_quanta.q_res(chips)',
 PATH='I31',
 DRAWING='@T6G_MB_LIB.T6G(SCH_1):PAGE246',
 WATTAGE='1/16W',
 TOLERANCE='5%',
 MATERIAL='CHIP',
 PHYS_PAGE='245',
 XY='(-6275,5300)',
 ROT='0',
 VER='1',
 PACK_TYPE='0402LF',
 LOCATION='R2922',
 CDS_LIB='pure_quanta',
 CDS_PART_NAME='Q_RES_0402LF-0,5%,1/16W,CHIP,CS00002JB13',
 PART_NUMBER='CS00002JB13',
 VALUE='0',
 PRIM_FILE='./archive_libs/logical/q_res/chips/chips.prt';

PART_NAME
 R2923 'Q_RES_0402LF-4.7K,5%,1/16W,EMPTY,CS24702JB10':;

SECTION_NUMBER 1
 '@T6G_MB_LIB.T6G(SCH_1):PAGE246_I37@PURE_QUANTA.Q_RES(CHIPS)':
 C_PATH='@t6g_mb_lib.t6g(sch_1):page246_i37@pure_quanta.q_res(chips)',
 P_PATH='@t6g_mb_lib.t6g(sch_1):page245_i37@pure_quanta.q_res(chips)',
 PATH='I37',
 DRAWING='@T6G_MB_LIB.T6G(SCH_1):PAGE246',
 WATTAGE='1/16W',
 TOLERANCE='5%',
 MATERIAL='EMPTY',
 PHYS_PAGE='245',
 XY='(-5600,5800)',
 ROT='0',
 VER='2',
 PACK_TYPE='0402LF',
 LOCATION='R2923',
 CDS_LIB='pure_quanta',
 CDS_PART_NAME='Q_RES_0402LF-4.7K,5%,1/16W,EMPTY,CS24702JB10',
 PART_NUMBER='CS24702JB10',
 VALUE='4.7K',
 PRIM_FILE='./archive_libs/logical/q_res/chips/chips.prt';

PART_NAME
 R2924 'Q_RES_0402LF-49.9,1%,1/16W,CHIP,CS04992FB07':;

SECTION_NUMBER 1
 '@T6G_MB_LIB.T6G(SCH_1):PAGE256_I155@PURE_QUANTA.Q_RES(CHIPS)':
 C_PATH='@t6g_mb_lib.t6g(sch_1):page256_i155@pure_quanta.q_res(chips)',
 P_PATH='@t6g_mb_lib.t6g(sch_1):page130_i155@pure_quanta.q_res(chips)',
 PATH='I155',
 DRAWING='@T6G_MB_LIB.T6G(SCH_1):PAGE256',
 WATTAGE='1/16W',
 TOLERANCE='1%',
 MATERIAL='CHIP',
 PHYS_PAGE='130',
 XY='(2925,1875)',
 ROT='0',
 VER='1',
 PACK_TYPE='0402LF',
 LOCATION='R2924',
 CDS_LIB='pure_quanta',
 CDS_PART_NAME='Q_RES_0402LF-49.9,1%,1/16W,CHIP,CS04992FB07',
 PART_NUMBER='CS04992FB07',
 VALUE='49.9',
 PRIM_FILE='./archive_libs/logical/q_res/chips/chips.prt';

PART_NAME
 R2925 'Q_RES_0402LF-49.9,1%,1/16W,CHIP,CS04992FB07':;

SECTION_NUMBER 1
 '@T6G_MB_LIB.T6G(SCH_1):PAGE256_I156@PURE_QUANTA.Q_RES(CHIPS)':
 C_PATH='@t6g_mb_lib.t6g(sch_1):page256_i156@pure_quanta.q_res(chips)',
 P_PATH='@t6g_mb_lib.t6g(sch_1):page130_i156@pure_quanta.q_res(chips)',
 PATH='I156',
 DRAWING='@T6G_MB_LIB.T6G(SCH_1):PAGE256',
 WATTAGE='1/16W',
 TOLERANCE='1%',
 MATERIAL='CHIP',
 PHYS_PAGE='130',
 XY='(2825,600)',
 ROT='0',
 VER='1',
 PACK_TYPE='0402LF',
 LOCATION='R2925',
 CDS_LIB='pure_quanta',
 CDS_PART_NAME='Q_RES_0402LF-49.9,1%,1/16W,CHIP,CS04992FB07',
 PART_NUMBER='CS04992FB07',
 VALUE='49.9',
 PRIM_FILE='./archive_libs/logical/q_res/chips/chips.prt';

PART_NAME
 R2926 'Q_RES_0402LF-4.7K,5%,1/16W,CHIP,CS24702JB10':;

SECTION_NUMBER 1
 '@T6G_MB_LIB.T6G(SCH_1):PAGE256_I121@PURE_QUANTA.Q_RES(CHIPS)':
 C_PATH='@t6g_mb_lib.t6g(sch_1):page256_i121@pure_quanta.q_res(chips)',
 P_PATH='@t6g_mb_lib.t6g(sch_1):page130_i121@pure_quanta.q_res(chips)',
 PATH='I121',
 DRAWING='@T6G_MB_LIB.T6G(SCH_1):PAGE256',
 WATTAGE='1/16W',
 TOLERANCE='5%',
 MATERIAL='CHIP',
 PHYS_PAGE='130',
 XY='(2525,2700)',
 ROT='0',
 VER='2',
 PACK_TYPE='0402LF',
 LOCATION='R2926',
 CDS_LIB='pure_quanta',
 CDS_PART_NAME='Q_RES_0402LF-4.7K,5%,1/16W,CHIP,CS24702JB10',
 PART_NUMBER='CS24702JB10',
 VALUE='4.7K',
 PRIM_FILE='./archive_libs/logical/q_res/chips/chips.prt';

PART_NAME
 R2927 'Q_RES_0402LF-100K,1%,1/16W,CHIP,CS41002FB09':;

SECTION_NUMBER 1
 '@T6G_MB_LIB.T6G(SCH_1):PAGE256_I203@PURE_QUANTA.Q_RES(CHIPS)':
 C_PATH='@t6g_mb_lib.t6g(sch_1):page256_i203@pure_quanta.q_res(chips)',
 P_PATH='@t6g_mb_lib.t6g(sch_1):page130_i203@pure_quanta.q_res(chips)',
 PATH='I203',
 DRAWING='@T6G_MB_LIB.T6G(SCH_1):PAGE256',
 WATTAGE='1/16W',
 TOLERANCE='1%',
 MATERIAL='CHIP',
 PHYS_PAGE='130',
 XY='(2625,1575)',
 ROT='0',
 VER='2',
 PACK_TYPE='0402LF',
 LOCATION='R2927',
 CDS_LIB='pure_quanta',
 CDS_PART_NAME='Q_RES_0402LF-100K,1%,1/16W,CHIP,CS41002FB09',
 PART_NUMBER='CS41002FB09',
 VALUE='100K',
 PRIM_FILE='./archive_libs/logical/q_res/chips/chips.prt';

PART_NAME
 R2932 'Q_RES_0402LF-4.7K,5%,1/16W,CHIP,CS24702JB10':;

SECTION_NUMBER 1
 '@T6G_MB_LIB.T6G(SCH_1):PAGE334_I195@PURE_QUANTA.Q_RES(CHIPS)':
 C_PATH='@t6g_mb_lib.t6g(sch_1):page334_i195@pure_quanta.q_res(chips)',
 P_PATH='@t6g_mb_lib.t6g(sch_1):page128_i195@pure_quanta.q_res(chips)',
 PATH='I195',
 DRAWING='@T6G_MB_LIB.T6G(SCH_1):PAGE334',
 WATTAGE='1/16W',
 TOLERANCE='5%',
 MATERIAL='CHIP',
 PHYS_PAGE='128',
 XY='(-4125,-800)',
 ROT='0',
 VER='2',
 PACK_TYPE='0402LF',
 LOCATION='R2932',
 CDS_LIB='pure_quanta',
 CDS_PART_NAME='Q_RES_0402LF-4.7K,5%,1/16W,CHIP,CS24702JB10',
 PART_NUMBER='CS24702JB10',
 VALUE='4.7K',
 PRIM_FILE='./archive_libs/logical/q_res/chips/chips.prt';

PART_NAME
 R2933 'Q_RES_0402LF-100K,1%,1/16W,CHIP,CS41002FB09':;

SECTION_NUMBER 1
 '@T6G_MB_LIB.T6G(SCH_1):PAGE333_I180@PURE_QUANTA.Q_RES(CHIPS)':
 C_PATH='@t6g_mb_lib.t6g(sch_1):page333_i180@pure_quanta.q_res(chips)',
 P_PATH='@t6g_mb_lib.t6g(sch_1):page127_i180@pure_quanta.q_res(chips)',
 PATH='I180',
 DRAWING='@T6G_MB_LIB.T6G(SCH_1):PAGE333',
 WATTAGE='1/16W',
 TOLERANCE='1%',
 MATERIAL='CHIP',
 PHYS_PAGE='127',
 XY='(-2500,5350)',
 ROT='2',
 VER='2',
 PACK_TYPE='0402LF',
 LOCATION='R2933',
 CDS_LIB='pure_quanta',
 CDS_PART_NAME='Q_RES_0402LF-100K,1%,1/16W,CHIP,CS41002FB09',
 PART_NUMBER='CS41002FB09',
 VALUE='100K',
 PRIM_FILE='./archive_libs/logical/q_res/chips/chips.prt';

PART_NAME
 R2934 'Q_RES_0402LF-100K,1%,1/16W,CHIP,CS41002FB09':;

SECTION_NUMBER 1
 '@T6G_MB_LIB.T6G(SCH_1):PAGE333_I101@PURE_QUANTA.Q_RES(CHIPS)':
 C_PATH='@t6g_mb_lib.t6g(sch_1):page333_i101@pure_quanta.q_res(chips)',
 P_PATH='@t6g_mb_lib.t6g(sch_1):page127_i101@pure_quanta.q_res(chips)',
 PATH='I101',
 DRAWING='@T6G_MB_LIB.T6G(SCH_1):PAGE333',
 WATTAGE='1/16W',
 TOLERANCE='1%',
 MATERIAL='CHIP',
 PHYS_PAGE='127',
 XY='(1925,8175)',
 ROT='0',
 VER='2',
 PACK_TYPE='0402LF',
 LOCATION='R2934',
 CDS_LIB='pure_quanta',
 CDS_PART_NAME='Q_RES_0402LF-100K,1%,1/16W,CHIP,CS41002FB09',
 PART_NUMBER='CS41002FB09',
 VALUE='100K',
 PRIM_FILE='./archive_libs/logical/q_res/chips/chips.prt';

PART_NAME
 R2935 'Q_RES_0402LF-100K,1%,1/16W,CHIP,CS41002FB09':;

SECTION_NUMBER 1
 '@T6G_MB_LIB.T6G(SCH_1):PAGE333_I109@PURE_QUANTA.Q_RES(CHIPS)':
 C_PATH='@t6g_mb_lib.t6g(sch_1):page333_i109@pure_quanta.q_res(chips)',
 P_PATH='@t6g_mb_lib.t6g(sch_1):page127_i109@pure_quanta.q_res(chips)',
 PATH='I109',
 DRAWING='@T6G_MB_LIB.T6G(SCH_1):PAGE333',
 WATTAGE='1/16W',
 TOLERANCE='1%',
 MATERIAL='CHIP',
 PHYS_PAGE='127',
 XY='(2025,6875)',
 ROT='0',
 VER='2',
 PACK_TYPE='0402LF',
 LOCATION='R2935',
 CDS_LIB='pure_quanta',
 CDS_PART_NAME='Q_RES_0402LF-100K,1%,1/16W,CHIP,CS41002FB09',
 PART_NUMBER='CS41002FB09',
 VALUE='100K',
 PRIM_FILE='./archive_libs/logical/q_res/chips/chips.prt';

PART_NAME
 R2936 'Q_RES_0402LF-100K,1%,1/16W,EMPTY,CS41002FB09':;

SECTION_NUMBER 1
 '@T6G_MB_LIB.T6G(SCH_1):PAGE256_I162@PURE_QUANTA.Q_RES(CHIPS)':
 C_PATH='@t6g_mb_lib.t6g(sch_1):page256_i162@pure_quanta.q_res(chips)',
 P_PATH='@t6g_mb_lib.t6g(sch_1):page130_i162@pure_quanta.q_res(chips)',
 PATH='I162',
 DRAWING='@T6G_MB_LIB.T6G(SCH_1):PAGE256',
 WATTAGE='1/16W',
 TOLERANCE='1%',
 MATERIAL='EMPTY',
 PHYS_PAGE='130',
 XY='(-75,875)',
 ROT='0',
 VER='2',
 PACK_TYPE='0402LF',
 LOCATION='R2936',
 CDS_LIB='pure_quanta',
 CDS_PART_NAME='Q_RES_0402LF-100K,1%,1/16W,EMPTY,CS41002FB09',
 PART_NUMBER='CS41002FB09',
 VALUE='100K',
 PRIM_FILE='./archive_libs/logical/q_res/chips/chips.prt';

PART_NAME
 R2937 'Q_RES_0402LF-4.7K,5%,1/16W,CHIP,CS24702JB10':;

SECTION_NUMBER 1
 '@T6G_MB_LIB.T6G(SCH_1):PAGE256_I160@PURE_QUANTA.Q_RES(CHIPS)':
 C_PATH='@t6g_mb_lib.t6g(sch_1):page256_i160@pure_quanta.q_res(chips)',
 P_PATH='@t6g_mb_lib.t6g(sch_1):page130_i160@pure_quanta.q_res(chips)',
 PATH='I160',
 DRAWING='@T6G_MB_LIB.T6G(SCH_1):PAGE256',
 WATTAGE='1/16W',
 TOLERANCE='5%',
 MATERIAL='CHIP',
 PHYS_PAGE='130',
 XY='(-50,400)',
 ROT='0',
 VER='2',
 PACK_TYPE='0402LF',
 LOCATION='R2937',
 CDS_LIB='pure_quanta',
 CDS_PART_NAME='Q_RES_0402LF-4.7K,5%,1/16W,CHIP,CS24702JB10',
 PART_NUMBER='CS24702JB10',
 VALUE='4.7K',
 PRIM_FILE='./archive_libs/logical/q_res/chips/chips.prt';

PART_NAME
 R2939 'Q_RES_0402LF-33.2,1%,1/16W,CHIP,CS03322FB03':;

SECTION_NUMBER 1
 '@T6G_MB_LIB.T6G(SCH_1):PAGE80_I311@PURE_QUANTA.Q_RES(CHIPS)':
 C_PATH='@t6g_mb_lib.t6g(sch_1):page80_i311@pure_quanta.q_res(chips)',
 P_PATH='@t6g_mb_lib.t6g(sch_1):page81_i311@pure_quanta.q_res(chips)',
 PATH='I311',
 DRAWING='@T6G_MB_LIB.T6G(SCH_1):PAGE80',
 WATTAGE='1/16W',
 TOLERANCE='1%',
 MATERIAL='CHIP',
 PHYS_PAGE='81',
 XY='(-6725,1475)',
 ROT='0',
 VER='1',
 PACK_TYPE='0402LF',
 LOCATION='R2939',
 CDS_LIB='pure_quanta',
 CDS_PART_NAME='Q_RES_0402LF-33.2,1%,1/16W,CHIP,CS03322FB03',
 PART_NUMBER='CS03322FB03',
 VALUE='33.2',
 PRIM_FILE='./archive_libs/logical/q_res/chips/chips.prt';

PART_NAME
 R2940 'Q_RES_0402LF-4.7K,5%,1/16W,EMPTY,CS24702JB10':;

SECTION_NUMBER 1
 '@T6G_MB_LIB.T6G(SCH_1):PAGE364_I28@PURE_QUANTA.Q_RES(CHIPS)':
 C_PATH='@t6g_mb_lib.t6g(sch_1):page364_i28@pure_quanta.q_res(chips)',
 P_PATH='@t6g_mb_lib.t6g(sch_1):page241_i28@pure_quanta.q_res(chips)',
 PATH='I28',
 DRAWING='@T6G_MB_LIB.T6G(SCH_1):PAGE364',
 WATTAGE='1/16W',
 TOLERANCE='5%',
 MATERIAL='EMPTY',
 PHYS_PAGE='241',
 XY='(-1800,3100)',
 ROT='0',
 VER='2',
 PACK_TYPE='0402LF',
 LOCATION='R2940',
 CDS_LIB='pure_quanta',
 CDS_PART_NAME='Q_RES_0402LF-4.7K,5%,1/16W,EMPTY,CS24702JB10',
 PART_NUMBER='CS24702JB10',
 VALUE='4.7K',
 PRIM_FILE='./archive_libs/logical/q_res/chips/chips.prt';

PART_NAME
 R2941 'Q_RES_0402LF-100K,1%,1/16W,CHIP,CS41002FB09':;

SECTION_NUMBER 1
 '@T6G_MB_LIB.T6G(SCH_1):PAGE364_I29@PURE_QUANTA.Q_RES(CHIPS)':
 C_PATH='@t6g_mb_lib.t6g(sch_1):page364_i29@pure_quanta.q_res(chips)',
 P_PATH='@t6g_mb_lib.t6g(sch_1):page241_i29@pure_quanta.q_res(chips)',
 PATH='I29',
 DRAWING='@T6G_MB_LIB.T6G(SCH_1):PAGE364',
 WATTAGE='1/16W',
 TOLERANCE='1%',
 MATERIAL='CHIP',
 PHYS_PAGE='241',
 XY='(-1775,2625)',
 ROT='0',
 VER='2',
 PACK_TYPE='0402LF',
 LOCATION='R2941',
 CDS_LIB='pure_quanta',
 CDS_PART_NAME='Q_RES_0402LF-100K,1%,1/16W,CHIP,CS41002FB09',
 PART_NUMBER='CS41002FB09',
 VALUE='100K',
 PRIM_FILE='./archive_libs/logical/q_res/chips/chips.prt';

PART_NAME
 R2944 'Q_RES_0402LF-33.2,1%,1/16W,CHIP,CS03322FB03':;

SECTION_NUMBER 1
 '@T6G_MB_LIB.T6G(SCH_1):PAGE364_I24@PURE_QUANTA.Q_RES(CHIPS)':
 C_PATH='@t6g_mb_lib.t6g(sch_1):page364_i24@pure_quanta.q_res(chips)',
 P_PATH='@t6g_mb_lib.t6g(sch_1):page241_i24@pure_quanta.q_res(chips)',
 PATH='I24',
 DRAWING='@T6G_MB_LIB.T6G(SCH_1):PAGE364',
 WATTAGE='1/16W',
 TOLERANCE='1%',
 MATERIAL='CHIP',
 PHYS_PAGE='241',
 XY='(2000,2075)',
 ROT='0',
 VER='1',
 PACK_TYPE='0402LF',
 LOCATION='R2944',
 CDS_LIB='pure_quanta',
 CDS_PART_NAME='Q_RES_0402LF-33.2,1%,1/16W,CHIP,CS03322FB03',
 PART_NUMBER='CS03322FB03',
 VALUE='33.2',
 PRIM_FILE='./archive_libs/logical/q_res/chips/chips.prt';

PART_NAME
 R2946 'Q_RES_0402LF-4.7K,5%,1/16W,EMPTY,CS24702JB10':;

SECTION_NUMBER 1
 '@T6G_MB_LIB.T6G(SCH_1):PAGE364_I25@PURE_QUANTA.Q_RES(CHIPS)':
 C_PATH='@t6g_mb_lib.t6g(sch_1):page364_i25@pure_quanta.q_res(chips)',
 P_PATH='@t6g_mb_lib.t6g(sch_1):page241_i25@pure_quanta.q_res(chips)',
 PATH='I25',
 DRAWING='@T6G_MB_LIB.T6G(SCH_1):PAGE364',
 WATTAGE='1/16W',
 TOLERANCE='5%',
 MATERIAL='EMPTY',
 PHYS_PAGE='241',
 XY='(1725,2325)',
 ROT='0',
 VER='2',
 PACK_TYPE='0402LF',
 LOCATION='R2946',
 CDS_LIB='pure_quanta',
 CDS_PART_NAME='Q_RES_0402LF-4.7K,5%,1/16W,EMPTY,CS24702JB10',
 PART_NUMBER='CS24702JB10',
 VALUE='4.7K',
 PRIM_FILE='./archive_libs/logical/q_res/chips/chips.prt';

PART_NAME
 R2948 'Q_RES_0402LF-4.7K,5%,1/16W,EMPTY,CS24702JB10':;

SECTION_NUMBER 1
 '@T6G_MB_LIB.T6G(SCH_1):PAGE364_I30@PURE_QUANTA.Q_RES(CHIPS)':
 C_PATH='@t6g_mb_lib.t6g(sch_1):page364_i30@pure_quanta.q_res(chips)',
 P_PATH='@t6g_mb_lib.t6g(sch_1):page241_i30@pure_quanta.q_res(chips)',
 PATH='I30',
 DRAWING='@T6G_MB_LIB.T6G(SCH_1):PAGE364',
 WATTAGE='1/16W',
 TOLERANCE='5%',
 MATERIAL='EMPTY',
 PHYS_PAGE='241',
 XY='(1750,1775)',
 ROT='0',
 VER='2',
 PACK_TYPE='0402LF',
 LOCATION='R2948',
 CDS_LIB='pure_quanta',
 CDS_PART_NAME='Q_RES_0402LF-4.7K,5%,1/16W,EMPTY,CS24702JB10',
 PART_NUMBER='CS24702JB10',
 VALUE='4.7K',
 PRIM_FILE='./archive_libs/logical/q_res/chips/chips.prt';

PART_NAME
 R2950 'Q_RES_0402LF-1K,1%,1/16W,CHIP,CS21002FB06':;

SECTION_NUMBER 1
 '@T6G_MB_LIB.T6G(SCH_1):PAGE363_I475@PURE_QUANTA.Q_RES(CHIPS)':
 C_PATH='@t6g_mb_lib.t6g(sch_1):page363_i475@pure_quanta.q_res(chips)',
 P_PATH='@t6g_mb_lib.t6g(sch_1):page240_i475@pure_quanta.q_res(chips)',
 PATH='I475',
 DRAWING='@T6G_MB_LIB.T6G(SCH_1):PAGE363',
 WATTAGE='1/16W',
 TOLERANCE='1%',
 MATERIAL='CHIP',
 PHYS_PAGE='240',
 XY='(-6275,-2325)',
 ROT='2',
 VER='2',
 PACK_TYPE='0402LF',
 LOCATION='R2950',
 CDS_LIB='pure_quanta',
 CDS_PART_NAME='Q_RES_0402LF-1K,1%,1/16W,CHIP,CS21002FB06',
 PART_NUMBER='CS21002FB06',
 VALUE='1K',
 PRIM_FILE='./archive_libs/logical/q_res/chips/chips.prt';

PART_NAME
 R2967 'Q_RES_0402LF-0,5%,1/16W,CHIP,CS00002JB13':;

SECTION_NUMBER 1
 '@T6G_MB_LIB.T6G(SCH_1):PAGE252_I25@PURE_QUANTA.Q_RES(CHIPS)':
 C_PATH='@t6g_mb_lib.t6g(sch_1):page252_i25@pure_quanta.q_res(chips)',
 P_PATH='@t6g_mb_lib.t6g(sch_1):page250_i25@pure_quanta.q_res(chips)',
 PATH='I25',
 DRAWING='@T6G_MB_LIB.T6G(SCH_1):PAGE252',
 WATTAGE='1/16W',
 TOLERANCE='5%',
 MATERIAL='CHIP',
 PHYS_PAGE='250',
 XY='(-5400,4325)',
 ROT='2',
 VER='1',
 PACK_TYPE='0402LF',
 LOCATION='R2967',
 CDS_LIB='pure_quanta',
 CDS_PART_NAME='Q_RES_0402LF-0,5%,1/16W,CHIP,CS00002JB13',
 PART_NUMBER='CS00002JB13',
 VALUE='0',
 PRIM_FILE='./archive_libs/logical/q_res/chips/chips.prt';

PART_NAME
 R2968 'Q_RES_0402LF-0,5%,1/16W,CHIP,CS00002JB13':;

SECTION_NUMBER 1
 '@T6G_MB_LIB.T6G(SCH_1):PAGE252_I26@PURE_QUANTA.Q_RES(CHIPS)':
 C_PATH='@t6g_mb_lib.t6g(sch_1):page252_i26@pure_quanta.q_res(chips)',
 P_PATH='@t6g_mb_lib.t6g(sch_1):page250_i26@pure_quanta.q_res(chips)',
 PATH='I26',
 DRAWING='@T6G_MB_LIB.T6G(SCH_1):PAGE252',
 WATTAGE='1/16W',
 TOLERANCE='5%',
 MATERIAL='CHIP',
 PHYS_PAGE='250',
 XY='(-5400,4375)',
 ROT='2',
 VER='1',
 PACK_TYPE='0402LF',
 LOCATION='R2968',
 CDS_LIB='pure_quanta',
 CDS_PART_NAME='Q_RES_0402LF-0,5%,1/16W,CHIP,CS00002JB13',
 PART_NUMBER='CS00002JB13',
 VALUE='0',
 PRIM_FILE='./archive_libs/logical/q_res/chips/chips.prt';

PART_NAME
 R2982 'Q_RES_0402LF-0,5%,1/16W,CHIP,CS00002JB13':;

SECTION_NUMBER 1
 '@T6G_MB_LIB.T6G(SCH_1):PAGE246_I82@PURE_QUANTA.Q_RES(CHIPS)':
 C_PATH='@t6g_mb_lib.t6g(sch_1):page246_i82@pure_quanta.q_res(chips)',
 P_PATH='@t6g_mb_lib.t6g(sch_1):page245_i82@pure_quanta.q_res(chips)',
 PATH='I82',
 DRAWING='@T6G_MB_LIB.T6G(SCH_1):PAGE246',
 WATTAGE='1/16W',
 TOLERANCE='5%',
 MATERIAL='CHIP',
 PHYS_PAGE='245',
 XY='(-3525,3250)',
 ROT='0',
 VER='1',
 PACK_TYPE='0402LF',
 LOCATION='R2982',
 CDS_LIB='pure_quanta',
 CDS_PART_NAME='Q_RES_0402LF-0,5%,1/16W,CHIP,CS00002JB13',
 PART_NUMBER='CS00002JB13',
 VALUE='0',
 PRIM_FILE='./archive_libs/logical/q_res/chips/chips.prt';

PART_NAME
 R2983 'Q_RES_0402LF-0,5%,1/16W,CHIP,CS00002JB13':;

SECTION_NUMBER 1
 '@T6G_MB_LIB.T6G(SCH_1):PAGE246_I58@PURE_QUANTA.Q_RES(CHIPS)':
 C_PATH='@t6g_mb_lib.t6g(sch_1):page246_i58@pure_quanta.q_res(chips)',
 P_PATH='@t6g_mb_lib.t6g(sch_1):page245_i58@pure_quanta.q_res(chips)',
 PATH='I58',
 DRAWING='@T6G_MB_LIB.T6G(SCH_1):PAGE246',
 WATTAGE='1/16W',
 TOLERANCE='5%',
 MATERIAL='CHIP',
 PHYS_PAGE='245',
 XY='(-3525,3050)',
 ROT='0',
 VER='1',
 PACK_TYPE='0402LF',
 LOCATION='R2983',
 CDS_LIB='pure_quanta',
 CDS_PART_NAME='Q_RES_0402LF-0,5%,1/16W,CHIP,CS00002JB13',
 PART_NUMBER='CS00002JB13',
 VALUE='0',
 PRIM_FILE='./archive_libs/logical/q_res/chips/chips.prt';

PART_NAME
 R2984 'Q_RES_0402LF-2.2K,5%,1/16W,CHIP,CS22202JB07':;

SECTION_NUMBER 1
 '@T6G_MB_LIB.T6G(SCH_1):PAGE252_I41@PURE_QUANTA.Q_RES(CHIPS)':
 C_PATH='@t6g_mb_lib.t6g(sch_1):page252_i41@pure_quanta.q_res(chips)',
 P_PATH='@t6g_mb_lib.t6g(sch_1):page250_i41@pure_quanta.q_res(chips)',
 PATH='I41',
 DRAWING='@T6G_MB_LIB.T6G(SCH_1):PAGE252',
 WATTAGE='1/16W',
 TOLERANCE='5%',
 MATERIAL='CHIP',
 PHYS_PAGE='250',
 XY='(-2125,1225)',
 ROT='0',
 VER='1',
 PACK_TYPE='0402LF',
 LOCATION='R2984',
 CDS_LIB='pure_quanta',
 CDS_PART_NAME='Q_RES_0402LF-2.2K,5%,1/16W,CHIP,CS22202JB07',
 PART_NUMBER='CS22202JB07',
 VALUE='2.2K',
 PRIM_FILE='./archive_libs/logical/q_res/chips/chips.prt';

PART_NAME
 R2985 'Q_RES_0402LF-2.2K,5%,1/16W,CHIP,CS22202JB07':;

SECTION_NUMBER 1
 '@T6G_MB_LIB.T6G(SCH_1):PAGE252_I42@PURE_QUANTA.Q_RES(CHIPS)':
 C_PATH='@t6g_mb_lib.t6g(sch_1):page252_i42@pure_quanta.q_res(chips)',
 P_PATH='@t6g_mb_lib.t6g(sch_1):page250_i42@pure_quanta.q_res(chips)',
 PATH='I42',
 DRAWING='@T6G_MB_LIB.T6G(SCH_1):PAGE252',
 WATTAGE='1/16W',
 TOLERANCE='5%',
 MATERIAL='CHIP',
 PHYS_PAGE='250',
 XY='(-2125,1175)',
 ROT='0',
 VER='1',
 PACK_TYPE='0402LF',
 LOCATION='R2985',
 CDS_LIB='pure_quanta',
 CDS_PART_NAME='Q_RES_0402LF-2.2K,5%,1/16W,CHIP,CS22202JB07',
 PART_NUMBER='CS22202JB07',
 VALUE='2.2K',
 PRIM_FILE='./archive_libs/logical/q_res/chips/chips.prt';

PART_NAME
 R2986 'Q_RES_0402LF-0,5%,1/16W,EMPTY,CS00002JB13':;

SECTION_NUMBER 1
 '@T6G_MB_LIB.T6G(SCH_1):PAGE249_I18@PURE_QUANTA.Q_RES(CHIPS)':
 C_PATH='@t6g_mb_lib.t6g(sch_1):page249_i18@pure_quanta.q_res(chips)',
 P_PATH='@t6g_mb_lib.t6g(sch_1):page248_i18@pure_quanta.q_res(chips)',
 PATH='I18',
 DRAWING='@T6G_MB_LIB.T6G(SCH_1):PAGE249',
 WATTAGE='1/16W',
 TOLERANCE='5%',
 MATERIAL='EMPTY',
 PHYS_PAGE='248',
 XY='(-6525,2200)',
 ROT='0',
 VER='1',
 PACK_TYPE='0402LF',
 LOCATION='R2986',
 CDS_LIB='pure_quanta',
 CDS_PART_NAME='Q_RES_0402LF-0,5%,1/16W,EMPTY,CS00002JB13',
 PART_NUMBER='CS00002JB13',
 VALUE='0',
 PRIM_FILE='./archive_libs/logical/q_res/chips/chips.prt';

PART_NAME
 R2987 'Q_RES_0402LF-0,5%,1/16W,EMPTY,CS00002JB13':;

SECTION_NUMBER 1
 '@T6G_MB_LIB.T6G(SCH_1):PAGE249_I17@PURE_QUANTA.Q_RES(CHIPS)':
 C_PATH='@t6g_mb_lib.t6g(sch_1):page249_i17@pure_quanta.q_res(chips)',
 P_PATH='@t6g_mb_lib.t6g(sch_1):page248_i17@pure_quanta.q_res(chips)',
 PATH='I17',
 DRAWING='@T6G_MB_LIB.T6G(SCH_1):PAGE249',
 WATTAGE='1/16W',
 TOLERANCE='5%',
 MATERIAL='EMPTY',
 PHYS_PAGE='248',
 XY='(-6525,2125)',
 ROT='0',
 VER='1',
 PACK_TYPE='0402LF',
 LOCATION='R2987',
 CDS_LIB='pure_quanta',
 CDS_PART_NAME='Q_RES_0402LF-0,5%,1/16W,EMPTY,CS00002JB13',
 PART_NUMBER='CS00002JB13',
 VALUE='0',
 PRIM_FILE='./archive_libs/logical/q_res/chips/chips.prt';

PART_NAME
 R2990 'Q_RES_0402LF-33.2,1%,1/16W,CHIP,CS03322FB03':;

SECTION_NUMBER 1
 '@T6G_MB_LIB.T6G(SCH_1):PAGE249_I38@PURE_QUANTA.Q_RES(CHIPS)':
 C_PATH='@t6g_mb_lib.t6g(sch_1):page249_i38@pure_quanta.q_res(chips)',
 P_PATH='@t6g_mb_lib.t6g(sch_1):page248_i38@pure_quanta.q_res(chips)',
 PATH='I38',
 DRAWING='@T6G_MB_LIB.T6G(SCH_1):PAGE249',
 WATTAGE='1/16W',
 TOLERANCE='1%',
 MATERIAL='CHIP',
 PHYS_PAGE='248',
 XY='(-4475,2650)',
 ROT='0',
 VER='1',
 PACK_TYPE='0402LF',
 LOCATION='R2990',
 CDS_LIB='pure_quanta',
 CDS_PART_NAME='Q_RES_0402LF-33.2,1%,1/16W,CHIP,CS03322FB03',
 PART_NUMBER='CS03322FB03',
 VALUE='33.2',
 PRIM_FILE='./archive_libs/logical/q_res/chips/chips.prt';

PART_NAME
 R2991 'Q_RES_0402LF-33.2,1%,1/16W,CHIP,CS03322FB03':;

SECTION_NUMBER 1
 '@T6G_MB_LIB.T6G(SCH_1):PAGE249_I39@PURE_QUANTA.Q_RES(CHIPS)':
 C_PATH='@t6g_mb_lib.t6g(sch_1):page249_i39@pure_quanta.q_res(chips)',
 P_PATH='@t6g_mb_lib.t6g(sch_1):page248_i39@pure_quanta.q_res(chips)',
 PATH='I39',
 DRAWING='@T6G_MB_LIB.T6G(SCH_1):PAGE249',
 WATTAGE='1/16W',
 TOLERANCE='1%',
 MATERIAL='CHIP',
 PHYS_PAGE='248',
 XY='(-4475,2550)',
 ROT='0',
 VER='1',
 PACK_TYPE='0402LF',
 LOCATION='R2991',
 CDS_LIB='pure_quanta',
 CDS_PART_NAME='Q_RES_0402LF-33.2,1%,1/16W,CHIP,CS03322FB03',
 PART_NUMBER='CS03322FB03',
 VALUE='33.2',
 PRIM_FILE='./archive_libs/logical/q_res/chips/chips.prt';

PART_NAME
 R2992 'Q_RES_0402LF-0,5%,1/16W,CHIP,CS00002JB13':;

SECTION_NUMBER 1
 '@T6G_MB_LIB.T6G(SCH_1):PAGE249_I12@PURE_QUANTA.Q_RES(CHIPS)':
 C_PATH='@t6g_mb_lib.t6g(sch_1):page249_i12@pure_quanta.q_res(chips)',
 P_PATH='@t6g_mb_lib.t6g(sch_1):page248_i12@pure_quanta.q_res(chips)',
 PATH='I12',
 DRAWING='@T6G_MB_LIB.T6G(SCH_1):PAGE249',
 WATTAGE='1/16W',
 TOLERANCE='5%',
 MATERIAL='CHIP',
 PHYS_PAGE='248',
 XY='(-7825,2750)',
 ROT='0',
 VER='1',
 PACK_TYPE='0402LF',
 LOCATION='R2992',
 CDS_LIB='pure_quanta',
 CDS_PART_NAME='Q_RES_0402LF-0,5%,1/16W,CHIP,CS00002JB13',
 PART_NUMBER='CS00002JB13',
 VALUE='0',
 PRIM_FILE='./archive_libs/logical/q_res/chips/chips.prt';

PART_NAME
 R2995 'Q_RES_0402LF-33.2,1%,1/16W,CHIP,CS03322FB03':;

SECTION_NUMBER 1
 '@T6G_MB_LIB.T6G(SCH_1):PAGE349_I91@PURE_QUANTA.Q_RES(CHIPS)':
 C_PATH='@t6g_mb_lib.t6g(sch_1):page349_i91@pure_quanta.q_res(chips)',
 P_PATH='@t6g_mb_lib.t6g(sch_1):page151_i91@pure_quanta.q_res(chips)',
 PATH='I91',
 DRAWING='@T6G_MB_LIB.T6G(SCH_1):PAGE349',
 WATTAGE='1/16W',
 TOLERANCE='1%',
 MATERIAL='CHIP',
 PHYS_PAGE='151',
 XY='(1925,6775)',
 ROT='0',
 VER='1',
 PACK_TYPE='0402LF',
 LOCATION='R2995',
 CDS_LIB='pure_quanta',
 CDS_PART_NAME='Q_RES_0402LF-33.2,1%,1/16W,CHIP,CS03322FB03',
 PART_NUMBER='CS03322FB03',
 VALUE='33.2',
 PRIM_FILE='./archive_libs/logical/q_res/chips/chips.prt';

PART_NAME
 R2996 'Q_RES_0402LF-33.2,1%,1/16W,CHIP,CS03322FB03':;

SECTION_NUMBER 1
 '@T6G_MB_LIB.T6G(SCH_1):PAGE349_I92@PURE_QUANTA.Q_RES(CHIPS)':
 C_PATH='@t6g_mb_lib.t6g(sch_1):page349_i92@pure_quanta.q_res(chips)',
 P_PATH='@t6g_mb_lib.t6g(sch_1):page151_i92@pure_quanta.q_res(chips)',
 PATH='I92',
 DRAWING='@T6G_MB_LIB.T6G(SCH_1):PAGE349',
 WATTAGE='1/16W',
 TOLERANCE='1%',
 MATERIAL='CHIP',
 PHYS_PAGE='151',
 XY='(1925,6725)',
 ROT='0',
 VER='1',
 PACK_TYPE='0402LF',
 LOCATION='R2996',
 CDS_LIB='pure_quanta',
 CDS_PART_NAME='Q_RES_0402LF-33.2,1%,1/16W,CHIP,CS03322FB03',
 PART_NUMBER='CS03322FB03',
 VALUE='33.2',
 PRIM_FILE='./archive_libs/logical/q_res/chips/chips.prt';

PART_NAME
 R2999 'Q_RES_0402LF-2.2K,5%,1/16W,EMPTY,CS22202JB07':;

SECTION_NUMBER 1
 '@T6G_MB_LIB.T6G(SCH_1):PAGE349_I124@PURE_QUANTA.Q_RES(CHIPS)':
 C_PATH='@t6g_mb_lib.t6g(sch_1):page349_i124@pure_quanta.q_res(chips)',
 P_PATH='@t6g_mb_lib.t6g(sch_1):page151_i124@pure_quanta.q_res(chips)',
 PATH='I124',
 DRAWING='@T6G_MB_LIB.T6G(SCH_1):PAGE349',
 WATTAGE='1/16W',
 TOLERANCE='5%',
 MATERIAL='EMPTY',
 PHYS_PAGE='151',
 XY='(4275,3100)',
 ROT='0',
 VER='1',
 PACK_TYPE='0402LF',
 LOCATION='R2999',
 CDS_LIB='pure_quanta',
 CDS_PART_NAME='Q_RES_0402LF-2.2K,5%,1/16W,EMPTY,CS22202JB07',
 PART_NUMBER='CS22202JB07',
 VALUE='2.2K',
 PRIM_FILE='./archive_libs/logical/q_res/chips/chips.prt';

PART_NAME
 R3004 'Q_RES_0402LF-2.2K,5%,1/16W,EMPTY,CS22202JB07':;

SECTION_NUMBER 1
 '@T6G_MB_LIB.T6G(SCH_1):PAGE349_I123@PURE_QUANTA.Q_RES(CHIPS)':
 C_PATH='@t6g_mb_lib.t6g(sch_1):page349_i123@pure_quanta.q_res(chips)',
 P_PATH='@t6g_mb_lib.t6g(sch_1):page151_i123@pure_quanta.q_res(chips)',
 PATH='I123',
 DRAWING='@T6G_MB_LIB.T6G(SCH_1):PAGE349',
 WATTAGE='1/16W',
 TOLERANCE='5%',
 MATERIAL='EMPTY',
 PHYS_PAGE='151',
 XY='(4275,3050)',
 ROT='0',
 VER='1',
 PACK_TYPE='0402LF',
 LOCATION='R3004',
 CDS_LIB='pure_quanta',
 CDS_PART_NAME='Q_RES_0402LF-2.2K,5%,1/16W,EMPTY,CS22202JB07',
 PART_NUMBER='CS22202JB07',
 VALUE='2.2K',
 PRIM_FILE='./archive_libs/logical/q_res/chips/chips.prt';

PART_NAME
 R3005 'Q_RES_0402LF-18K,1%,1/16W,CHIP,CS31802FB04':;

SECTION_NUMBER 1
 '@T6G_MB_LIB.T6G(SCH_1):PAGE369_I15@PURE_QUANTA.Q_RES(CHIPS)':
 C_PATH='@t6g_mb_lib.t6g(sch_1):page369_i15@pure_quanta.q_res(chips)',
 P_PATH='@t6g_mb_lib.t6g(sch_1):page257_i15@pure_quanta.q_res(chips)',
 PATH='I15',
 DRAWING='@T6G_MB_LIB.T6G(SCH_1):PAGE369',
 WATTAGE='1/16W',
 TOLERANCE='1%',
 MATERIAL='CHIP',
 PHYS_PAGE='257',
 XY='(-8900,3750)',
 ROT='0',
 VER='2',
 PACK_TYPE='0402LF',
 LOCATION='R3005',
 CDS_LIB='pure_quanta',
 CDS_PART_NAME='Q_RES_0402LF-18K,1%,1/16W,CHIP,CS31802FB04',
 PART_NUMBER='CS31802FB04',
 VALUE='18K',
 PRIM_FILE='./archive_libs/logical/q_res/chips/chips.prt';

PART_NAME
 R3028 'Q_RES_0402LF-100K,1%,1/16W,EMPTY,CS41002FB09':;

SECTION_NUMBER 1
 '@T6G_MB_LIB.T6G(SCH_1):PAGE333_I139@PURE_QUANTA.Q_RES(CHIPS)':
 C_PATH='@t6g_mb_lib.t6g(sch_1):page333_i139@pure_quanta.q_res(chips)',
 P_PATH='@t6g_mb_lib.t6g(sch_1):page127_i139@pure_quanta.q_res(chips)',
 PATH='I139',
 DRAWING='@T6G_MB_LIB.T6G(SCH_1):PAGE333',
 WATTAGE='1/16W',
 TOLERANCE='1%',
 MATERIAL='EMPTY',
 PHYS_PAGE='127',
 XY='(-4650,2825)',
 ROT='0',
 VER='2',
 PACK_TYPE='0402LF',
 LOCATION='R3028',
 CDS_LIB='pure_quanta',
 CDS_PART_NAME='Q_RES_0402LF-100K,1%,1/16W,EMPTY,CS41002FB09',
 PART_NUMBER='CS41002FB09',
 VALUE='100K',
 PRIM_FILE='./archive_libs/logical/q_res/chips/chips.prt';

PART_NAME
 R3029 'Q_RES_0402LF-4.7K,5%,1/16W,CHIP,CS24702JB10':;

SECTION_NUMBER 1
 '@T6G_MB_LIB.T6G(SCH_1):PAGE333_I144@PURE_QUANTA.Q_RES(CHIPS)':
 C_PATH='@t6g_mb_lib.t6g(sch_1):page333_i144@pure_quanta.q_res(chips)',
 P_PATH='@t6g_mb_lib.t6g(sch_1):page127_i144@pure_quanta.q_res(chips)',
 PATH='I144',
 DRAWING='@T6G_MB_LIB.T6G(SCH_1):PAGE333',
 WATTAGE='1/16W',
 TOLERANCE='5%',
 MATERIAL='CHIP',
 PHYS_PAGE='127',
 XY='(-3425,3550)',
 ROT='0',
 VER='2',
 PACK_TYPE='0402LF',
 LOCATION='R3029',
 CDS_LIB='pure_quanta',
 CDS_PART_NAME='Q_RES_0402LF-4.7K,5%,1/16W,CHIP,CS24702JB10',
 PART_NUMBER='CS24702JB10',
 VALUE='4.7K',
 PRIM_FILE='./archive_libs/logical/q_res/chips/chips.prt';

PART_NAME
 R3030 'Q_RES_0402LF-100K,1%,1/16W,CHIP,CS41002FB09':;

SECTION_NUMBER 1
 '@T6G_MB_LIB.T6G(SCH_1):PAGE333_I178@PURE_QUANTA.Q_RES(CHIPS)':
 C_PATH='@t6g_mb_lib.t6g(sch_1):page333_i178@pure_quanta.q_res(chips)',
 P_PATH='@t6g_mb_lib.t6g(sch_1):page127_i178@pure_quanta.q_res(chips)',
 PATH='I178',
 DRAWING='@T6G_MB_LIB.T6G(SCH_1):PAGE333',
 WATTAGE='1/16W',
 TOLERANCE='1%',
 MATERIAL='CHIP',
 PHYS_PAGE='127',
 XY='(-2500,3800)',
 ROT='2',
 VER='2',
 PACK_TYPE='0402LF',
 LOCATION='R3030',
 CDS_LIB='pure_quanta',
 CDS_PART_NAME='Q_RES_0402LF-100K,1%,1/16W,CHIP,CS41002FB09',
 PART_NUMBER='CS41002FB09',
 VALUE='100K',
 PRIM_FILE='./archive_libs/logical/q_res/chips/chips.prt';

PART_NAME
 R3032 'Q_RES_0402LF-100K,1%,1/16W,EMPTY,CS41002FB09':;

SECTION_NUMBER 1
 '@T6G_MB_LIB.T6G(SCH_1):PAGE333_I134@PURE_QUANTA.Q_RES(CHIPS)':
 C_PATH='@t6g_mb_lib.t6g(sch_1):page333_i134@pure_quanta.q_res(chips)',
 P_PATH='@t6g_mb_lib.t6g(sch_1):page127_i134@pure_quanta.q_res(chips)',
 PATH='I134',
 DRAWING='@T6G_MB_LIB.T6G(SCH_1):PAGE333',
 WATTAGE='1/16W',
 TOLERANCE='1%',
 MATERIAL='EMPTY',
 PHYS_PAGE='127',
 XY='(-100,4525)',
 ROT='0',
 VER='2',
 PACK_TYPE='0402LF',
 LOCATION='R3032',
 CDS_LIB='pure_quanta',
 CDS_PART_NAME='Q_RES_0402LF-100K,1%,1/16W,EMPTY,CS41002FB09',
 PART_NUMBER='CS41002FB09',
 VALUE='100K',
 PRIM_FILE='./archive_libs/logical/q_res/chips/chips.prt';

PART_NAME
 R3033 'Q_RES_0402LF-0,5%,1/16W,CHIP,CS00002JB13':;

SECTION_NUMBER 1
 '@T6G_MB_LIB.T6G(SCH_1):PAGE256_I170@PURE_QUANTA.Q_RES(CHIPS)':
 C_PATH='@t6g_mb_lib.t6g(sch_1):page256_i170@pure_quanta.q_res(chips)',
 P_PATH='@t6g_mb_lib.t6g(sch_1):page130_i170@pure_quanta.q_res(chips)',
 PATH='I170',
 DRAWING='@T6G_MB_LIB.T6G(SCH_1):PAGE256',
 WATTAGE='1/16W',
 TOLERANCE='5%',
 MATERIAL='CHIP',
 PHYS_PAGE='130',
 XY='(975,-1900)',
 ROT='0',
 VER='1',
 PACK_TYPE='0402LF',
 LOCATION='R3033',
 CDS_LIB='pure_quanta',
 CDS_PART_NAME='Q_RES_0402LF-0,5%,1/16W,CHIP,CS00002JB13',
 PART_NUMBER='CS00002JB13',
 VALUE='0',
 PRIM_FILE='./archive_libs/logical/q_res/chips/chips.prt';

PART_NAME
 R3034 'Q_RES_0402LF-4.7K,5%,1/16W,CHIP,CS24702JB10':;

SECTION_NUMBER 1
 '@T6G_MB_LIB.T6G(SCH_1):PAGE333_I129@PURE_QUANTA.Q_RES(CHIPS)':
 C_PATH='@t6g_mb_lib.t6g(sch_1):page333_i129@pure_quanta.q_res(chips)',
 P_PATH='@t6g_mb_lib.t6g(sch_1):page127_i129@pure_quanta.q_res(chips)',
 PATH='I129',
 DRAWING='@T6G_MB_LIB.T6G(SCH_1):PAGE333',
 WATTAGE='1/16W',
 TOLERANCE='5%',
 MATERIAL='CHIP',
 PHYS_PAGE='127',
 XY='(1125,5250)',
 ROT='0',
 VER='2',
 PACK_TYPE='0402LF',
 LOCATION='R3034',
 CDS_LIB='pure_quanta',
 CDS_PART_NAME='Q_RES_0402LF-4.7K,5%,1/16W,CHIP,CS24702JB10',
 PART_NUMBER='CS24702JB10',
 VALUE='4.7K',
 PRIM_FILE='./archive_libs/logical/q_res/chips/chips.prt';

PART_NAME
 R3035 'Q_RES_0402LF-100K,1%,1/16W,CHIP,CS41002FB09':;

SECTION_NUMBER 1
 '@T6G_MB_LIB.T6G(SCH_1):PAGE333_I179@PURE_QUANTA.Q_RES(CHIPS)':
 C_PATH='@t6g_mb_lib.t6g(sch_1):page333_i179@pure_quanta.q_res(chips)',
 P_PATH='@t6g_mb_lib.t6g(sch_1):page127_i179@pure_quanta.q_res(chips)',
 PATH='I179',
 DRAWING='@T6G_MB_LIB.T6G(SCH_1):PAGE333',
 SEC_TYPE='0402LF',
 WATTAGE='1/16W',
 TOLERANCE='1%',
 MATERIAL='CHIP',
 PHYS_PAGE='127',
 XY='(2050,5500)',
 ROT='2',
 VER='2',
 PACK_TYPE='0402LF',
 LOCATION='R3035',
 SEC='1',
 CDS_LIB='pure_quanta',
 CDS_PART_NAME='Q_RES_0402LF-100K,1%,1/16W,CHIP,CS41002FB09',
 PART_NUMBER='CS41002FB09',
 VALUE='100K',
 PRIM_FILE='./archive_libs/logical/q_res/chips/chips.prt';

PART_NAME
 R3036 'Q_RES_0402LF-33.2,1%,1/16W,CHIP,CS03322FB03':;

SECTION_NUMBER 1
 '@T6G_MB_LIB.T6G(SCH_1):PAGE256_I197@PURE_QUANTA.Q_RES(CHIPS)':
 C_PATH='@t6g_mb_lib.t6g(sch_1):page256_i197@pure_quanta.q_res(chips)',
 P_PATH='@t6g_mb_lib.t6g(sch_1):page130_i197@pure_quanta.q_res(chips)',
 PATH='I197',
 DRAWING='@T6G_MB_LIB.T6G(SCH_1):PAGE256',
 WATTAGE='1/16W',
 TOLERANCE='1%',
 MATERIAL='CHIP',
 PHYS_PAGE='130',
 XY='(3200,-1950)',
 ROT='0',
 VER='1',
 PACK_TYPE='0402LF',
 LOCATION='R3036',
 CDS_LIB='pure_quanta',
 CDS_PART_NAME='Q_RES_0402LF-33.2,1%,1/16W,CHIP,CS03322FB03',
 PART_NUMBER='CS03322FB03',
 VALUE='33.2',
 PRIM_FILE='./archive_libs/logical/q_res/chips/chips.prt';

PART_NAME
 R3047 'Q_RES_0402LF-0,5%,1/16W,CHIP,CS00002JB13':;

SECTION_NUMBER 1
 '@T6G_MB_LIB.T6G(SCH_1):PAGE368_I8@PURE_QUANTA.Q_RES(CHIPS)':
 C_PATH='@t6g_mb_lib.t6g(sch_1):page368_i8@pure_quanta.q_res(chips)',
 P_PATH='@t6g_mb_lib.t6g(sch_1):page253_i8@pure_quanta.q_res(chips)',
 PATH='I8',
 DRAWING='@T6G_MB_LIB.T6G(SCH_1):PAGE368',
 WATTAGE='1/16W',
 TOLERANCE='5%',
 MATERIAL='CHIP',
 PHYS_PAGE='253',
 XY='(-4550,2750)',
 ROT='0',
 VER='1',
 PACK_TYPE='0402LF',
 LOCATION='R3047',
 CDS_LIB='pure_quanta',
 CDS_PART_NAME='Q_RES_0402LF-0,5%,1/16W,CHIP,CS00002JB13',
 PART_NUMBER='CS00002JB13',
 VALUE='0',
 PRIM_FILE='./archive_libs/logical/q_res/chips/chips.prt';

PART_NAME
 R3048 'Q_RES_0402LF-0,5%,1/16W,CHIP,CS00002JB13':;

SECTION_NUMBER 1
 '@T6G_MB_LIB.T6G(SCH_1):PAGE368_I7@PURE_QUANTA.Q_RES(CHIPS)':
 C_PATH='@t6g_mb_lib.t6g(sch_1):page368_i7@pure_quanta.q_res(chips)',
 P_PATH='@t6g_mb_lib.t6g(sch_1):page253_i7@pure_quanta.q_res(chips)',
 PATH='I7',
 DRAWING='@T6G_MB_LIB.T6G(SCH_1):PAGE368',
 WATTAGE='1/16W',
 TOLERANCE='5%',
 MATERIAL='CHIP',
 PHYS_PAGE='253',
 XY='(-4550,2575)',
 ROT='0',
 VER='1',
 PACK_TYPE='0402LF',
 LOCATION='R3048',
 CDS_LIB='pure_quanta',
 CDS_PART_NAME='Q_RES_0402LF-0,5%,1/16W,CHIP,CS00002JB13',
 PART_NUMBER='CS00002JB13',
 VALUE='0',
 PRIM_FILE='./archive_libs/logical/q_res/chips/chips.prt';

PART_NAME
 R3062 'Q_RES_0402LF-2K,1%,1/16W,EMPTY,CS22002FB07':;

SECTION_NUMBER 1
 '@T6G_MB_LIB.T6G(SCH_1):PAGE349_I137@PURE_QUANTA.Q_RES(CHIPS)':
 C_PATH='@t6g_mb_lib.t6g(sch_1):page349_i137@pure_quanta.q_res(chips)',
 P_PATH='@t6g_mb_lib.t6g(sch_1):page151_i137@pure_quanta.q_res(chips)',
 PATH='I137',
 DRAWING='@T6G_MB_LIB.T6G(SCH_1):PAGE349',
 WATTAGE='1/16W',
 TOLERANCE='1%',
 MATERIAL='EMPTY',
 PHYS_PAGE='151',
 XY='(4275,5225)',
 ROT='0',
 VER='1',
 PACK_TYPE='0402LF',
 LOCATION='R3062',
 CDS_LIB='pure_quanta',
 CDS_PART_NAME='Q_RES_0402LF-2K,1%,1/16W,EMPTY,CS22002FB07',
 PART_NUMBER='CS22002FB07',
 VALUE='2K',
 PRIM_FILE='./archive_libs/logical/q_res/chips/chips.prt';

PART_NAME
 R3063 'Q_RES_0402LF-0,5%,1/16W,CHIP,CS00002JB13':;

SECTION_NUMBER 1
 '@T6G_MB_LIB.T6G(SCH_1):PAGE256_I171@PURE_QUANTA.Q_RES(CHIPS)':
 C_PATH='@t6g_mb_lib.t6g(sch_1):page256_i171@pure_quanta.q_res(chips)',
 P_PATH='@t6g_mb_lib.t6g(sch_1):page130_i171@pure_quanta.q_res(chips)',
 PATH='I171',
 DRAWING='@T6G_MB_LIB.T6G(SCH_1):PAGE256',
 WATTAGE='1/16W',
 TOLERANCE='5%',
 MATERIAL='CHIP',
 PHYS_PAGE='130',
 XY='(975,-2000)',
 ROT='0',
 VER='1',
 PACK_TYPE='0402LF',
 LOCATION='R3063',
 CDS_LIB='pure_quanta',
 CDS_PART_NAME='Q_RES_0402LF-0,5%,1/16W,CHIP,CS00002JB13',
 PART_NUMBER='CS00002JB13',
 VALUE='0',
 PRIM_FILE='./archive_libs/logical/q_res/chips/chips.prt';

PART_NAME
 R3066 'Q_RES_0402LF-33.2,1%,1/16W,CHIP,CS03322FB03':;

SECTION_NUMBER 1
 '@T6G_MB_LIB.T6G(SCH_1):PAGE80_I268@PURE_QUANTA.Q_RES(CHIPS)':
 C_PATH='@t6g_mb_lib.t6g(sch_1):page80_i268@pure_quanta.q_res(chips)',
 P_PATH='@t6g_mb_lib.t6g(sch_1):page81_i268@pure_quanta.q_res(chips)',
 PATH='I268',
 DRAWING='@T6G_MB_LIB.T6G(SCH_1):PAGE80',
 WATTAGE='1/16W',
 TOLERANCE='1%',
 MATERIAL='CHIP',
 PHYS_PAGE='81',
 XY='(-2300,1725)',
 ROT='0',
 VER='1',
 PACK_TYPE='0402LF',
 LOCATION='R3066',
 CDS_LIB='pure_quanta',
 CDS_PART_NAME='Q_RES_0402LF-33.2,1%,1/16W,CHIP,CS03322FB03',
 PART_NUMBER='CS03322FB03',
 VALUE='33.2',
 PRIM_FILE='./archive_libs/logical/q_res/chips/chips.prt';

PART_NAME
 R3069 'Q_RES_0402LF-130,1%,1/16W,CHIP,CS11302FB03':;

SECTION_NUMBER 1
 '@T6G_MB_LIB.T6G(SCH_1):PAGE254_I32@PURE_QUANTA.Q_RES(CHIPS)':
 C_PATH='@t6g_mb_lib.t6g(sch_1):page254_i32@pure_quanta.q_res(chips)',
 P_PATH='@t6g_mb_lib.t6g(sch_1):page254_i32@pure_quanta.q_res(chips)',
 PATH='I32',
 DRAWING='@T6G_MB_LIB.T6G(SCH_1):PAGE254',
 WATTAGE='1/16W',
 TOLERANCE='1%',
 MATERIAL='CHIP',
 PHYS_PAGE='254',
 XY='(-5375,1475)',
 ROT='0',
 VER='1',
 PACK_TYPE='0402LF',
 LOCATION='R3069',
 CDS_LIB='pure_quanta',
 CDS_PART_NAME='Q_RES_0402LF-130,1%,1/16W,CHIP,CS11302FB03',
 PART_NUMBER='CS11302FB03',
 VALUE='130',
 PRIM_FILE='./archive_libs/logical/q_res/chips/chips.prt';

PART_NAME
 R3071 'Q_RES_0402LF-130,1%,1/16W,CHIP,CS11302FB03':;

SECTION_NUMBER 1
 '@T6G_MB_LIB.T6G(SCH_1):PAGE254_I21@PURE_QUANTA.Q_RES(CHIPS)':
 C_PATH='@t6g_mb_lib.t6g(sch_1):page254_i21@pure_quanta.q_res(chips)',
 P_PATH='@t6g_mb_lib.t6g(sch_1):page254_i21@pure_quanta.q_res(chips)',
 PATH='I21',
 DRAWING='@T6G_MB_LIB.T6G(SCH_1):PAGE254',
 WATTAGE='1/16W',
 TOLERANCE='1%',
 MATERIAL='CHIP',
 PHYS_PAGE='254',
 XY='(-5250,4550)',
 ROT='0',
 VER='1',
 PACK_TYPE='0402LF',
 LOCATION='R3071',
 CDS_LIB='pure_quanta',
 CDS_PART_NAME='Q_RES_0402LF-130,1%,1/16W,CHIP,CS11302FB03',
 PART_NUMBER='CS11302FB03',
 VALUE='130',
 PRIM_FILE='./archive_libs/logical/q_res/chips/chips.prt';

PART_NAME
 R3074 'Q_RES_0402LF-130,1%,1/16W,CHIP,CS11302FB03':;

SECTION_NUMBER 1
 '@T6G_MB_LIB.T6G(SCH_1):PAGE254_I41@PURE_QUANTA.Q_RES(CHIPS)':
 C_PATH='@t6g_mb_lib.t6g(sch_1):page254_i41@pure_quanta.q_res(chips)',
 P_PATH='@t6g_mb_lib.t6g(sch_1):page254_i41@pure_quanta.q_res(chips)',
 PATH='I41',
 DRAWING='@T6G_MB_LIB.T6G(SCH_1):PAGE254',
 WATTAGE='1/16W',
 TOLERANCE='1%',
 MATERIAL='CHIP',
 PHYS_PAGE='254',
 XY='(-5200,3125)',
 ROT='0',
 VER='1',
 PACK_TYPE='0402LF',
 LOCATION='R3074',
 CDS_LIB='pure_quanta',
 CDS_PART_NAME='Q_RES_0402LF-130,1%,1/16W,CHIP,CS11302FB03',
 PART_NUMBER='CS11302FB03',
 VALUE='130',
 PRIM_FILE='./archive_libs/logical/q_res/chips/chips.prt';

PART_NAME
 R3075 'Q_RES_0402LF-130,1%,1/16W,CHIP,CS11302FB03':;

SECTION_NUMBER 1
 '@T6G_MB_LIB.T6G(SCH_1):PAGE254_I15@PURE_QUANTA.Q_RES(CHIPS)':
 C_PATH='@t6g_mb_lib.t6g(sch_1):page254_i15@pure_quanta.q_res(chips)',
 P_PATH='@t6g_mb_lib.t6g(sch_1):page254_i15@pure_quanta.q_res(chips)',
 PATH='I15',
 DRAWING='@T6G_MB_LIB.T6G(SCH_1):PAGE254',
 WATTAGE='1/16W',
 TOLERANCE='1%',
 MATERIAL='CHIP',
 PHYS_PAGE='254',
 XY='(-5375,5925)',
 ROT='0',
 VER='1',
 PACK_TYPE='0402LF',
 LOCATION='R3075',
 CDS_LIB='pure_quanta',
 CDS_PART_NAME='Q_RES_0402LF-130,1%,1/16W,CHIP,CS11302FB03',
 PART_NUMBER='CS11302FB03',
 VALUE='130',
 PRIM_FILE='./archive_libs/logical/q_res/chips/chips.prt';

PART_NAME
 R3086 'Q_RES_0402LF-130,1%,1/16W,CHIP,CS11302FB03':;

SECTION_NUMBER 1
 '@T6G_MB_LIB.T6G(SCH_1):PAGE374_I20@PURE_QUANTA.Q_RES(CHIPS)':
 C_PATH='@t6g_mb_lib.t6g(sch_1):page374_i20@pure_quanta.q_res(chips)',
 P_PATH='@t6g_mb_lib.t6g(sch_1):page255_i20@pure_quanta.q_res(chips)',
 PATH='I20',
 DRAWING='@T6G_MB_LIB.T6G(SCH_1):PAGE374',
 WATTAGE='1/16W',
 TOLERANCE='1%',
 MATERIAL='CHIP',
 PHYS_PAGE='255',
 XY='(-5550,5725)',
 ROT='0',
 VER='1',
 PACK_TYPE='0402LF',
 LOCATION='R3086',
 CDS_LIB='pure_quanta',
 CDS_PART_NAME='Q_RES_0402LF-130,1%,1/16W,CHIP,CS11302FB03',
 PART_NUMBER='CS11302FB03',
 VALUE='130',
 PRIM_FILE='./archive_libs/logical/q_res/chips/chips.prt';

PART_NAME
 R3087 'Q_RES_0402LF-130,1%,1/16W,CHIP,CS11302FB03':;

SECTION_NUMBER 1
 '@T6G_MB_LIB.T6G(SCH_1):PAGE374_I16@PURE_QUANTA.Q_RES(CHIPS)':
 C_PATH='@t6g_mb_lib.t6g(sch_1):page374_i16@pure_quanta.q_res(chips)',
 P_PATH='@t6g_mb_lib.t6g(sch_1):page255_i16@pure_quanta.q_res(chips)',
 PATH='I16',
 DRAWING='@T6G_MB_LIB.T6G(SCH_1):PAGE374',
 WATTAGE='1/16W',
 TOLERANCE='1%',
 MATERIAL='CHIP',
 PHYS_PAGE='255',
 XY='(-5525,4400)',
 ROT='0',
 VER='1',
 PACK_TYPE='0402LF',
 LOCATION='R3087',
 CDS_LIB='pure_quanta',
 CDS_PART_NAME='Q_RES_0402LF-130,1%,1/16W,CHIP,CS11302FB03',
 PART_NUMBER='CS11302FB03',
 VALUE='130',
 PRIM_FILE='./archive_libs/logical/q_res/chips/chips.prt';

PART_NAME
 R3088 'Q_RES_0402LF-130,1%,1/16W,CHIP,CS11302FB03':;

SECTION_NUMBER 1
 '@T6G_MB_LIB.T6G(SCH_1):PAGE374_I12@PURE_QUANTA.Q_RES(CHIPS)':
 C_PATH='@t6g_mb_lib.t6g(sch_1):page374_i12@pure_quanta.q_res(chips)',
 P_PATH='@t6g_mb_lib.t6g(sch_1):page255_i12@pure_quanta.q_res(chips)',
 PATH='I12',
 DRAWING='@T6G_MB_LIB.T6G(SCH_1):PAGE374',
 WATTAGE='1/16W',
 TOLERANCE='1%',
 MATERIAL='CHIP',
 PHYS_PAGE='255',
 XY='(-5525,1850)',
 ROT='0',
 VER='1',
 PACK_TYPE='0402LF',
 LOCATION='R3088',
 CDS_LIB='pure_quanta',
 CDS_PART_NAME='Q_RES_0402LF-130,1%,1/16W,CHIP,CS11302FB03',
 PART_NUMBER='CS11302FB03',
 VALUE='130',
 PRIM_FILE='./archive_libs/logical/q_res/chips/chips.prt';

PART_NAME
 R3089 'Q_RES_0402LF-130,1%,1/16W,CHIP,CS11302FB03':;

SECTION_NUMBER 1
 '@T6G_MB_LIB.T6G(SCH_1):PAGE374_I15@PURE_QUANTA.Q_RES(CHIPS)':
 C_PATH='@t6g_mb_lib.t6g(sch_1):page374_i15@pure_quanta.q_res(chips)',
 P_PATH='@t6g_mb_lib.t6g(sch_1):page255_i15@pure_quanta.q_res(chips)',
 PATH='I15',
 DRAWING='@T6G_MB_LIB.T6G(SCH_1):PAGE374',
 WATTAGE='1/16W',
 TOLERANCE='1%',
 MATERIAL='CHIP',
 PHYS_PAGE='255',
 XY='(-5475,3175)',
 ROT='0',
 VER='1',
 PACK_TYPE='0402LF',
 LOCATION='R3089',
 CDS_LIB='pure_quanta',
 CDS_PART_NAME='Q_RES_0402LF-130,1%,1/16W,CHIP,CS11302FB03',
 PART_NUMBER='CS11302FB03',
 VALUE='130',
 PRIM_FILE='./archive_libs/logical/q_res/chips/chips.prt';

PART_NAME
 R3090 'Q_RES_0402LF-130,1%,1/16W,CHIP,CS11302FB03':;

SECTION_NUMBER 1
 '@T6G_MB_LIB.T6G(SCH_1):PAGE374_I38@PURE_QUANTA.Q_RES(CHIPS)':
 C_PATH='@t6g_mb_lib.t6g(sch_1):page374_i38@pure_quanta.q_res(chips)',
 P_PATH='@t6g_mb_lib.t6g(sch_1):page255_i38@pure_quanta.q_res(chips)',
 PATH='I38',
 DRAWING='@T6G_MB_LIB.T6G(SCH_1):PAGE374',
 WATTAGE='1/16W',
 TOLERANCE='1%',
 MATERIAL='CHIP',
 PHYS_PAGE='255',
 XY='(-825,4400)',
 ROT='0',
 VER='1',
 PACK_TYPE='0402LF',
 LOCATION='R3090',
 CDS_LIB='pure_quanta',
 CDS_PART_NAME='Q_RES_0402LF-130,1%,1/16W,CHIP,CS11302FB03',
 PART_NUMBER='CS11302FB03',
 VALUE='130',
 PRIM_FILE='./archive_libs/logical/q_res/chips/chips.prt';

PART_NAME
 R3091 'Q_RES_0402LF-130,1%,1/16W,CHIP,CS11302FB03':;

SECTION_NUMBER 1
 '@T6G_MB_LIB.T6G(SCH_1):PAGE374_I37@PURE_QUANTA.Q_RES(CHIPS)':
 C_PATH='@t6g_mb_lib.t6g(sch_1):page374_i37@pure_quanta.q_res(chips)',
 P_PATH='@t6g_mb_lib.t6g(sch_1):page255_i37@pure_quanta.q_res(chips)',
 PATH='I37',
 DRAWING='@T6G_MB_LIB.T6G(SCH_1):PAGE374',
 WATTAGE='1/16W',
 TOLERANCE='1%',
 MATERIAL='CHIP',
 PHYS_PAGE='255',
 XY='(-825,3150)',
 ROT='0',
 VER='1',
 PACK_TYPE='0402LF',
 LOCATION='R3091',
 CDS_LIB='pure_quanta',
 CDS_PART_NAME='Q_RES_0402LF-130,1%,1/16W,CHIP,CS11302FB03',
 PART_NUMBER='CS11302FB03',
 VALUE='130',
 PRIM_FILE='./archive_libs/logical/q_res/chips/chips.prt';

PART_NAME
 R3092 'Q_RES_0402LF-130,1%,1/16W,CHIP,CS11302FB03':;

SECTION_NUMBER 1
 '@T6G_MB_LIB.T6G(SCH_1):PAGE374_I41@PURE_QUANTA.Q_RES(CHIPS)':
 C_PATH='@t6g_mb_lib.t6g(sch_1):page374_i41@pure_quanta.q_res(chips)',
 P_PATH='@t6g_mb_lib.t6g(sch_1):page255_i41@pure_quanta.q_res(chips)',
 PATH='I41',
 DRAWING='@T6G_MB_LIB.T6G(SCH_1):PAGE374',
 WATTAGE='1/16W',
 TOLERANCE='1%',
 MATERIAL='CHIP',
 PHYS_PAGE='255',
 XY='(-800,5725)',
 ROT='0',
 VER='1',
 PACK_TYPE='0402LF',
 LOCATION='R3092',
 CDS_LIB='pure_quanta',
 CDS_PART_NAME='Q_RES_0402LF-130,1%,1/16W,CHIP,CS11302FB03',
 PART_NUMBER='CS11302FB03',
 VALUE='130',
 PRIM_FILE='./archive_libs/logical/q_res/chips/chips.prt';

PART_NAME
 R3093 'Q_RES_0402LF-130,1%,1/16W,CHIP,CS11302FB03':;

SECTION_NUMBER 1
 '@T6G_MB_LIB.T6G(SCH_1):PAGE375_I20@PURE_QUANTA.Q_RES(CHIPS)':
 C_PATH='@t6g_mb_lib.t6g(sch_1):page375_i20@pure_quanta.q_res(chips)',
 P_PATH='@t6g_mb_lib.t6g(sch_1):page256_i20@pure_quanta.q_res(chips)',
 PATH='I20',
 DRAWING='@T6G_MB_LIB.T6G(SCH_1):PAGE375',
 WATTAGE='1/16W',
 TOLERANCE='1%',
 MATERIAL='CHIP',
 PHYS_PAGE='256',
 XY='(-5500,6000)',
 ROT='0',
 VER='1',
 PACK_TYPE='0402LF',
 LOCATION='R3093',
 CDS_LIB='pure_quanta',
 CDS_PART_NAME='Q_RES_0402LF-130,1%,1/16W,CHIP,CS11302FB03',
 PART_NUMBER='CS11302FB03',
 VALUE='130',
 PRIM_FILE='./archive_libs/logical/q_res/chips/chips.prt';

PART_NAME
 R3094 'Q_RES_0402LF-130,1%,1/16W,CHIP,CS11302FB03':;

SECTION_NUMBER 1
 '@T6G_MB_LIB.T6G(SCH_1):PAGE375_I18@PURE_QUANTA.Q_RES(CHIPS)':
 C_PATH='@t6g_mb_lib.t6g(sch_1):page375_i18@pure_quanta.q_res(chips)',
 P_PATH='@t6g_mb_lib.t6g(sch_1):page256_i18@pure_quanta.q_res(chips)',
 PATH='I18',
 DRAWING='@T6G_MB_LIB.T6G(SCH_1):PAGE375',
 WATTAGE='1/16W',
 TOLERANCE='1%',
 MATERIAL='CHIP',
 PHYS_PAGE='256',
 XY='(-5475,4675)',
 ROT='0',
 VER='1',
 PACK_TYPE='0402LF',
 LOCATION='R3094',
 CDS_LIB='pure_quanta',
 CDS_PART_NAME='Q_RES_0402LF-130,1%,1/16W,CHIP,CS11302FB03',
 PART_NUMBER='CS11302FB03',
 VALUE='130',
 PRIM_FILE='./archive_libs/logical/q_res/chips/chips.prt';

PART_NAME
 R3095 'Q_RES_0402LF-130,1%,1/16W,CHIP,CS11302FB03':;

SECTION_NUMBER 1
 '@T6G_MB_LIB.T6G(SCH_1):PAGE375_I15@PURE_QUANTA.Q_RES(CHIPS)':
 C_PATH='@t6g_mb_lib.t6g(sch_1):page375_i15@pure_quanta.q_res(chips)',
 P_PATH='@t6g_mb_lib.t6g(sch_1):page256_i15@pure_quanta.q_res(chips)',
 PATH='I15',
 DRAWING='@T6G_MB_LIB.T6G(SCH_1):PAGE375',
 WATTAGE='1/16W',
 TOLERANCE='1%',
 MATERIAL='CHIP',
 PHYS_PAGE='256',
 XY='(-5475,2125)',
 ROT='0',
 VER='1',
 PACK_TYPE='0402LF',
 LOCATION='R3095',
 CDS_LIB='pure_quanta',
 CDS_PART_NAME='Q_RES_0402LF-130,1%,1/16W,CHIP,CS11302FB03',
 PART_NUMBER='CS11302FB03',
 VALUE='130',
 PRIM_FILE='./archive_libs/logical/q_res/chips/chips.prt';

PART_NAME
 R3096 'Q_RES_0402LF-130,1%,1/16W,CHIP,CS11302FB03':;

SECTION_NUMBER 1
 '@T6G_MB_LIB.T6G(SCH_1):PAGE375_I16@PURE_QUANTA.Q_RES(CHIPS)':
 C_PATH='@t6g_mb_lib.t6g(sch_1):page375_i16@pure_quanta.q_res(chips)',
 P_PATH='@t6g_mb_lib.t6g(sch_1):page256_i16@pure_quanta.q_res(chips)',
 PATH='I16',
 DRAWING='@T6G_MB_LIB.T6G(SCH_1):PAGE375',
 WATTAGE='1/16W',
 TOLERANCE='1%',
 MATERIAL='CHIP',
 PHYS_PAGE='256',
 XY='(-5425,3450)',
 ROT='0',
 VER='1',
 PACK_TYPE='0402LF',
 LOCATION='R3096',
 CDS_LIB='pure_quanta',
 CDS_PART_NAME='Q_RES_0402LF-130,1%,1/16W,CHIP,CS11302FB03',
 PART_NUMBER='CS11302FB03',
 VALUE='130',
 PRIM_FILE='./archive_libs/logical/q_res/chips/chips.prt';

PART_NAME
 R3097 'Q_RES_0402LF-130,1%,1/16W,CHIP,CS11302FB03':;

SECTION_NUMBER 1
 '@T6G_MB_LIB.T6G(SCH_1):PAGE375_I38@PURE_QUANTA.Q_RES(CHIPS)':
 C_PATH='@t6g_mb_lib.t6g(sch_1):page375_i38@pure_quanta.q_res(chips)',
 P_PATH='@t6g_mb_lib.t6g(sch_1):page256_i38@pure_quanta.q_res(chips)',
 PATH='I38',
 DRAWING='@T6G_MB_LIB.T6G(SCH_1):PAGE375',
 WATTAGE='1/16W',
 TOLERANCE='1%',
 MATERIAL='CHIP',
 PHYS_PAGE='256',
 XY='(-875,4700)',
 ROT='0',
 VER='1',
 PACK_TYPE='0402LF',
 LOCATION='R3097',
 CDS_LIB='pure_quanta',
 CDS_PART_NAME='Q_RES_0402LF-130,1%,1/16W,CHIP,CS11302FB03',
 PART_NUMBER='CS11302FB03',
 VALUE='130',
 PRIM_FILE='./archive_libs/logical/q_res/chips/chips.prt';

PART_NAME
 R3099 'Q_RES_0402LF-130,1%,1/16W,CHIP,CS11302FB03':;

SECTION_NUMBER 1
 '@T6G_MB_LIB.T6G(SCH_1):PAGE375_I40@PURE_QUANTA.Q_RES(CHIPS)':
 C_PATH='@t6g_mb_lib.t6g(sch_1):page375_i40@pure_quanta.q_res(chips)',
 P_PATH='@t6g_mb_lib.t6g(sch_1):page256_i40@pure_quanta.q_res(chips)',
 PATH='I40',
 DRAWING='@T6G_MB_LIB.T6G(SCH_1):PAGE375',
 WATTAGE='1/16W',
 TOLERANCE='1%',
 MATERIAL='CHIP',
 PHYS_PAGE='256',
 XY='(-850,6025)',
 ROT='0',
 VER='1',
 PACK_TYPE='0402LF',
 LOCATION='R3099',
 CDS_LIB='pure_quanta',
 CDS_PART_NAME='Q_RES_0402LF-130,1%,1/16W,CHIP,CS11302FB03',
 PART_NUMBER='CS11302FB03',
 VALUE='130',
 PRIM_FILE='./archive_libs/logical/q_res/chips/chips.prt';

PART_NAME
 R3100 'Q_RES_0402LF-130,1%,1/16W,CHIP,CS11302FB03':;

SECTION_NUMBER 1
 '@T6G_MB_LIB.T6G(SCH_1):PAGE254_I8@PURE_QUANTA.Q_RES(CHIPS)':
 C_PATH='@t6g_mb_lib.t6g(sch_1):page254_i8@pure_quanta.q_res(chips)',
 P_PATH='@t6g_mb_lib.t6g(sch_1):page254_i8@pure_quanta.q_res(chips)',
 PATH='I8',
 DRAWING='@T6G_MB_LIB.T6G(SCH_1):PAGE254',
 WATTAGE='1/16W',
 TOLERANCE='1%',
 MATERIAL='CHIP',
 PHYS_PAGE='254',
 XY='(-1025,975)',
 ROT='0',
 VER='1',
 PACK_TYPE='0402LF',
 LOCATION='R3100',
 CDS_LIB='pure_quanta',
 CDS_PART_NAME='Q_RES_0402LF-130,1%,1/16W,CHIP,CS11302FB03',
 PART_NUMBER='CS11302FB03',
 VALUE='130',
 PRIM_FILE='./archive_libs/logical/q_res/chips/chips.prt';

PART_NAME
 R3102 'Q_RES_0402LF-470,1%,1/16W,CHIP,CS14702FB04':;

SECTION_NUMBER 1
 '@T6G_MB_LIB.T6G(SCH_1):PAGE254_I9@PURE_QUANTA.Q_RES(CHIPS)':
 C_PATH='@t6g_mb_lib.t6g(sch_1):page254_i9@pure_quanta.q_res(chips)',
 P_PATH='@t6g_mb_lib.t6g(sch_1):page254_i9@pure_quanta.q_res(chips)',
 PATH='I9',
 DRAWING='@T6G_MB_LIB.T6G(SCH_1):PAGE254',
 WATTAGE='1/16W',
 TOLERANCE='1%',
 MATERIAL='CHIP',
 PHYS_PAGE='254',
 XY='(-950,2200)',
 ROT='0',
 VER='1',
 PACK_TYPE='0402LF',
 LOCATION='R3102',
 CDS_LIB='pure_quanta',
 CDS_PART_NAME='Q_RES_0402LF-470,1%,1/16W,CHIP,CS14702FB04',
 PART_NUMBER='CS14702FB04',
 VALUE='470',
 PRIM_FILE='./archive_libs/logical/q_res/chips/chips.prt';

PART_NAME
 R3105 'Q_RES_0402LF-0,5%,1/16W,CHIP,CS00002JB13':;

SECTION_NUMBER 1
 '@T6G_MB_LIB.T6G(SCH_1):PAGE249_I44@PURE_QUANTA.Q_RES(CHIPS)':
 C_PATH='@t6g_mb_lib.t6g(sch_1):page249_i44@pure_quanta.q_res(chips)',
 P_PATH='@t6g_mb_lib.t6g(sch_1):page248_i44@pure_quanta.q_res(chips)',
 PATH='I44',
 DRAWING='@T6G_MB_LIB.T6G(SCH_1):PAGE249',
 WATTAGE='1/16W',
 TOLERANCE='5%',
 MATERIAL='CHIP',
 PHYS_PAGE='248',
 XY='(-7775,5375)',
 ROT='0',
 VER='1',
 PACK_TYPE='0402LF',
 LOCATION='R3105',
 CDS_LIB='pure_quanta',
 CDS_PART_NAME='Q_RES_0402LF-0,5%,1/16W,CHIP,CS00002JB13',
 PART_NUMBER='CS00002JB13',
 VALUE='0',
 PRIM_FILE='./archive_libs/logical/q_res/chips/chips.prt';

PART_NAME
 R3106 'Q_RES_0402LF-0,5%,1/16W,CHIP,CS00002JB13':;

SECTION_NUMBER 1
 '@T6G_MB_LIB.T6G(SCH_1):PAGE249_I43@PURE_QUANTA.Q_RES(CHIPS)':
 C_PATH='@t6g_mb_lib.t6g(sch_1):page249_i43@pure_quanta.q_res(chips)',
 P_PATH='@t6g_mb_lib.t6g(sch_1):page248_i43@pure_quanta.q_res(chips)',
 PATH='I43',
 DRAWING='@T6G_MB_LIB.T6G(SCH_1):PAGE249',
 WATTAGE='1/16W',
 TOLERANCE='5%',
 MATERIAL='CHIP',
 PHYS_PAGE='248',
 XY='(-7775,5275)',
 ROT='0',
 VER='1',
 PACK_TYPE='0402LF',
 LOCATION='R3106',
 CDS_LIB='pure_quanta',
 CDS_PART_NAME='Q_RES_0402LF-0,5%,1/16W,CHIP,CS00002JB13',
 PART_NUMBER='CS00002JB13',
 VALUE='0',
 PRIM_FILE='./archive_libs/logical/q_res/chips/chips.prt';

PART_NAME
 R3107 'Q_RES_0402LF-0,5%,1/16W,CHIP,CS00002JB13':;

SECTION_NUMBER 1
 '@T6G_MB_LIB.T6G(SCH_1):PAGE249_I13@PURE_QUANTA.Q_RES(CHIPS)':
 C_PATH='@t6g_mb_lib.t6g(sch_1):page249_i13@pure_quanta.q_res(chips)',
 P_PATH='@t6g_mb_lib.t6g(sch_1):page248_i13@pure_quanta.q_res(chips)',
 PATH='I13',
 DRAWING='@T6G_MB_LIB.T6G(SCH_1):PAGE249',
 WATTAGE='1/16W',
 TOLERANCE='5%',
 MATERIAL='CHIP',
 PHYS_PAGE='248',
 XY='(-7825,2650)',
 ROT='0',
 VER='1',
 PACK_TYPE='0402LF',
 LOCATION='R3107',
 CDS_LIB='pure_quanta',
 CDS_PART_NAME='Q_RES_0402LF-0,5%,1/16W,CHIP,CS00002JB13',
 PART_NUMBER='CS00002JB13',
 VALUE='0',
 PRIM_FILE='./archive_libs/logical/q_res/chips/chips.prt';

PART_NAME
 R3108 'Q_RES_0402LF-0,5%,1/16W,CHIP,CS00002JB13':;

SECTION_NUMBER 1
 '@T6G_MB_LIB.T6G(SCH_1):PAGE249_I14@PURE_QUANTA.Q_RES(CHIPS)':
 C_PATH='@t6g_mb_lib.t6g(sch_1):page249_i14@pure_quanta.q_res(chips)',
 P_PATH='@t6g_mb_lib.t6g(sch_1):page248_i14@pure_quanta.q_res(chips)',
 PATH='I14',
 DRAWING='@T6G_MB_LIB.T6G(SCH_1):PAGE249',
 WATTAGE='1/16W',
 TOLERANCE='5%',
 MATERIAL='CHIP',
 PHYS_PAGE='248',
 XY='(-7825,2550)',
 ROT='0',
 VER='1',
 PACK_TYPE='0402LF',
 LOCATION='R3108',
 CDS_LIB='pure_quanta',
 CDS_PART_NAME='Q_RES_0402LF-0,5%,1/16W,CHIP,CS00002JB13',
 PART_NUMBER='CS00002JB13',
 VALUE='0',
 PRIM_FILE='./archive_libs/logical/q_res/chips/chips.prt';

PART_NAME
 R3109 'Q_RES_0402LF-0,5%,1/16W,CHIP,CS00002JB13':;

SECTION_NUMBER 1
 '@T6G_MB_LIB.T6G(SCH_1):PAGE249_I35@PURE_QUANTA.Q_RES(CHIPS)':
 C_PATH='@t6g_mb_lib.t6g(sch_1):page249_i35@pure_quanta.q_res(chips)',
 P_PATH='@t6g_mb_lib.t6g(sch_1):page248_i35@pure_quanta.q_res(chips)',
 PATH='I35',
 DRAWING='@T6G_MB_LIB.T6G(SCH_1):PAGE249',
 WATTAGE='1/16W',
 TOLERANCE='5%',
 MATERIAL='CHIP',
 PHYS_PAGE='248',
 XY='(-5750,4000)',
 ROT='0',
 VER='1',
 PACK_TYPE='0402LF',
 LOCATION='R3109',
 CDS_LIB='pure_quanta',
 CDS_PART_NAME='Q_RES_0402LF-0,5%,1/16W,CHIP,CS00002JB13',
 PART_NUMBER='CS00002JB13',
 VALUE='0',
 PRIM_FILE='./archive_libs/logical/q_res/chips/chips.prt';

PART_NAME
 R3110 'Q_RES_0402LF-0,5%,1/16W,CHIP,CS00002JB13':;

SECTION_NUMBER 1
 '@T6G_MB_LIB.T6G(SCH_1):PAGE249_I34@PURE_QUANTA.Q_RES(CHIPS)':
 C_PATH='@t6g_mb_lib.t6g(sch_1):page249_i34@pure_quanta.q_res(chips)',
 P_PATH='@t6g_mb_lib.t6g(sch_1):page248_i34@pure_quanta.q_res(chips)',
 PATH='I34',
 DRAWING='@T6G_MB_LIB.T6G(SCH_1):PAGE249',
 WATTAGE='1/16W',
 TOLERANCE='5%',
 MATERIAL='CHIP',
 PHYS_PAGE='248',
 XY='(-5750,3900)',
 ROT='0',
 VER='1',
 PACK_TYPE='0402LF',
 LOCATION='R3110',
 CDS_LIB='pure_quanta',
 CDS_PART_NAME='Q_RES_0402LF-0,5%,1/16W,CHIP,CS00002JB13',
 PART_NUMBER='CS00002JB13',
 VALUE='0',
 PRIM_FILE='./archive_libs/logical/q_res/chips/chips.prt';

PART_NAME
 R3111 'Q_RES_0402LF-0,5%,1/16W,CHIP,CS00002JB13':;

SECTION_NUMBER 1
 '@T6G_MB_LIB.T6G(SCH_1):PAGE249_I85@PURE_QUANTA.Q_RES(CHIPS)':
 C_PATH='@t6g_mb_lib.t6g(sch_1):page249_i85@pure_quanta.q_res(chips)',
 P_PATH='@t6g_mb_lib.t6g(sch_1):page248_i85@pure_quanta.q_res(chips)',
 PATH='I85',
 DRAWING='@T6G_MB_LIB.T6G(SCH_1):PAGE249',
 WATTAGE='1/16W',
 TOLERANCE='5%',
 MATERIAL='CHIP',
 PHYS_PAGE='248',
 XY='(-5700,1125)',
 ROT='0',
 VER='1',
 PACK_TYPE='0402LF',
 LOCATION='R3111',
 CDS_LIB='pure_quanta',
 CDS_PART_NAME='Q_RES_0402LF-0,5%,1/16W,CHIP,CS00002JB13',
 PART_NUMBER='CS00002JB13',
 VALUE='0',
 PRIM_FILE='./archive_libs/logical/q_res/chips/chips.prt';

PART_NAME
 R3112 'Q_RES_0402LF-33.2,1%,1/16W,CHIP,CS03322FB03':;

SECTION_NUMBER 1
 '@T6G_MB_LIB.T6G(SCH_1):PAGE249_I25@PURE_QUANTA.Q_RES(CHIPS)':
 C_PATH='@t6g_mb_lib.t6g(sch_1):page249_i25@pure_quanta.q_res(chips)',
 P_PATH='@t6g_mb_lib.t6g(sch_1):page248_i25@pure_quanta.q_res(chips)',
 PATH='I25',
 DRAWING='@T6G_MB_LIB.T6G(SCH_1):PAGE249',
 WATTAGE='1/16W',
 TOLERANCE='1%',
 MATERIAL='CHIP',
 PHYS_PAGE='248',
 XY='(-5700,1225)',
 ROT='0',
 VER='1',
 PACK_TYPE='0402LF',
 LOCATION='R3112',
 CDS_LIB='pure_quanta',
 CDS_PART_NAME='Q_RES_0402LF-33.2,1%,1/16W,CHIP,CS03322FB03',
 PART_NUMBER='CS03322FB03',
 VALUE='33.2',
 PRIM_FILE='./archive_libs/logical/q_res/chips/chips.prt';

PART_NAME
 R3113 'Q_RES_0402LF-33.2,1%,1/16W,CHIP,CS03322FB03':;

SECTION_NUMBER 1
 '@T6G_MB_LIB.T6G(SCH_1):PAGE363_I463@PURE_QUANTA.Q_RES(CHIPS)':
 C_PATH='@t6g_mb_lib.t6g(sch_1):page363_i463@pure_quanta.q_res(chips)',
 P_PATH='@t6g_mb_lib.t6g(sch_1):page240_i463@pure_quanta.q_res(chips)',
 PATH='I463',
 DRAWING='@T6G_MB_LIB.T6G(SCH_1):PAGE363',
 WATTAGE='1/16W',
 TOLERANCE='1%',
 MATERIAL='CHIP',
 PHYS_PAGE='240',
 XY='(-4650,-3350)',
 ROT='0',
 VER='1',
 PACK_TYPE='0402LF',
 LOCATION='R3113',
 CDS_LIB='pure_quanta',
 CDS_PART_NAME='Q_RES_0402LF-33.2,1%,1/16W,CHIP,CS03322FB03',
 PART_NUMBER='CS03322FB03',
 VALUE='33.2',
 PRIM_FILE='./archive_libs/logical/q_res/chips/chips.prt';

PART_NAME
 R3114 'Q_RES_0402LF-33.2,1%,1/16W,CHIP,CS03322FB03':;

SECTION_NUMBER 1
 '@T6G_MB_LIB.T6G(SCH_1):PAGE363_I464@PURE_QUANTA.Q_RES(CHIPS)':
 C_PATH='@t6g_mb_lib.t6g(sch_1):page363_i464@pure_quanta.q_res(chips)',
 P_PATH='@t6g_mb_lib.t6g(sch_1):page240_i464@pure_quanta.q_res(chips)',
 PATH='I464',
 DRAWING='@T6G_MB_LIB.T6G(SCH_1):PAGE363',
 WATTAGE='1/16W',
 TOLERANCE='1%',
 MATERIAL='CHIP',
 PHYS_PAGE='240',
 XY='(-4650,-3450)',
 ROT='0',
 VER='1',
 PACK_TYPE='0402LF',
 LOCATION='R3114',
 CDS_LIB='pure_quanta',
 CDS_PART_NAME='Q_RES_0402LF-33.2,1%,1/16W,CHIP,CS03322FB03',
 PART_NUMBER='CS03322FB03',
 VALUE='33.2',
 PRIM_FILE='./archive_libs/logical/q_res/chips/chips.prt';

PART_NAME
 R3117 'Q_RES_0402LF-510K,5%,1/16W,EMPTY,CS45102JB03':;

SECTION_NUMBER 1
 '@T6G_MB_LIB.T6G(SCH_1):PAGE245_I4@PURE_QUANTA.Q_RES(CHIPS)':
 C_PATH='@t6g_mb_lib.t6g(sch_1):page245_i4@pure_quanta.q_res(chips)',
 P_PATH='@t6g_mb_lib.t6g(sch_1):page190_i4@pure_quanta.q_res(chips)',
 PATH='I4',
 DRAWING='@T6G_MB_LIB.T6G(SCH_1):PAGE245',
 WATTAGE='1/16W',
 TOLERANCE='5%',
 MATERIAL='EMPTY',
 PHYS_PAGE='190',
 XY='(-3300,-600)',
 ROT='0',
 VER='2',
 PACK_TYPE='0402LF',
 LOCATION='R3117',
 CDS_LIB='pure_quanta',
 CDS_PART_NAME='Q_RES_0402LF-510K,5%,1/16W,EMPTY,CS45102JB03',
 PART_NUMBER='CS45102JB03',
 VALUE='510K',
 PRIM_FILE='./archive_libs/logical/q_res/chips/chips.prt';

PART_NAME
 R3118 'Q_RES_0402LF-86.6K,1%,1/16W,EMPTY,CS38662FB05':;

SECTION_NUMBER 1
 '@T6G_MB_LIB.T6G(SCH_1):PAGE245_I2@PURE_QUANTA.Q_RES(CHIPS)':
 C_PATH='@t6g_mb_lib.t6g(sch_1):page245_i2@pure_quanta.q_res(chips)',
 P_PATH='@t6g_mb_lib.t6g(sch_1):page190_i2@pure_quanta.q_res(chips)',
 PATH='I2',
 DRAWING='@T6G_MB_LIB.T6G(SCH_1):PAGE245',
 WATTAGE='1/16W',
 TOLERANCE='1%',
 MATERIAL='EMPTY',
 PHYS_PAGE='190',
 XY='(-3300,-1175)',
 ROT='0',
 VER='2',
 PACK_TYPE='0402LF',
 LOCATION='R3118',
 CDS_LIB='pure_quanta',
 CDS_PART_NAME='Q_RES_0402LF-86.6K,1%,1/16W,EMPTY,CS38662FB05',
 PART_NUMBER='CS38662FB05',
 VALUE='86.6K',
 PRIM_FILE='./archive_libs/logical/q_res/chips/chips.prt';

PART_NAME
 R3132 'Q_RES_0402LF-100K,1%,1/16W,CHIP,CS41002FB09':;

SECTION_NUMBER 1
 '@T6G_MB_LIB.T6G(SCH_1):PAGE335_I6@PURE_QUANTA.Q_RES(CHIPS)':
 C_PATH='@t6g_mb_lib.t6g(sch_1):page335_i6@pure_quanta.q_res(chips)',
 P_PATH='@t6g_mb_lib.t6g(sch_1):page131_i6@pure_quanta.q_res(chips)',
 PATH='I6',
 DRAWING='@T6G_MB_LIB.T6G(SCH_1):PAGE335',
 WATTAGE='1/16W',
 TOLERANCE='1%',
 MATERIAL='CHIP',
 PHYS_PAGE='131',
 XY='(-4225,4425)',
 ROT='0',
 VER='1',
 PACK_TYPE='0402LF',
 LOCATION='R3132',
 CDS_LIB='pure_quanta',
 CDS_PART_NAME='Q_RES_0402LF-100K,1%,1/16W,CHIP,CS41002FB09',
 PART_NUMBER='CS41002FB09',
 VALUE='100K',
 PRIM_FILE='./archive_libs/logical/q_res/chips/chips.prt';

PART_NAME
 R3133 'Q_RES_0402LF-1K,1%,1/16W,CHIP,CS21002FB06':;

SECTION_NUMBER 1
 '@T6G_MB_LIB.T6G(SCH_1):PAGE343_I14@PURE_QUANTA.Q_RES(CHIPS)':
 C_PATH='@t6g_mb_lib.t6g(sch_1):page343_i14@pure_quanta.q_res(chips)',
 P_PATH='@t6g_mb_lib.t6g(sch_1):page140_i14@pure_quanta.q_res(chips)',
 PATH='I14',
 DRAWING='@T6G_MB_LIB.T6G(SCH_1):PAGE343',
 WATTAGE='1/16W',
 TOLERANCE='1%',
 MATERIAL='CHIP',
 PHYS_PAGE='140',
 XY='(-2350,5375)',
 ROT='0',
 VER='2',
 PACK_TYPE='0402LF',
 LOCATION='R3133',
 CDS_LIB='pure_quanta',
 CDS_PART_NAME='Q_RES_0402LF-1K,1%,1/16W,CHIP,CS21002FB06',
 PART_NUMBER='CS21002FB06',
 VALUE='1K',
 PRIM_FILE='./archive_libs/logical/q_res/chips/chips.prt';

PART_NAME
 R3134 'Q_RES_0402LF-1K,1%,1/16W,CHIP,CS21002FB06':;

SECTION_NUMBER 1
 '@T6G_MB_LIB.T6G(SCH_1):PAGE343_I4@PURE_QUANTA.Q_RES(CHIPS)':
 C_PATH='@t6g_mb_lib.t6g(sch_1):page343_i4@pure_quanta.q_res(chips)',
 P_PATH='@t6g_mb_lib.t6g(sch_1):page140_i4@pure_quanta.q_res(chips)',
 PATH='I4',
 DRAWING='@T6G_MB_LIB.T6G(SCH_1):PAGE343',
 WATTAGE='1/16W',
 TOLERANCE='1%',
 MATERIAL='CHIP',
 PHYS_PAGE='140',
 XY='(-2525,4475)',
 ROT='0',
 VER='2',
 PACK_TYPE='0402LF',
 LOCATION='R3134',
 CDS_LIB='pure_quanta',
 CDS_PART_NAME='Q_RES_0402LF-1K,1%,1/16W,CHIP,CS21002FB06',
 PART_NUMBER='CS21002FB06',
 VALUE='1K',
 PRIM_FILE='./archive_libs/logical/q_res/chips/chips.prt';

PART_NAME
 R3135 'Q_RES_0402LF-1K,1%,1/16W,CHIP,CS21002FB06':;

SECTION_NUMBER 1
 '@T6G_MB_LIB.T6G(SCH_1):PAGE343_I16@PURE_QUANTA.Q_RES(CHIPS)':
 C_PATH='@t6g_mb_lib.t6g(sch_1):page343_i16@pure_quanta.q_res(chips)',
 P_PATH='@t6g_mb_lib.t6g(sch_1):page140_i16@pure_quanta.q_res(chips)',
 PATH='I16',
 DRAWING='@T6G_MB_LIB.T6G(SCH_1):PAGE343',
 WATTAGE='1/16W',
 TOLERANCE='1%',
 MATERIAL='CHIP',
 PHYS_PAGE='140',
 XY='(-2075,5375)',
 ROT='0',
 VER='2',
 PACK_TYPE='0402LF',
 LOCATION='R3135',
 CDS_LIB='pure_quanta',
 CDS_PART_NAME='Q_RES_0402LF-1K,1%,1/16W,CHIP,CS21002FB06',
 PART_NUMBER='CS21002FB06',
 VALUE='1K',
 PRIM_FILE='./archive_libs/logical/q_res/chips/chips.prt';

PART_NAME
 R3136 'Q_RES_0402LF-1K,1%,1/16W,CHIP,CS21002FB06':;

SECTION_NUMBER 1
 '@T6G_MB_LIB.T6G(SCH_1):PAGE343_I6@PURE_QUANTA.Q_RES(CHIPS)':
 C_PATH='@t6g_mb_lib.t6g(sch_1):page343_i6@pure_quanta.q_res(chips)',
 P_PATH='@t6g_mb_lib.t6g(sch_1):page140_i6@pure_quanta.q_res(chips)',
 PATH='I6',
 DRAWING='@T6G_MB_LIB.T6G(SCH_1):PAGE343',
 WATTAGE='1/16W',
 TOLERANCE='1%',
 MATERIAL='CHIP',
 PHYS_PAGE='140',
 XY='(-2300,4475)',
 ROT='0',
 VER='2',
 PACK_TYPE='0402LF',
 LOCATION='R3136',
 CDS_LIB='pure_quanta',
 CDS_PART_NAME='Q_RES_0402LF-1K,1%,1/16W,CHIP,CS21002FB06',
 PART_NUMBER='CS21002FB06',
 VALUE='1K',
 PRIM_FILE='./archive_libs/logical/q_res/chips/chips.prt';

PART_NAME
 R3142 'Q_RES_0402LF-0,5%,1/16W,CHIP,CS00002JB13':;

SECTION_NUMBER 1
 '@T6G_MB_LIB.T6G(SCH_1):PAGE343_I59@PURE_QUANTA.Q_RES(CHIPS)':
 C_PATH='@t6g_mb_lib.t6g(sch_1):page343_i59@pure_quanta.q_res(chips)',
 P_PATH='@t6g_mb_lib.t6g(sch_1):page140_i59@pure_quanta.q_res(chips)',
 PATH='I59',
 DRAWING='@T6G_MB_LIB.T6G(SCH_1):PAGE343',
 WATTAGE='1/16W',
 TOLERANCE='5%',
 MATERIAL='CHIP',
 PHYS_PAGE='140',
 XY='(425,4525)',
 ROT='0',
 VER='1',
 PACK_TYPE='0402LF',
 LOCATION='R3142',
 CDS_LIB='pure_quanta',
 CDS_PART_NAME='Q_RES_0402LF-0,5%,1/16W,CHIP,CS00002JB13',
 PART_NUMBER='CS00002JB13',
 VALUE='0',
 PRIM_FILE='./archive_libs/logical/q_res/chips/chips.prt';

PART_NAME
 R3144 'Q_RES_0402LF-0,5%,1/16W,CHIP,CS00002JB13':
 ROOM='NIC_P12V_MAM_TIC_BOM1';

SECTION_NUMBER 1
 '@T6G_MB_LIB.T6G(SCH_1):PAGE338_I75@PURE_QUANTA.Q_RES(CHIPS)':
 C_PATH='@t6g_mb_lib.t6g(sch_1):page338_i75@pure_quanta.q_res(chips)',
 P_PATH='@t6g_mb_lib.t6g(sch_1):page134_i75@pure_quanta.q_res(chips)',
 PATH='I75',
 DRAWING='@T6G_MB_LIB.T6G(SCH_1):PAGE338',
 WATTAGE='1/16W',
 TOLERANCE='5%',
 MATERIAL='CHIP',
 PHYS_PAGE='134',
 XY='(9125,10725)',
 ROT='0',
 VER='1',
 PACK_TYPE='0402LF',
 LOCATION='R3144',
 CDS_LIB='pure_quanta',
 CDS_PART_NAME='Q_RES_0402LF-0,5%,1/16W,CHIP,CS00002JB13',
 ROOM='NIC_P12V_MAM_TIC_BOM1',
 PART_NUMBER='CS00002JB13',
 VALUE='0',
 PRIM_FILE='./archive_libs/logical/q_res/chips/chips.prt';

PART_NAME
 R3147 'Q_RES_0402LF-1K,1%,1/16W,CHIP,CS21002FB06':;

SECTION_NUMBER 1
 '@T6G_MB_LIB.T6G(SCH_1):PAGE343_I69@PURE_QUANTA.Q_RES(CHIPS)':
 C_PATH='@t6g_mb_lib.t6g(sch_1):page343_i69@pure_quanta.q_res(chips)',
 P_PATH='@t6g_mb_lib.t6g(sch_1):page140_i69@pure_quanta.q_res(chips)',
 PATH='I69',
 DRAWING='@T6G_MB_LIB.T6G(SCH_1):PAGE343',
 WATTAGE='1/16W',
 TOLERANCE='1%',
 MATERIAL='CHIP',
 PHYS_PAGE='140',
 XY='(1925,4950)',
 ROT='0',
 VER='2',
 PACK_TYPE='0402LF',
 LOCATION='R3147',
 CDS_LIB='pure_quanta',
 CDS_PART_NAME='Q_RES_0402LF-1K,1%,1/16W,CHIP,CS21002FB06',
 PART_NUMBER='CS21002FB06',
 VALUE='1K',
 PRIM_FILE='./archive_libs/logical/q_res/chips/chips.prt';

PART_NAME
 R3162 'Q_RES_0402LF-4.7K,1%,1/16W,CHIP,CS24702FB06':;

SECTION_NUMBER 1
 '@T6G_MB_LIB.T6G(SCH_1):PAGE341_I26@PURE_QUANTA.Q_RES(CHIPS)':
 C_PATH='@t6g_mb_lib.t6g(sch_1):page341_i26@pure_quanta.q_res(chips)',
 P_PATH='@t6g_mb_lib.t6g(sch_1):page137_i26@pure_quanta.q_res(chips)',
 PATH='I26',
 DRAWING='@T6G_MB_LIB.T6G(SCH_1):PAGE341',
 WATTAGE='1/16W',
 TOLERANCE='1%',
 MATERIAL='CHIP',
 PHYS_PAGE='137',
 XY='(275,300)',
 ROT='0',
 VER='2',
 PACK_TYPE='0402LF',
 LOCATION='R3162',
 CDS_LIB='pure_quanta',
 CDS_PART_NAME='Q_RES_0402LF-4.7K,1%,1/16W,CHIP,CS24702FB06',
 PART_NUMBER='CS24702FB06',
 VALUE='4.7K',
 PRIM_FILE='./archive_libs/logical/q_res/chips/chips.prt';

PART_NAME
 R3163 'Q_RES_0402LF-4.7K,1%,1/16W,EMPTY,CS24702FB06':;

SECTION_NUMBER 1
 '@T6G_MB_LIB.T6G(SCH_1):PAGE341_I2@PURE_QUANTA.Q_RES(CHIPS)':
 C_PATH='@t6g_mb_lib.t6g(sch_1):page341_i2@pure_quanta.q_res(chips)',
 P_PATH='@t6g_mb_lib.t6g(sch_1):page137_i2@pure_quanta.q_res(chips)',
 PATH='I2',
 DRAWING='@T6G_MB_LIB.T6G(SCH_1):PAGE341',
 WATTAGE='1/16W',
 TOLERANCE='1%',
 MATERIAL='EMPTY',
 PHYS_PAGE='137',
 XY='(275,-225)',
 ROT='0',
 VER='2',
 PACK_TYPE='0402LF',
 LOCATION='R3163',
 CDS_LIB='pure_quanta',
 CDS_PART_NAME='Q_RES_0402LF-4.7K,1%,1/16W,EMPTY,CS24702FB06',
 PART_NUMBER='CS24702FB06',
 VALUE='4.7K',
 PRIM_FILE='./archive_libs/logical/q_res/chips/chips.prt';

PART_NAME
 R3164 'Q_RES_0402LF-10K,1%,1/16W,CHIP,CS31002FB08':;

SECTION_NUMBER 1
 '@T6G_MB_LIB.T6G(SCH_1):PAGE341_I34@PURE_QUANTA.Q_RES(CHIPS)':
 C_PATH='@t6g_mb_lib.t6g(sch_1):page341_i34@pure_quanta.q_res(chips)',
 P_PATH='@t6g_mb_lib.t6g(sch_1):page137_i34@pure_quanta.q_res(chips)',
 PATH='I34',
 DRAWING='@T6G_MB_LIB.T6G(SCH_1):PAGE341',
 WATTAGE='1/16W',
 TOLERANCE='1%',
 MATERIAL='CHIP',
 PHYS_PAGE='137',
 XY='(725,2850)',
 ROT='0',
 VER='1',
 PACK_TYPE='0402LF',
 LOCATION='R3164',
 CDS_LIB='pure_quanta',
 CDS_PART_NAME='Q_RES_0402LF-10K,1%,1/16W,CHIP,CS31002FB08',
 PART_NUMBER='CS31002FB08',
 VALUE='10K',
 PRIM_FILE='./archive_libs/logical/q_res/chips/chips.prt';

PART_NAME
 R3165 'Q_RES_0402LF-10K,1%,1/16W,CHIP,CS31002FB08':;

SECTION_NUMBER 1
 '@T6G_MB_LIB.T6G(SCH_1):PAGE341_I32@PURE_QUANTA.Q_RES(CHIPS)':
 C_PATH='@t6g_mb_lib.t6g(sch_1):page341_i32@pure_quanta.q_res(chips)',
 P_PATH='@t6g_mb_lib.t6g(sch_1):page137_i32@pure_quanta.q_res(chips)',
 PATH='I32',
 DRAWING='@T6G_MB_LIB.T6G(SCH_1):PAGE341',
 WATTAGE='1/16W',
 TOLERANCE='1%',
 MATERIAL='CHIP',
 PHYS_PAGE='137',
 XY='(725,2750)',
 ROT='0',
 VER='1',
 PACK_TYPE='0402LF',
 LOCATION='R3165',
 CDS_LIB='pure_quanta',
 CDS_PART_NAME='Q_RES_0402LF-10K,1%,1/16W,CHIP,CS31002FB08',
 PART_NUMBER='CS31002FB08',
 VALUE='10K',
 PRIM_FILE='./archive_libs/logical/q_res/chips/chips.prt';

PART_NAME
 R3166 'Q_RES_0402LF-4.7K,1%,1/16W,EMPTY,CS24702FB06':;

SECTION_NUMBER 1
 '@T6G_MB_LIB.T6G(SCH_1):PAGE341_I28@PURE_QUANTA.Q_RES(CHIPS)':
 C_PATH='@t6g_mb_lib.t6g(sch_1):page341_i28@pure_quanta.q_res(chips)',
 P_PATH='@t6g_mb_lib.t6g(sch_1):page137_i28@pure_quanta.q_res(chips)',
 PATH='I28',
 DRAWING='@T6G_MB_LIB.T6G(SCH_1):PAGE341',
 WATTAGE='1/16W',
 TOLERANCE='1%',
 MATERIAL='EMPTY',
 PHYS_PAGE='137',
 XY='(750,300)',
 ROT='0',
 VER='2',
 PACK_TYPE='0402LF',
 LOCATION='R3166',
 CDS_LIB='pure_quanta',
 CDS_PART_NAME='Q_RES_0402LF-4.7K,1%,1/16W,EMPTY,CS24702FB06',
 PART_NUMBER='CS24702FB06',
 VALUE='4.7K',
 PRIM_FILE='./archive_libs/logical/q_res/chips/chips.prt';

PART_NAME
 R3167 'Q_RES_0402LF-4.7K,1%,1/16W,CHIP,CS24702FB06':;

SECTION_NUMBER 1
 '@T6G_MB_LIB.T6G(SCH_1):PAGE341_I3@PURE_QUANTA.Q_RES(CHIPS)':
 C_PATH='@t6g_mb_lib.t6g(sch_1):page341_i3@pure_quanta.q_res(chips)',
 P_PATH='@t6g_mb_lib.t6g(sch_1):page137_i3@pure_quanta.q_res(chips)',
 PATH='I3',
 DRAWING='@T6G_MB_LIB.T6G(SCH_1):PAGE341',
 WATTAGE='1/16W',
 TOLERANCE='1%',
 MATERIAL='CHIP',
 PHYS_PAGE='137',
 XY='(750,-225)',
 ROT='0',
 VER='2',
 PACK_TYPE='0402LF',
 LOCATION='R3167',
 CDS_LIB='pure_quanta',
 CDS_PART_NAME='Q_RES_0402LF-4.7K,1%,1/16W,CHIP,CS24702FB06',
 PART_NUMBER='CS24702FB06',
 VALUE='4.7K',
 PRIM_FILE='./archive_libs/logical/q_res/chips/chips.prt';

PART_NAME
 R3168 'Q_RES_0402LF-0,5%,1/16W,CHIP,CS00002JB13':;

SECTION_NUMBER 1
 '@T6G_MB_LIB.T6G(SCH_1):PAGE341_I86@PURE_QUANTA.Q_RES(CHIPS)':
 C_PATH='@t6g_mb_lib.t6g(sch_1):page341_i86@pure_quanta.q_res(chips)',
 P_PATH='@t6g_mb_lib.t6g(sch_1):page137_i86@pure_quanta.q_res(chips)',
 PATH='I86',
 DRAWING='@T6G_MB_LIB.T6G(SCH_1):PAGE341',
 WATTAGE='1/16W',
 TOLERANCE='5%',
 MATERIAL='CHIP',
 PHYS_PAGE='137',
 XY='(1950,5075)',
 ROT='0',
 VER='1',
 PACK_TYPE='0402LF',
 LOCATION='R3168',
 CDS_LIB='pure_quanta',
 CDS_PART_NAME='Q_RES_0402LF-0,5%,1/16W,CHIP,CS00002JB13',
 PART_NUMBER='CS00002JB13',
 VALUE='0',
 PRIM_FILE='./archive_libs/logical/q_res/chips/chips.prt';

PART_NAME
 R3169 'Q_RES_0402LF-0,5%,1/16W,CHIP,CS00002JB13':;

SECTION_NUMBER 1
 '@T6G_MB_LIB.T6G(SCH_1):PAGE341_I43@PURE_QUANTA.Q_RES(CHIPS)':
 C_PATH='@t6g_mb_lib.t6g(sch_1):page341_i43@pure_quanta.q_res(chips)',
 P_PATH='@t6g_mb_lib.t6g(sch_1):page137_i43@pure_quanta.q_res(chips)',
 PATH='I43',
 DRAWING='@T6G_MB_LIB.T6G(SCH_1):PAGE341',
 WATTAGE='1/16W',
 TOLERANCE='5%',
 MATERIAL='CHIP',
 PHYS_PAGE='137',
 XY='(1950,4025)',
 ROT='0',
 VER='1',
 PACK_TYPE='0402LF',
 LOCATION='R3169',
 CDS_LIB='pure_quanta',
 CDS_PART_NAME='Q_RES_0402LF-0,5%,1/16W,CHIP,CS00002JB13',
 PART_NUMBER='CS00002JB13',
 VALUE='0',
 PRIM_FILE='./archive_libs/logical/q_res/chips/chips.prt';

PART_NAME
 R3170 'Q_RES_0402LF-0,5%,1/16W,CHIP,CS00002JB13':;

SECTION_NUMBER 1
 '@T6G_MB_LIB.T6G(SCH_1):PAGE341_I44@PURE_QUANTA.Q_RES(CHIPS)':
 C_PATH='@t6g_mb_lib.t6g(sch_1):page341_i44@pure_quanta.q_res(chips)',
 P_PATH='@t6g_mb_lib.t6g(sch_1):page137_i44@pure_quanta.q_res(chips)',
 PATH='I44',
 DRAWING='@T6G_MB_LIB.T6G(SCH_1):PAGE341',
 WATTAGE='1/16W',
 TOLERANCE='5%',
 MATERIAL='CHIP',
 PHYS_PAGE='137',
 XY='(1950,3975)',
 ROT='0',
 VER='1',
 PACK_TYPE='0402LF',
 LOCATION='R3170',
 CDS_LIB='pure_quanta',
 CDS_PART_NAME='Q_RES_0402LF-0,5%,1/16W,CHIP,CS00002JB13',
 PART_NUMBER='CS00002JB13',
 VALUE='0',
 PRIM_FILE='./archive_libs/logical/q_res/chips/chips.prt';

PART_NAME
 R3171 'Q_RES_0402LF-0,5%,1/16W,CHIP,CS00002JB13':;

SECTION_NUMBER 1
 '@T6G_MB_LIB.T6G(SCH_1):PAGE341_I45@PURE_QUANTA.Q_RES(CHIPS)':
 C_PATH='@t6g_mb_lib.t6g(sch_1):page341_i45@pure_quanta.q_res(chips)',
 P_PATH='@t6g_mb_lib.t6g(sch_1):page137_i45@pure_quanta.q_res(chips)',
 PATH='I45',
 DRAWING='@T6G_MB_LIB.T6G(SCH_1):PAGE341',
 WATTAGE='1/16W',
 TOLERANCE='5%',
 MATERIAL='CHIP',
 PHYS_PAGE='137',
 XY='(1950,3925)',
 ROT='0',
 VER='1',
 PACK_TYPE='0402LF',
 LOCATION='R3171',
 CDS_LIB='pure_quanta',
 CDS_PART_NAME='Q_RES_0402LF-0,5%,1/16W,CHIP,CS00002JB13',
 PART_NUMBER='CS00002JB13',
 VALUE='0',
 PRIM_FILE='./archive_libs/logical/q_res/chips/chips.prt';

PART_NAME
 R3172 'Q_RES_0402LF-0,5%,1/16W,CHIP,CS00002JB13':;

SECTION_NUMBER 1
 '@T6G_MB_LIB.T6G(SCH_1):PAGE341_I42@PURE_QUANTA.Q_RES(CHIPS)':
 C_PATH='@t6g_mb_lib.t6g(sch_1):page341_i42@pure_quanta.q_res(chips)',
 P_PATH='@t6g_mb_lib.t6g(sch_1):page137_i42@pure_quanta.q_res(chips)',
 PATH='I42',
 DRAWING='@T6G_MB_LIB.T6G(SCH_1):PAGE341',
 WATTAGE='1/16W',
 TOLERANCE='5%',
 MATERIAL='CHIP',
 PHYS_PAGE='137',
 XY='(1950,3775)',
 ROT='0',
 VER='1',
 PACK_TYPE='0402LF',
 LOCATION='R3172',
 CDS_LIB='pure_quanta',
 CDS_PART_NAME='Q_RES_0402LF-0,5%,1/16W,CHIP,CS00002JB13',
 PART_NUMBER='CS00002JB13',
 VALUE='0',
 PRIM_FILE='./archive_libs/logical/q_res/chips/chips.prt';

PART_NAME
 R3173 'Q_RES_0402LF-1K,1%,1/16W,CHIP,CS21002FB06':;

SECTION_NUMBER 1
 '@T6G_MB_LIB.T6G(SCH_1):PAGE341_I10@PURE_QUANTA.Q_RES(CHIPS)':
 C_PATH='@t6g_mb_lib.t6g(sch_1):page341_i10@pure_quanta.q_res(chips)',
 P_PATH='@t6g_mb_lib.t6g(sch_1):page137_i10@pure_quanta.q_res(chips)',
 PATH='I10',
 DRAWING='@T6G_MB_LIB.T6G(SCH_1):PAGE341',
 WATTAGE='1/16W',
 TOLERANCE='1%',
 MATERIAL='CHIP',
 PHYS_PAGE='137',
 XY='(3650,-100)',
 ROT='0',
 VER='1',
 PACK_TYPE='0402LF',
 LOCATION='R3173',
 CDS_LIB='pure_quanta',
 CDS_PART_NAME='Q_RES_0402LF-1K,1%,1/16W,CHIP,CS21002FB06',
 PART_NUMBER='CS21002FB06',
 VALUE='1K',
 PRIM_FILE='./archive_libs/logical/q_res/chips/chips.prt';

PART_NAME
 R3174 'Q_RES_0402LF-10K,1%,1/16W,CHIP,CS31002FB08':;

SECTION_NUMBER 1
 '@T6G_MB_LIB.T6G(SCH_1):PAGE341_I9@PURE_QUANTA.Q_RES(CHIPS)':
 C_PATH='@t6g_mb_lib.t6g(sch_1):page341_i9@pure_quanta.q_res(chips)',
 P_PATH='@t6g_mb_lib.t6g(sch_1):page137_i9@pure_quanta.q_res(chips)',
 PATH='I9',
 DRAWING='@T6G_MB_LIB.T6G(SCH_1):PAGE341',
 WATTAGE='1/16W',
 TOLERANCE='1%',
 MATERIAL='CHIP',
 PHYS_PAGE='137',
 XY='(3650,-275)',
 ROT='0',
 VER='1',
 PACK_TYPE='0402LF',
 LOCATION='R3174',
 CDS_LIB='pure_quanta',
 CDS_PART_NAME='Q_RES_0402LF-10K,1%,1/16W,CHIP,CS31002FB08',
 PART_NUMBER='CS31002FB08',
 VALUE='10K',
 PRIM_FILE='./archive_libs/logical/q_res/chips/chips.prt';

PART_NAME
 R3175 'Q_RES_0402LF-10K,1%,1/16W,CHIP,CS31002FB08':;

SECTION_NUMBER 1
 '@T6G_MB_LIB.T6G(SCH_1):PAGE341_I11@PURE_QUANTA.Q_RES(CHIPS)':
 C_PATH='@t6g_mb_lib.t6g(sch_1):page341_i11@pure_quanta.q_res(chips)',
 P_PATH='@t6g_mb_lib.t6g(sch_1):page137_i11@pure_quanta.q_res(chips)',
 PATH='I11',
 DRAWING='@T6G_MB_LIB.T6G(SCH_1):PAGE341',
 WATTAGE='1/16W',
 TOLERANCE='1%',
 MATERIAL='CHIP',
 PHYS_PAGE='137',
 XY='(3675,-625)',
 ROT='0',
 VER='1',
 PACK_TYPE='0402LF',
 LOCATION='R3175',
 CDS_LIB='pure_quanta',
 CDS_PART_NAME='Q_RES_0402LF-10K,1%,1/16W,CHIP,CS31002FB08',
 PART_NUMBER='CS31002FB08',
 VALUE='10K',
 PRIM_FILE='./archive_libs/logical/q_res/chips/chips.prt';

PART_NAME
 R3176 'Q_RES_0402LF-1K,1%,1/16W,CHIP,CS21002FB06':;

SECTION_NUMBER 1
 '@T6G_MB_LIB.T6G(SCH_1):PAGE341_I12@PURE_QUANTA.Q_RES(CHIPS)':
 C_PATH='@t6g_mb_lib.t6g(sch_1):page341_i12@pure_quanta.q_res(chips)',
 P_PATH='@t6g_mb_lib.t6g(sch_1):page137_i12@pure_quanta.q_res(chips)',
 PATH='I12',
 DRAWING='@T6G_MB_LIB.T6G(SCH_1):PAGE341',
 WATTAGE='1/16W',
 TOLERANCE='1%',
 MATERIAL='CHIP',
 PHYS_PAGE='137',
 XY='(3675,-450)',
 ROT='0',
 VER='1',
 PACK_TYPE='0402LF',
 LOCATION='R3176',
 CDS_LIB='pure_quanta',
 CDS_PART_NAME='Q_RES_0402LF-1K,1%,1/16W,CHIP,CS21002FB06',
 PART_NUMBER='CS21002FB06',
 VALUE='1K',
 PRIM_FILE='./archive_libs/logical/q_res/chips/chips.prt';

PART_NAME
 R3177 'Q_RES_0402LF-0,5%,1/16W,CHIP,CS00002JB13':;

SECTION_NUMBER 1
 '@T6G_MB_LIB.T6G(SCH_1):PAGE341_I136@PURE_QUANTA.Q_RES(CHIPS)':
 C_PATH='@t6g_mb_lib.t6g(sch_1):page341_i136@pure_quanta.q_res(chips)',
 P_PATH='@t6g_mb_lib.t6g(sch_1):page137_i136@pure_quanta.q_res(chips)',
 PATH='I136',
 DRAWING='@T6G_MB_LIB.T6G(SCH_1):PAGE341',
 WATTAGE='1/16W',
 TOLERANCE='5%',
 MATERIAL='CHIP',
 PHYS_PAGE='137',
 XY='(6850,775)',
 ROT='0',
 VER='1',
 PACK_TYPE='0402LF',
 LOCATION='R3177',
 CDS_LIB='pure_quanta',
 CDS_PART_NAME='Q_RES_0402LF-0,5%,1/16W,CHIP,CS00002JB13',
 PART_NUMBER='CS00002JB13',
 VALUE='0',
 PRIM_FILE='./archive_libs/logical/q_res/chips/chips.prt';

PART_NAME
 R3178 'Q_RES_0402LF-0,5%,1/16W,CHIP,CS00002JB13':;

SECTION_NUMBER 1
 '@T6G_MB_LIB.T6G(SCH_1):PAGE341_I135@PURE_QUANTA.Q_RES(CHIPS)':
 C_PATH='@t6g_mb_lib.t6g(sch_1):page341_i135@pure_quanta.q_res(chips)',
 P_PATH='@t6g_mb_lib.t6g(sch_1):page137_i135@pure_quanta.q_res(chips)',
 PATH='I135',
 DRAWING='@T6G_MB_LIB.T6G(SCH_1):PAGE341',
 WATTAGE='1/16W',
 TOLERANCE='5%',
 MATERIAL='CHIP',
 PHYS_PAGE='137',
 XY='(6850,725)',
 ROT='0',
 VER='1',
 PACK_TYPE='0402LF',
 LOCATION='R3178',
 CDS_LIB='pure_quanta',
 CDS_PART_NAME='Q_RES_0402LF-0,5%,1/16W,CHIP,CS00002JB13',
 PART_NUMBER='CS00002JB13',
 VALUE='0',
 PRIM_FILE='./archive_libs/logical/q_res/chips/chips.prt';

PART_NAME
 R3180 'Q_RES_0402LF-0,5%,1/16W,CHIP,CS00002JB13':;

SECTION_NUMBER 1
 '@T6G_MB_LIB.T6G(SCH_1):PAGE341_I150@PURE_QUANTA.Q_RES(CHIPS)':
 C_PATH='@t6g_mb_lib.t6g(sch_1):page341_i150@pure_quanta.q_res(chips)',
 P_PATH='@t6g_mb_lib.t6g(sch_1):page137_i150@pure_quanta.q_res(chips)',
 PATH='I150',
 DRAWING='@T6G_MB_LIB.T6G(SCH_1):PAGE341',
 WATTAGE='1/16W',
 TOLERANCE='5%',
 MATERIAL='CHIP',
 PHYS_PAGE='137',
 XY='(7950,3625)',
 ROT='0',
 VER='2',
 PACK_TYPE='0402LF',
 LOCATION='R3180',
 CDS_LIB='pure_quanta',
 CDS_PART_NAME='Q_RES_0402LF-0,5%,1/16W,CHIP,CS00002JB13',
 PART_NUMBER='CS00002JB13',
 VALUE='0',
 PRIM_FILE='./archive_libs/logical/q_res/chips/chips.prt';

PART_NAME
 R3181 'Q_RES_0402LF-27.4,1%,1/16W,CHIP,CS02742FB03':;

SECTION_NUMBER 1
 '@T6G_MB_LIB.T6G(SCH_1):PAGE337_I20@PURE_QUANTA.Q_RES(CHIPS)':
 C_PATH='@t6g_mb_lib.t6g(sch_1):page337_i20@pure_quanta.q_res(chips)',
 P_PATH='@t6g_mb_lib.t6g(sch_1):page133_i20@pure_quanta.q_res(chips)',
 PATH='I20',
 DRAWING='@T6G_MB_LIB.T6G(SCH_1):PAGE337',
 WATTAGE='1/16W',
 TOLERANCE='1%',
 MATERIAL='CHIP',
 PHYS_PAGE='133',
 XY='(-5550,2425)',
 ROT='0',
 VER='1',
 PACK_TYPE='0402LF',
 LOCATION='R3181',
 CDS_LIB='pure_quanta',
 CDS_PART_NAME='Q_RES_0402LF-27.4,1%,1/16W,CHIP,CS02742FB03',
 PART_NUMBER='CS02742FB03',
 VALUE='27.4',
 PRIM_FILE='./archive_libs/logical/q_res/chips/chips.prt';

PART_NAME
 R3182 'Q_RES_0402LF-10K,1%,1/16W,CHIP,CS31002FB08':;

SECTION_NUMBER 1
 '@T6G_MB_LIB.T6G(SCH_1):PAGE342_I3@PURE_QUANTA.Q_RES(CHIPS)':
 C_PATH='@t6g_mb_lib.t6g(sch_1):page342_i3@pure_quanta.q_res(chips)',
 P_PATH='@t6g_mb_lib.t6g(sch_1):page139_i3@pure_quanta.q_res(chips)',
 PATH='I3',
 DRAWING='@T6G_MB_LIB.T6G(SCH_1):PAGE342',
 WATTAGE='1/16W',
 TOLERANCE='1%',
 MATERIAL='CHIP',
 PHYS_PAGE='139',
 XY='(3350,-1375)',
 ROT='2',
 VER='2',
 PACK_TYPE='0402LF',
 LOCATION='R3182',
 CDS_LIB='pure_quanta',
 CDS_PART_NAME='Q_RES_0402LF-10K,1%,1/16W,CHIP,CS31002FB08',
 PART_NUMBER='CS31002FB08',
 VALUE='10K',
 PRIM_FILE='./archive_libs/logical/q_res/chips/chips.prt';

PART_NAME
 R3183 'Q_RES_0402LF-10K,1%,1/16W,CHIP,CS31002FB08':;

SECTION_NUMBER 1
 '@T6G_MB_LIB.T6G(SCH_1):PAGE342_I4@PURE_QUANTA.Q_RES(CHIPS)':
 C_PATH='@t6g_mb_lib.t6g(sch_1):page342_i4@pure_quanta.q_res(chips)',
 P_PATH='@t6g_mb_lib.t6g(sch_1):page139_i4@pure_quanta.q_res(chips)',
 PATH='I4',
 DRAWING='@T6G_MB_LIB.T6G(SCH_1):PAGE342',
 WATTAGE='1/16W',
 TOLERANCE='1%',
 MATERIAL='CHIP',
 PHYS_PAGE='139',
 XY='(3625,-1375)',
 ROT='0',
 VER='2',
 PACK_TYPE='0402LF',
 LOCATION='R3183',
 CDS_LIB='pure_quanta',
 CDS_PART_NAME='Q_RES_0402LF-10K,1%,1/16W,CHIP,CS31002FB08',
 PART_NUMBER='CS31002FB08',
 VALUE='10K',
 PRIM_FILE='./archive_libs/logical/q_res/chips/chips.prt';

PART_NAME
 R3184 'Q_RES_0402LF-4.7K,1%,1/16W,CHIP,CS24702FB06':;

SECTION_NUMBER 1
 '@T6G_MB_LIB.T6G(SCH_1):PAGE342_I18@PURE_QUANTA.Q_RES(CHIPS)':
 C_PATH='@t6g_mb_lib.t6g(sch_1):page342_i18@pure_quanta.q_res(chips)',
 P_PATH='@t6g_mb_lib.t6g(sch_1):page139_i18@pure_quanta.q_res(chips)',
 PATH='I18',
 DRAWING='@T6G_MB_LIB.T6G(SCH_1):PAGE342',
 WATTAGE='1/16W',
 TOLERANCE='1%',
 MATERIAL='CHIP',
 PHYS_PAGE='139',
 XY='(5975,-1275)',
 ROT='0',
 VER='2',
 PACK_TYPE='0402LF',
 LOCATION='R3184',
 CDS_LIB='pure_quanta',
 CDS_PART_NAME='Q_RES_0402LF-4.7K,1%,1/16W,CHIP,CS24702FB06',
 PART_NUMBER='CS24702FB06',
 VALUE='4.7K',
 PRIM_FILE='./archive_libs/logical/q_res/chips/chips.prt';

PART_NAME
 R3185 'Q_RES_0402LF-33.2,1%,1/16W,CHIP,CS03322FB03':;

SECTION_NUMBER 1
 '@T6G_MB_LIB.T6G(SCH_1):PAGE342_I29@PURE_QUANTA.Q_RES(CHIPS)':
 C_PATH='@t6g_mb_lib.t6g(sch_1):page342_i29@pure_quanta.q_res(chips)',
 P_PATH='@t6g_mb_lib.t6g(sch_1):page139_i29@pure_quanta.q_res(chips)',
 PATH='I29',
 DRAWING='@T6G_MB_LIB.T6G(SCH_1):PAGE342',
 WATTAGE='1/16W',
 TOLERANCE='1%',
 MATERIAL='CHIP',
 PHYS_PAGE='139',
 XY='(6300,-1725)',
 ROT='0',
 VER='1',
 PACK_TYPE='0402LF',
 LOCATION='R3185',
 CDS_LIB='pure_quanta',
 CDS_PART_NAME='Q_RES_0402LF-33.2,1%,1/16W,CHIP,CS03322FB03',
 PART_NUMBER='CS03322FB03',
 VALUE='33.2',
 PRIM_FILE='./archive_libs/logical/q_res/chips/chips.prt';

PART_NAME
 R3190 'Q_RES_0402LF-4.7K,1%,1/16W,CHIP,CS24702FB06':;

SECTION_NUMBER 1
 '@T6G_MB_LIB.T6G(SCH_1):PAGE342_I34@PURE_QUANTA.Q_RES(CHIPS)':
 C_PATH='@t6g_mb_lib.t6g(sch_1):page342_i34@pure_quanta.q_res(chips)',
 P_PATH='@t6g_mb_lib.t6g(sch_1):page139_i34@pure_quanta.q_res(chips)',
 PATH='I34',
 DRAWING='@T6G_MB_LIB.T6G(SCH_1):PAGE342',
 WATTAGE='1/16W',
 TOLERANCE='1%',
 MATERIAL='CHIP',
 PHYS_PAGE='139',
 XY='(7150,-125)',
 ROT='0',
 VER='2',
 PACK_TYPE='0402LF',
 LOCATION='R3190',
 CDS_LIB='pure_quanta',
 CDS_PART_NAME='Q_RES_0402LF-4.7K,1%,1/16W,CHIP,CS24702FB06',
 PART_NUMBER='CS24702FB06',
 VALUE='4.7K',
 PRIM_FILE='./archive_libs/logical/q_res/chips/chips.prt';

PART_NAME
 R3191 'Q_RES_0402LF-33.2,1%,1/16W,CHIP,CS03322FB03':;

SECTION_NUMBER 1
 '@T6G_MB_LIB.T6G(SCH_1):PAGE342_I33@PURE_QUANTA.Q_RES(CHIPS)':
 C_PATH='@t6g_mb_lib.t6g(sch_1):page342_i33@pure_quanta.q_res(chips)',
 P_PATH='@t6g_mb_lib.t6g(sch_1):page139_i33@pure_quanta.q_res(chips)',
 PATH='I33',
 DRAWING='@T6G_MB_LIB.T6G(SCH_1):PAGE342',
 WATTAGE='1/16W',
 TOLERANCE='1%',
 MATERIAL='CHIP',
 PHYS_PAGE='139',
 XY='(7700,-500)',
 ROT='0',
 VER='1',
 PACK_TYPE='0402LF',
 LOCATION='R3191',
 CDS_LIB='pure_quanta',
 CDS_PART_NAME='Q_RES_0402LF-33.2,1%,1/16W,CHIP,CS03322FB03',
 PART_NUMBER='CS03322FB03',
 VALUE='33.2',
 PRIM_FILE='./archive_libs/logical/q_res/chips/chips.prt';

PART_NAME
 R3192 'Q_RES_0402LF-4.7K,1%,1/16W,EMPTY,CS24702FB06':;

SECTION_NUMBER 1
 '@T6G_MB_LIB.T6G(SCH_1):PAGE342_I44@PURE_QUANTA.Q_RES(CHIPS)':
 C_PATH='@t6g_mb_lib.t6g(sch_1):page342_i44@pure_quanta.q_res(chips)',
 P_PATH='@t6g_mb_lib.t6g(sch_1):page139_i44@pure_quanta.q_res(chips)',
 PATH='I44',
 DRAWING='@T6G_MB_LIB.T6G(SCH_1):PAGE342',
 WATTAGE='1/16W',
 TOLERANCE='1%',
 MATERIAL='EMPTY',
 PHYS_PAGE='139',
 XY='(9250,-1375)',
 ROT='0',
 VER='2',
 PACK_TYPE='0402LF',
 LOCATION='R3192',
 CDS_LIB='pure_quanta',
 CDS_PART_NAME='Q_RES_0402LF-4.7K,1%,1/16W,EMPTY,CS24702FB06',
 PART_NUMBER='CS24702FB06',
 VALUE='4.7K',
 PRIM_FILE='./archive_libs/logical/q_res/chips/chips.prt';

PART_NAME
 R3193 'Q_RES_0402LF-33.2,1%,1/16W,CHIP,CS03322FB03':;

SECTION_NUMBER 1
 '@T6G_MB_LIB.T6G(SCH_1):PAGE342_I43@PURE_QUANTA.Q_RES(CHIPS)':
 C_PATH='@t6g_mb_lib.t6g(sch_1):page342_i43@pure_quanta.q_res(chips)',
 P_PATH='@t6g_mb_lib.t6g(sch_1):page139_i43@pure_quanta.q_res(chips)',
 PATH='I43',
 DRAWING='@T6G_MB_LIB.T6G(SCH_1):PAGE342',
 WATTAGE='1/16W',
 TOLERANCE='1%',
 MATERIAL='CHIP',
 PHYS_PAGE='139',
 XY='(9550,-1825)',
 ROT='0',
 VER='1',
 PACK_TYPE='0402LF',
 LOCATION='R3193',
 CDS_LIB='pure_quanta',
 CDS_PART_NAME='Q_RES_0402LF-33.2,1%,1/16W,CHIP,CS03322FB03',
 PART_NUMBER='CS03322FB03',
 VALUE='33.2',
 PRIM_FILE='./archive_libs/logical/q_res/chips/chips.prt';

PART_NAME
 R3194 'Q_RES_0402LF-0,5%,1/16W,CHIP,CS00002JB13':;

SECTION_NUMBER 1
 '@T6G_MB_LIB.T6G(SCH_1):PAGE55_I308@PURE_QUANTA.Q_RES(CHIPS)':
 C_PATH='@t6g_mb_lib.t6g(sch_1):page55_i308@pure_quanta.q_res(chips)',
 P_PATH='@t6g_mb_lib.t6g(sch_1):page55_i308@pure_quanta.q_res(chips)',
 PATH='I308',
 DRAWING='@T6G_MB_LIB.T6G(SCH_1):PAGE55',
 WATTAGE='1/16W',
 TOLERANCE='5%',
 MATERIAL='CHIP',
 PHYS_PAGE='55',
 XY='(-2000,4775)',
 ROT='0',
 VER='1',
 PACK_TYPE='0402LF',
 LOCATION='R3194',
 CDS_LIB='pure_quanta',
 CDS_PART_NAME='Q_RES_0402LF-0,5%,1/16W,CHIP,CS00002JB13',
 PART_NUMBER='CS00002JB13',
 VALUE='0',
 PRIM_FILE='./archive_libs/logical/q_res/chips/chips.prt';

PART_NAME
 R3195 'Q_RES_0402LF-0,5%,1/16W,CHIP,CS00002JB13':;

SECTION_NUMBER 1
 '@T6G_MB_LIB.T6G(SCH_1):PAGE55_I309@PURE_QUANTA.Q_RES(CHIPS)':
 C_PATH='@t6g_mb_lib.t6g(sch_1):page55_i309@pure_quanta.q_res(chips)',
 P_PATH='@t6g_mb_lib.t6g(sch_1):page55_i309@pure_quanta.q_res(chips)',
 PATH='I309',
 DRAWING='@T6G_MB_LIB.T6G(SCH_1):PAGE55',
 WATTAGE='1/16W',
 TOLERANCE='5%',
 MATERIAL='CHIP',
 PHYS_PAGE='55',
 XY='(-2000,4725)',
 ROT='0',
 VER='1',
 PACK_TYPE='0402LF',
 LOCATION='R3195',
 CDS_LIB='pure_quanta',
 CDS_PART_NAME='Q_RES_0402LF-0,5%,1/16W,CHIP,CS00002JB13',
 PART_NUMBER='CS00002JB13',
 VALUE='0',
 PRIM_FILE='./archive_libs/logical/q_res/chips/chips.prt';

PART_NAME
 R3196 'Q_RES_0402LF-0,5%,1/16W,CHIP,CS00002JB13':;

SECTION_NUMBER 1
 '@T6G_MB_LIB.T6G(SCH_1):PAGE55_I312@PURE_QUANTA.Q_RES(CHIPS)':
 C_PATH='@t6g_mb_lib.t6g(sch_1):page55_i312@pure_quanta.q_res(chips)',
 P_PATH='@t6g_mb_lib.t6g(sch_1):page55_i312@pure_quanta.q_res(chips)',
 PATH='I312',
 DRAWING='@T6G_MB_LIB.T6G(SCH_1):PAGE55',
 WATTAGE='1/16W',
 TOLERANCE='5%',
 MATERIAL='CHIP',
 PHYS_PAGE='55',
 XY='(-2000,4625)',
 ROT='0',
 VER='1',
 PACK_TYPE='0402LF',
 LOCATION='R3196',
 CDS_LIB='pure_quanta',
 CDS_PART_NAME='Q_RES_0402LF-0,5%,1/16W,CHIP,CS00002JB13',
 PART_NUMBER='CS00002JB13',
 VALUE='0',
 PRIM_FILE='./archive_libs/logical/q_res/chips/chips.prt';

PART_NAME
 R3197 'Q_RES_0402LF-0,5%,1/16W,CHIP,CS00002JB13':;

SECTION_NUMBER 1
 '@T6G_MB_LIB.T6G(SCH_1):PAGE55_I313@PURE_QUANTA.Q_RES(CHIPS)':
 C_PATH='@t6g_mb_lib.t6g(sch_1):page55_i313@pure_quanta.q_res(chips)',
 P_PATH='@t6g_mb_lib.t6g(sch_1):page55_i313@pure_quanta.q_res(chips)',
 PATH='I313',
 DRAWING='@T6G_MB_LIB.T6G(SCH_1):PAGE55',
 WATTAGE='1/16W',
 TOLERANCE='5%',
 MATERIAL='CHIP',
 PHYS_PAGE='55',
 XY='(-2000,4575)',
 ROT='0',
 VER='1',
 PACK_TYPE='0402LF',
 LOCATION='R3197',
 CDS_LIB='pure_quanta',
 CDS_PART_NAME='Q_RES_0402LF-0,5%,1/16W,CHIP,CS00002JB13',
 PART_NUMBER='CS00002JB13',
 VALUE='0',
 PRIM_FILE='./archive_libs/logical/q_res/chips/chips.prt';

PART_NAME
 R3198 'Q_RES_0402LF-0,5%,1/16W,CHIP,CS00002JB13':;

SECTION_NUMBER 1
 '@T6G_MB_LIB.T6G(SCH_1):PAGE55_I316@PURE_QUANTA.Q_RES(CHIPS)':
 C_PATH='@t6g_mb_lib.t6g(sch_1):page55_i316@pure_quanta.q_res(chips)',
 P_PATH='@t6g_mb_lib.t6g(sch_1):page55_i316@pure_quanta.q_res(chips)',
 PATH='I316',
 DRAWING='@T6G_MB_LIB.T6G(SCH_1):PAGE55',
 WATTAGE='1/16W',
 TOLERANCE='5%',
 MATERIAL='CHIP',
 PHYS_PAGE='55',
 XY='(-2000,4475)',
 ROT='0',
 VER='1',
 PACK_TYPE='0402LF',
 LOCATION='R3198',
 CDS_LIB='pure_quanta',
 CDS_PART_NAME='Q_RES_0402LF-0,5%,1/16W,CHIP,CS00002JB13',
 PART_NUMBER='CS00002JB13',
 VALUE='0',
 PRIM_FILE='./archive_libs/logical/q_res/chips/chips.prt';

PART_NAME
 R3199 'Q_RES_0402LF-0,5%,1/16W,CHIP,CS00002JB13':;

SECTION_NUMBER 1
 '@T6G_MB_LIB.T6G(SCH_1):PAGE55_I317@PURE_QUANTA.Q_RES(CHIPS)':
 C_PATH='@t6g_mb_lib.t6g(sch_1):page55_i317@pure_quanta.q_res(chips)',
 P_PATH='@t6g_mb_lib.t6g(sch_1):page55_i317@pure_quanta.q_res(chips)',
 PATH='I317',
 DRAWING='@T6G_MB_LIB.T6G(SCH_1):PAGE55',
 WATTAGE='1/16W',
 TOLERANCE='5%',
 MATERIAL='CHIP',
 PHYS_PAGE='55',
 XY='(-2000,4425)',
 ROT='0',
 VER='1',
 PACK_TYPE='0402LF',
 LOCATION='R3199',
 CDS_LIB='pure_quanta',
 CDS_PART_NAME='Q_RES_0402LF-0,5%,1/16W,CHIP,CS00002JB13',
 PART_NUMBER='CS00002JB13',
 VALUE='0',
 PRIM_FILE='./archive_libs/logical/q_res/chips/chips.prt';

PART_NAME
 R3200 'Q_RES_0402LF-0,5%,1/16W,CHIP,CS00002JB13':;

SECTION_NUMBER 1
 '@T6G_MB_LIB.T6G(SCH_1):PAGE55_I320@PURE_QUANTA.Q_RES(CHIPS)':
 C_PATH='@t6g_mb_lib.t6g(sch_1):page55_i320@pure_quanta.q_res(chips)',
 P_PATH='@t6g_mb_lib.t6g(sch_1):page55_i320@pure_quanta.q_res(chips)',
 PATH='I320',
 DRAWING='@T6G_MB_LIB.T6G(SCH_1):PAGE55',
 WATTAGE='1/16W',
 TOLERANCE='5%',
 MATERIAL='CHIP',
 PHYS_PAGE='55',
 XY='(-2000,4325)',
 ROT='0',
 VER='1',
 PACK_TYPE='0402LF',
 LOCATION='R3200',
 CDS_LIB='pure_quanta',
 CDS_PART_NAME='Q_RES_0402LF-0,5%,1/16W,CHIP,CS00002JB13',
 PART_NUMBER='CS00002JB13',
 VALUE='0',
 PRIM_FILE='./archive_libs/logical/q_res/chips/chips.prt';

PART_NAME
 R3201 'Q_RES_0402LF-0,5%,1/16W,CHIP,CS00002JB13':;

SECTION_NUMBER 1
 '@T6G_MB_LIB.T6G(SCH_1):PAGE55_I321@PURE_QUANTA.Q_RES(CHIPS)':
 C_PATH='@t6g_mb_lib.t6g(sch_1):page55_i321@pure_quanta.q_res(chips)',
 P_PATH='@t6g_mb_lib.t6g(sch_1):page55_i321@pure_quanta.q_res(chips)',
 PATH='I321',
 DRAWING='@T6G_MB_LIB.T6G(SCH_1):PAGE55',
 WATTAGE='1/16W',
 TOLERANCE='5%',
 MATERIAL='CHIP',
 PHYS_PAGE='55',
 XY='(-2000,4275)',
 ROT='0',
 VER='1',
 PACK_TYPE='0402LF',
 LOCATION='R3201',
 CDS_LIB='pure_quanta',
 CDS_PART_NAME='Q_RES_0402LF-0,5%,1/16W,CHIP,CS00002JB13',
 PART_NUMBER='CS00002JB13',
 VALUE='0',
 PRIM_FILE='./archive_libs/logical/q_res/chips/chips.prt';

PART_NAME
 R3203 'Q_RES_0402LF-33.2,1%,1/16W,CHIP,CS03322FB03':;

SECTION_NUMBER 1
 '@T6G_MB_LIB.T6G(SCH_1):PAGE307_I81@PURE_QUANTA.Q_RES(CHIPS)':
 C_PATH='@t6g_mb_lib.t6g(sch_1):page307_i81@pure_quanta.q_res(chips)',
 P_PATH='@t6g_mb_lib.t6g(sch_1):page138_i81@pure_quanta.q_res(chips)',
 PATH='I81',
 DRAWING='@T6G_MB_LIB.T6G(SCH_1):PAGE307',
 WATTAGE='1/16W',
 TOLERANCE='1%',
 MATERIAL='CHIP',
 PHYS_PAGE='138',
 XY='(-2875,-475)',
 ROT='0',
 VER='1',
 PACK_TYPE='0402LF',
 LOCATION='R3203',
 CDS_LIB='pure_quanta',
 CDS_PART_NAME='Q_RES_0402LF-33.2,1%,1/16W,CHIP,CS03322FB03',
 PART_NUMBER='CS03322FB03',
 VALUE='33.2',
 PRIM_FILE='./archive_libs/logical/q_res/chips/chips.prt';

PART_NAME
 R3205 'Q_RES_0402LF-0,5%,1/16W,CHIP,CS00002JB13':;

SECTION_NUMBER 1
 '@T6G_MB_LIB.T6G(SCH_1):PAGE307_I86@PURE_QUANTA.Q_RES(CHIPS)':
 C_PATH='@t6g_mb_lib.t6g(sch_1):page307_i86@pure_quanta.q_res(chips)',
 P_PATH='@t6g_mb_lib.t6g(sch_1):page138_i86@pure_quanta.q_res(chips)',
 PATH='I86',
 DRAWING='@T6G_MB_LIB.T6G(SCH_1):PAGE307',
 WATTAGE='1/16W',
 TOLERANCE='5%',
 MATERIAL='CHIP',
 PHYS_PAGE='138',
 XY='(-75,-425)',
 ROT='0',
 VER='1',
 PACK_TYPE='0402LF',
 LOCATION='R3205',
 CDS_LIB='pure_quanta',
 CDS_PART_NAME='Q_RES_0402LF-0,5%,1/16W,CHIP,CS00002JB13',
 PART_NUMBER='CS00002JB13',
 VALUE='0',
 PRIM_FILE='./archive_libs/logical/q_res/chips/chips.prt';

PART_NAME
 R3206 'Q_RES_0402LF-0,5%,1/16W,EMPTY,CS00002JB13':;

SECTION_NUMBER 1
 '@T6G_MB_LIB.T6G(SCH_1):PAGE307_I85@PURE_QUANTA.Q_RES(CHIPS)':
 C_PATH='@t6g_mb_lib.t6g(sch_1):page307_i85@pure_quanta.q_res(chips)',
 P_PATH='@t6g_mb_lib.t6g(sch_1):page138_i85@pure_quanta.q_res(chips)',
 PATH='I85',
 DRAWING='@T6G_MB_LIB.T6G(SCH_1):PAGE307',
 WATTAGE='1/16W',
 TOLERANCE='5%',
 MATERIAL='EMPTY',
 PHYS_PAGE='138',
 XY='(-75,-950)',
 ROT='0',
 VER='1',
 PACK_TYPE='0402LF',
 LOCATION='R3206',
 CDS_LIB='pure_quanta',
 CDS_PART_NAME='Q_RES_0402LF-0,5%,1/16W,EMPTY,CS00002JB13',
 PART_NUMBER='CS00002JB13',
 VALUE='0',
 PRIM_FILE='./archive_libs/logical/q_res/chips/chips.prt';

PART_NAME
 R3207 'Q_RES_0402LF-100K,1%,1/16W,CHIP,CS41002FB09':;

SECTION_NUMBER 1
 '@T6G_MB_LIB.T6G(SCH_1):PAGE307_I15@PURE_QUANTA.Q_RES(CHIPS)':
 C_PATH='@t6g_mb_lib.t6g(sch_1):page307_i15@pure_quanta.q_res(chips)',
 P_PATH='@t6g_mb_lib.t6g(sch_1):page138_i15@pure_quanta.q_res(chips)',
 PATH='I15',
 DRAWING='@T6G_MB_LIB.T6G(SCH_1):PAGE307',
 WATTAGE='1/16W',
 TOLERANCE='1%',
 MATERIAL='CHIP',
 PHYS_PAGE='138',
 XY='(275,-625)',
 ROT='0',
 VER='2',
 PACK_TYPE='0402LF',
 LOCATION='R3207',
 CDS_LIB='pure_quanta',
 CDS_PART_NAME='Q_RES_0402LF-100K,1%,1/16W,CHIP,CS41002FB09',
 PART_NUMBER='CS41002FB09',
 VALUE='100K',
 PRIM_FILE='./archive_libs/logical/q_res/chips/chips.prt';

PART_NAME
 R3208 'Q_RES_0402LF-100,1%,1/16W,CHIP,CS11002FB07':;

SECTION_NUMBER 1
 '@T6G_MB_LIB.T6G(SCH_1):PAGE307_I37@PURE_QUANTA.Q_RES(CHIPS)':
 C_PATH='@t6g_mb_lib.t6g(sch_1):page307_i37@pure_quanta.q_res(chips)',
 P_PATH='@t6g_mb_lib.t6g(sch_1):page138_i37@pure_quanta.q_res(chips)',
 PATH='I37',
 DRAWING='@T6G_MB_LIB.T6G(SCH_1):PAGE307',
 WATTAGE='1/16W',
 TOLERANCE='1%',
 MATERIAL='CHIP',
 PHYS_PAGE='138',
 XY='(1800,-2525)',
 ROT='0',
 VER='2',
 PACK_TYPE='0402LF',
 LOCATION='R3208',
 CDS_LIB='pure_quanta',
 CDS_PART_NAME='Q_RES_0402LF-100,1%,1/16W,CHIP,CS11002FB07',
 PART_NUMBER='CS11002FB07',
 VALUE='100',
 PRIM_FILE='./archive_libs/logical/q_res/chips/chips.prt';

PART_NAME
 R3209 'Q_RES_0402LF-22,1%,1/16W,EMPTY,CS02202FB02':;

SECTION_NUMBER 1
 '@T6G_MB_LIB.T6G(SCH_1):PAGE307_I64@PURE_QUANTA.Q_RES(CHIPS)':
 C_PATH='@t6g_mb_lib.t6g(sch_1):page307_i64@pure_quanta.q_res(chips)',
 P_PATH='@t6g_mb_lib.t6g(sch_1):page138_i64@pure_quanta.q_res(chips)',
 PATH='I64',
 DRAWING='@T6G_MB_LIB.T6G(SCH_1):PAGE307',
 WATTAGE='1/16W',
 TOLERANCE='1%',
 MATERIAL='EMPTY',
 PHYS_PAGE='138',
 XY='(3450,2475)',
 ROT='0',
 VER='1',
 PACK_TYPE='0402LF',
 LOCATION='R3209',
 CDS_LIB='pure_quanta',
 CDS_PART_NAME='Q_RES_0402LF-22,1%,1/16W,EMPTY,CS02202FB02',
 PART_NUMBER='CS02202FB02',
 VALUE='22',
 PRIM_FILE='./archive_libs/logical/q_res/chips/chips.prt';

PART_NAME
 R3210 'Q_RES_0402LF-22,1%,1/16W,EMPTY,CS02202FB02':;

SECTION_NUMBER 1
 '@T6G_MB_LIB.T6G(SCH_1):PAGE307_I65@PURE_QUANTA.Q_RES(CHIPS)':
 C_PATH='@t6g_mb_lib.t6g(sch_1):page307_i65@pure_quanta.q_res(chips)',
 P_PATH='@t6g_mb_lib.t6g(sch_1):page138_i65@pure_quanta.q_res(chips)',
 PATH='I65',
 DRAWING='@T6G_MB_LIB.T6G(SCH_1):PAGE307',
 WATTAGE='1/16W',
 TOLERANCE='1%',
 MATERIAL='EMPTY',
 PHYS_PAGE='138',
 XY='(1900,2325)',
 ROT='0',
 VER='1',
 PACK_TYPE='0402LF',
 LOCATION='R3210',
 CDS_LIB='pure_quanta',
 CDS_PART_NAME='Q_RES_0402LF-22,1%,1/16W,EMPTY,CS02202FB02',
 PART_NUMBER='CS02202FB02',
 VALUE='22',
 PRIM_FILE='./archive_libs/logical/q_res/chips/chips.prt';

PART_NAME
 R3211 'Q_RES_0402LF-22,1%,1/16W,EMPTY,CS02202FB02':;

SECTION_NUMBER 1
 '@T6G_MB_LIB.T6G(SCH_1):PAGE307_I63@PURE_QUANTA.Q_RES(CHIPS)':
 C_PATH='@t6g_mb_lib.t6g(sch_1):page307_i63@pure_quanta.q_res(chips)',
 P_PATH='@t6g_mb_lib.t6g(sch_1):page138_i63@pure_quanta.q_res(chips)',
 PATH='I63',
 DRAWING='@T6G_MB_LIB.T6G(SCH_1):PAGE307',
 WATTAGE='1/16W',
 TOLERANCE='1%',
 MATERIAL='EMPTY',
 PHYS_PAGE='138',
 XY='(1900,2175)',
 ROT='0',
 VER='1',
 PACK_TYPE='0402LF',
 LOCATION='R3211',
 CDS_LIB='pure_quanta',
 CDS_PART_NAME='Q_RES_0402LF-22,1%,1/16W,EMPTY,CS02202FB02',
 PART_NUMBER='CS02202FB02',
 VALUE='22',
 PRIM_FILE='./archive_libs/logical/q_res/chips/chips.prt';

PART_NAME
 R3212 'Q_RES_0402LF-22,1%,1/16W,EMPTY,CS02202FB02':;

SECTION_NUMBER 1
 '@T6G_MB_LIB.T6G(SCH_1):PAGE307_I62@PURE_QUANTA.Q_RES(CHIPS)':
 C_PATH='@t6g_mb_lib.t6g(sch_1):page307_i62@pure_quanta.q_res(chips)',
 P_PATH='@t6g_mb_lib.t6g(sch_1):page138_i62@pure_quanta.q_res(chips)',
 PATH='I62',
 DRAWING='@T6G_MB_LIB.T6G(SCH_1):PAGE307',
 WATTAGE='1/16W',
 TOLERANCE='1%',
 MATERIAL='EMPTY',
 PHYS_PAGE='138',
 XY='(1900,2025)',
 ROT='0',
 VER='1',
 PACK_TYPE='0402LF',
 LOCATION='R3212',
 CDS_LIB='pure_quanta',
 CDS_PART_NAME='Q_RES_0402LF-22,1%,1/16W,EMPTY,CS02202FB02',
 PART_NUMBER='CS02202FB02',
 VALUE='22',
 PRIM_FILE='./archive_libs/logical/q_res/chips/chips.prt';

PART_NAME
 R3213 'Q_RES_0402LF-0,5%,1/16W,EMPTY,CS00002JB13':;

SECTION_NUMBER 1
 '@T6G_MB_LIB.T6G(SCH_1):PAGE307_I61@PURE_QUANTA.Q_RES(CHIPS)':
 C_PATH='@t6g_mb_lib.t6g(sch_1):page307_i61@pure_quanta.q_res(chips)',
 P_PATH='@t6g_mb_lib.t6g(sch_1):page138_i61@pure_quanta.q_res(chips)',
 PATH='I61',
 DRAWING='@T6G_MB_LIB.T6G(SCH_1):PAGE307',
 WATTAGE='1/16W',
 TOLERANCE='5%',
 MATERIAL='EMPTY',
 PHYS_PAGE='138',
 XY='(1900,900)',
 ROT='0',
 VER='1',
 PACK_TYPE='0402LF',
 LOCATION='R3213',
 CDS_LIB='pure_quanta',
 CDS_PART_NAME='Q_RES_0402LF-0,5%,1/16W,EMPTY,CS00002JB13',
 PART_NUMBER='CS00002JB13',
 VALUE='0',
 PRIM_FILE='./archive_libs/logical/q_res/chips/chips.prt';

PART_NAME
 R3214 'Q_RES_0402LF-0,5%,1/16W,EMPTY,CS00002JB13':;

SECTION_NUMBER 1
 '@T6G_MB_LIB.T6G(SCH_1):PAGE307_I60@PURE_QUANTA.Q_RES(CHIPS)':
 C_PATH='@t6g_mb_lib.t6g(sch_1):page307_i60@pure_quanta.q_res(chips)',
 P_PATH='@t6g_mb_lib.t6g(sch_1):page138_i60@pure_quanta.q_res(chips)',
 PATH='I60',
 DRAWING='@T6G_MB_LIB.T6G(SCH_1):PAGE307',
 WATTAGE='1/16W',
 TOLERANCE='5%',
 MATERIAL='EMPTY',
 PHYS_PAGE='138',
 XY='(1900,750)',
 ROT='0',
 VER='1',
 PACK_TYPE='0402LF',
 LOCATION='R3214',
 CDS_LIB='pure_quanta',
 CDS_PART_NAME='Q_RES_0402LF-0,5%,1/16W,EMPTY,CS00002JB13',
 PART_NUMBER='CS00002JB13',
 VALUE='0',
 PRIM_FILE='./archive_libs/logical/q_res/chips/chips.prt';

PART_NAME
 R3215 'Q_RES_0402LF-0,5%,1/16W,EMPTY,CS00002JB13':;

SECTION_NUMBER 1
 '@T6G_MB_LIB.T6G(SCH_1):PAGE307_I56@PURE_QUANTA.Q_RES(CHIPS)':
 C_PATH='@t6g_mb_lib.t6g(sch_1):page307_i56@pure_quanta.q_res(chips)',
 P_PATH='@t6g_mb_lib.t6g(sch_1):page138_i56@pure_quanta.q_res(chips)',
 PATH='I56',
 DRAWING='@T6G_MB_LIB.T6G(SCH_1):PAGE307',
 WATTAGE='1/16W',
 TOLERANCE='5%',
 MATERIAL='EMPTY',
 PHYS_PAGE='138',
 XY='(1900,600)',
 ROT='0',
 VER='1',
 PACK_TYPE='0402LF',
 LOCATION='R3215',
 CDS_LIB='pure_quanta',
 CDS_PART_NAME='Q_RES_0402LF-0,5%,1/16W,EMPTY,CS00002JB13',
 PART_NUMBER='CS00002JB13',
 VALUE='0',
 PRIM_FILE='./archive_libs/logical/q_res/chips/chips.prt';

PART_NAME
 R3216 'Q_RES_0402LF-100,1%,1/16W,CHIP,CS11002FB07':;

SECTION_NUMBER 1
 '@T6G_MB_LIB.T6G(SCH_1):PAGE307_I38@PURE_QUANTA.Q_RES(CHIPS)':
 C_PATH='@t6g_mb_lib.t6g(sch_1):page307_i38@pure_quanta.q_res(chips)',
 P_PATH='@t6g_mb_lib.t6g(sch_1):page138_i38@pure_quanta.q_res(chips)',
 PATH='I38',
 DRAWING='@T6G_MB_LIB.T6G(SCH_1):PAGE307',
 WATTAGE='1/16W',
 TOLERANCE='1%',
 MATERIAL='CHIP',
 PHYS_PAGE='138',
 XY='(2050,-2525)',
 ROT='0',
 VER='2',
 PACK_TYPE='0402LF',
 LOCATION='R3216',
 CDS_LIB='pure_quanta',
 CDS_PART_NAME='Q_RES_0402LF-100,1%,1/16W,CHIP,CS11002FB07',
 PART_NUMBER='CS11002FB07',
 VALUE='100',
 PRIM_FILE='./archive_libs/logical/q_res/chips/chips.prt';

PART_NAME
 R3217 'Q_RES_0402LF-100,1%,1/16W,CHIP,CS11002FB07':;

SECTION_NUMBER 1
 '@T6G_MB_LIB.T6G(SCH_1):PAGE307_I40@PURE_QUANTA.Q_RES(CHIPS)':
 C_PATH='@t6g_mb_lib.t6g(sch_1):page307_i40@pure_quanta.q_res(chips)',
 P_PATH='@t6g_mb_lib.t6g(sch_1):page138_i40@pure_quanta.q_res(chips)',
 PATH='I40',
 DRAWING='@T6G_MB_LIB.T6G(SCH_1):PAGE307',
 WATTAGE='1/16W',
 TOLERANCE='1%',
 MATERIAL='CHIP',
 PHYS_PAGE='138',
 XY='(2300,-2525)',
 ROT='0',
 VER='2',
 PACK_TYPE='0402LF',
 LOCATION='R3217',
 CDS_LIB='pure_quanta',
 CDS_PART_NAME='Q_RES_0402LF-100,1%,1/16W,CHIP,CS11002FB07',
 PART_NUMBER='CS11002FB07',
 VALUE='100',
 PRIM_FILE='./archive_libs/logical/q_res/chips/chips.prt';

PART_NAME
 R3226 'Q_RES_0402LF-2.2K,5%,1/16W,EMPTY,CS22202JB07':;

SECTION_NUMBER 1
 '@T6G_MB_LIB.T6G(SCH_1):PAGE349_I122@PURE_QUANTA.Q_RES(CHIPS)':
 C_PATH='@t6g_mb_lib.t6g(sch_1):page349_i122@pure_quanta.q_res(chips)',
 P_PATH='@t6g_mb_lib.t6g(sch_1):page151_i122@pure_quanta.q_res(chips)',
 PATH='I122',
 DRAWING='@T6G_MB_LIB.T6G(SCH_1):PAGE349',
 WATTAGE='1/16W',
 TOLERANCE='5%',
 MATERIAL='EMPTY',
 PHYS_PAGE='151',
 XY='(4275,2700)',
 ROT='0',
 VER='1',
 PACK_TYPE='0402LF',
 LOCATION='R3226',
 CDS_LIB='pure_quanta',
 CDS_PART_NAME='Q_RES_0402LF-2.2K,5%,1/16W,EMPTY,CS22202JB07',
 PART_NUMBER='CS22202JB07',
 VALUE='2.2K',
 PRIM_FILE='./archive_libs/logical/q_res/chips/chips.prt';

PART_NAME
 R3227 'Q_RES_0402LF-2.2K,5%,1/16W,EMPTY,CS22202JB07':;

SECTION_NUMBER 1
 '@T6G_MB_LIB.T6G(SCH_1):PAGE349_I121@PURE_QUANTA.Q_RES(CHIPS)':
 C_PATH='@t6g_mb_lib.t6g(sch_1):page349_i121@pure_quanta.q_res(chips)',
 P_PATH='@t6g_mb_lib.t6g(sch_1):page151_i121@pure_quanta.q_res(chips)',
 PATH='I121',
 DRAWING='@T6G_MB_LIB.T6G(SCH_1):PAGE349',
 WATTAGE='1/16W',
 TOLERANCE='5%',
 MATERIAL='EMPTY',
 PHYS_PAGE='151',
 XY='(4275,2650)',
 ROT='0',
 VER='1',
 PACK_TYPE='0402LF',
 LOCATION='R3227',
 CDS_LIB='pure_quanta',
 CDS_PART_NAME='Q_RES_0402LF-2.2K,5%,1/16W,EMPTY,CS22202JB07',
 PART_NUMBER='CS22202JB07',
 VALUE='2.2K',
 PRIM_FILE='./archive_libs/logical/q_res/chips/chips.prt';

PART_NAME
 R3228 'Q_RES_0402LF-200,1%,1/16W,CHIP,CS12002FB06':;

SECTION_NUMBER 1
 '@T6G_MB_LIB.T6G(SCH_1):PAGE341_I171@PURE_QUANTA.Q_RES(CHIPS)':
 C_PATH='@t6g_mb_lib.t6g(sch_1):page341_i171@pure_quanta.q_res(chips)',
 P_PATH='@t6g_mb_lib.t6g(sch_1):page137_i171@pure_quanta.q_res(chips)',
 PATH='I171',
 DRAWING='@T6G_MB_LIB.T6G(SCH_1):PAGE341',
 SEC_TYPE='0402LF',
 WATTAGE='1/16W',
 TOLERANCE='1%',
 MATERIAL='CHIP',
 PHYS_PAGE='137',
 XY='(6375,4025)',
 ROT='0',
 VER='1',
 PACK_TYPE='0402LF',
 LOCATION='R3228',
 SEC='1',
 CDS_LIB='pure_quanta',
 CDS_PART_NAME='Q_RES_0402LF-200,1%,1/16W,CHIP,CS12002FB06',
 PART_NUMBER='CS12002FB06',
 VALUE='200',
 PRIM_FILE='./archive_libs/logical/q_res/chips/chips.prt';

PART_NAME
 R3229 'Q_RES_0402LF-200,1%,1/16W,CHIP,CS12002FB06':;

SECTION_NUMBER 1
 '@T6G_MB_LIB.T6G(SCH_1):PAGE341_I170@PURE_QUANTA.Q_RES(CHIPS)':
 C_PATH='@t6g_mb_lib.t6g(sch_1):page341_i170@pure_quanta.q_res(chips)',
 P_PATH='@t6g_mb_lib.t6g(sch_1):page137_i170@pure_quanta.q_res(chips)',
 PATH='I170',
 DRAWING='@T6G_MB_LIB.T6G(SCH_1):PAGE341',
 SEC_TYPE='0402LF',
 WATTAGE='1/16W',
 TOLERANCE='1%',
 MATERIAL='CHIP',
 PHYS_PAGE='137',
 XY='(6375,3975)',
 ROT='0',
 VER='1',
 PACK_TYPE='0402LF',
 LOCATION='R3229',
 SEC='1',
 CDS_LIB='pure_quanta',
 CDS_PART_NAME='Q_RES_0402LF-200,1%,1/16W,CHIP,CS12002FB06',
 PART_NUMBER='CS12002FB06',
 VALUE='200',
 PRIM_FILE='./archive_libs/logical/q_res/chips/chips.prt';

PART_NAME
 R3231 'Q_RES_0402LF-33.2,1%,1/16W,CHIP,CS03322FB03':;

SECTION_NUMBER 1
 '@T6G_MB_LIB.T6G(SCH_1):PAGE336_I160@PURE_QUANTA.Q_RES(CHIPS)':
 C_PATH='@t6g_mb_lib.t6g(sch_1):page336_i160@pure_quanta.q_res(chips)',
 P_PATH='@t6g_mb_lib.t6g(sch_1):page132_i160@pure_quanta.q_res(chips)',
 PATH='I160',
 DRAWING='@T6G_MB_LIB.T6G(SCH_1):PAGE336',
 WATTAGE='1/16W',
 TOLERANCE='1%',
 MATERIAL='CHIP',
 PHYS_PAGE='132',
 XY='(-3350,2225)',
 ROT='0',
 VER='1',
 PACK_TYPE='0402LF',
 LOCATION='R3231',
 CDS_LIB='pure_quanta',
 CDS_PART_NAME='Q_RES_0402LF-33.2,1%,1/16W,CHIP,CS03322FB03',
 PART_NUMBER='CS03322FB03',
 VALUE='33.2',
 PRIM_FILE='./archive_libs/logical/q_res/chips/chips.prt';

PART_NAME
 R3232 'Q_RES_0402LF-100K,1%,1/16W,CHIP,CS41002FB09':;

SECTION_NUMBER 1
 '@T6G_MB_LIB.T6G(SCH_1):PAGE336_I152@PURE_QUANTA.Q_RES(CHIPS)':
 C_PATH='@t6g_mb_lib.t6g(sch_1):page336_i152@pure_quanta.q_res(chips)',
 P_PATH='@t6g_mb_lib.t6g(sch_1):page132_i152@pure_quanta.q_res(chips)',
 PATH='I152',
 DRAWING='@T6G_MB_LIB.T6G(SCH_1):PAGE336',
 WATTAGE='1/16W',
 TOLERANCE='1%',
 MATERIAL='CHIP',
 PHYS_PAGE='132',
 XY='(-1125,2050)',
 ROT='0',
 VER='2',
 PACK_TYPE='0402LF',
 LOCATION='R3232',
 CDS_LIB='pure_quanta',
 CDS_PART_NAME='Q_RES_0402LF-100K,1%,1/16W,CHIP,CS41002FB09',
 PART_NUMBER='CS41002FB09',
 VALUE='100K',
 PRIM_FILE='./archive_libs/logical/q_res/chips/chips.prt';

PART_NAME
 R3233 'Q_RES_0402LF-0,5%,1/16W,CHIP,CS00002JB13':;

SECTION_NUMBER 1
 '@T6G_MB_LIB.T6G(SCH_1):PAGE336_I153@PURE_QUANTA.Q_RES(CHIPS)':
 C_PATH='@t6g_mb_lib.t6g(sch_1):page336_i153@pure_quanta.q_res(chips)',
 P_PATH='@t6g_mb_lib.t6g(sch_1):page132_i153@pure_quanta.q_res(chips)',
 PATH='I153',
 DRAWING='@T6G_MB_LIB.T6G(SCH_1):PAGE336',
 WATTAGE='1/16W',
 TOLERANCE='5%',
 MATERIAL='CHIP',
 PHYS_PAGE='132',
 XY='(-800,2275)',
 ROT='0',
 VER='1',
 PACK_TYPE='0402LF',
 LOCATION='R3233',
 CDS_LIB='pure_quanta',
 CDS_PART_NAME='Q_RES_0402LF-0,5%,1/16W,CHIP,CS00002JB13',
 PART_NUMBER='CS00002JB13',
 VALUE='0',
 PRIM_FILE='./archive_libs/logical/q_res/chips/chips.prt';

PART_NAME
 R3234 'Q_RES_0402LF-33.2,1%,1/16W,CHIP,CS03322FB03':;

SECTION_NUMBER 1
 '@T6G_MB_LIB.T6G(SCH_1):PAGE342_I6@PURE_QUANTA.Q_RES(CHIPS)':
 C_PATH='@t6g_mb_lib.t6g(sch_1):page342_i6@pure_quanta.q_res(chips)',
 P_PATH='@t6g_mb_lib.t6g(sch_1):page139_i6@pure_quanta.q_res(chips)',
 PATH='I6',
 DRAWING='@T6G_MB_LIB.T6G(SCH_1):PAGE342',
 WATTAGE='1/16W',
 TOLERANCE='1%',
 MATERIAL='CHIP',
 PHYS_PAGE='139',
 XY='(4300,-3175)',
 ROT='0',
 VER='1',
 PACK_TYPE='0402LF',
 LOCATION='R3234',
 CDS_LIB='pure_quanta',
 CDS_PART_NAME='Q_RES_0402LF-33.2,1%,1/16W,CHIP,CS03322FB03',
 PART_NUMBER='CS03322FB03',
 VALUE='33.2',
 PRIM_FILE='./archive_libs/logical/q_res/chips/chips.prt';

PART_NAME
 R3235 'Q_RES_0402LF-100K,1%,1/16W,CHIP,CS41002FB09':;

SECTION_NUMBER 1
 '@T6G_MB_LIB.T6G(SCH_1):PAGE342_I24@PURE_QUANTA.Q_RES(CHIPS)':
 C_PATH='@t6g_mb_lib.t6g(sch_1):page342_i24@pure_quanta.q_res(chips)',
 P_PATH='@t6g_mb_lib.t6g(sch_1):page139_i24@pure_quanta.q_res(chips)',
 PATH='I24',
 DRAWING='@T6G_MB_LIB.T6G(SCH_1):PAGE342',
 WATTAGE='1/16W',
 TOLERANCE='1%',
 MATERIAL='CHIP',
 PHYS_PAGE='139',
 XY='(6825,-3325)',
 ROT='0',
 VER='2',
 PACK_TYPE='0402LF',
 LOCATION='R3235',
 CDS_LIB='pure_quanta',
 CDS_PART_NAME='Q_RES_0402LF-100K,1%,1/16W,CHIP,CS41002FB09',
 PART_NUMBER='CS41002FB09',
 VALUE='100K',
 PRIM_FILE='./archive_libs/logical/q_res/chips/chips.prt';

PART_NAME
 R3236 'Q_RES_0402LF-0,5%,1/16W,CHIP,CS00002JB13':;

SECTION_NUMBER 1
 '@T6G_MB_LIB.T6G(SCH_1):PAGE342_I25@PURE_QUANTA.Q_RES(CHIPS)':
 C_PATH='@t6g_mb_lib.t6g(sch_1):page342_i25@pure_quanta.q_res(chips)',
 P_PATH='@t6g_mb_lib.t6g(sch_1):page139_i25@pure_quanta.q_res(chips)',
 PATH='I25',
 DRAWING='@T6G_MB_LIB.T6G(SCH_1):PAGE342',
 WATTAGE='1/16W',
 TOLERANCE='5%',
 MATERIAL='CHIP',
 PHYS_PAGE='139',
 XY='(7100,-3125)',
 ROT='0',
 VER='1',
 PACK_TYPE='0402LF',
 LOCATION='R3236',
 CDS_LIB='pure_quanta',
 CDS_PART_NAME='Q_RES_0402LF-0,5%,1/16W,CHIP,CS00002JB13',
 PART_NUMBER='CS00002JB13',
 VALUE='0',
 PRIM_FILE='./archive_libs/logical/q_res/chips/chips.prt';

PART_NAME
 R3237 'Q_RES_0402LF-0,5%,1/16W,CHIP,CS00002JB13':;

SECTION_NUMBER 1
 '@T6G_MB_LIB.T6G(SCH_1):PAGE336_I156@PURE_QUANTA.Q_RES(CHIPS)':
 C_PATH='@t6g_mb_lib.t6g(sch_1):page336_i156@pure_quanta.q_res(chips)',
 P_PATH='@t6g_mb_lib.t6g(sch_1):page132_i156@pure_quanta.q_res(chips)',
 PATH='I156',
 DRAWING='@T6G_MB_LIB.T6G(SCH_1):PAGE336',
 WATTAGE='1/16W',
 TOLERANCE='5%',
 MATERIAL='CHIP',
 PHYS_PAGE='132',
 XY='(2900,6725)',
 ROT='1',
 VER='1',
 PACK_TYPE='0402LF',
 LOCATION='R3237',
 CDS_LIB='pure_quanta',
 CDS_PART_NAME='Q_RES_0402LF-0,5%,1/16W,CHIP,CS00002JB13',
 PART_NUMBER='CS00002JB13',
 VALUE='0',
 PRIM_FILE='./archive_libs/logical/q_res/chips/chips.prt';

PART_NAME
 R3238 'Q_RES_0402LF-33.2,1%,1/16W,CHIP,CS03322FB03':;

SECTION_NUMBER 1
 '@T6G_MB_LIB.T6G(SCH_1):PAGE348_I103@PURE_QUANTA.Q_RES(CHIPS)':
 C_PATH='@t6g_mb_lib.t6g(sch_1):page348_i103@pure_quanta.q_res(chips)',
 P_PATH='@t6g_mb_lib.t6g(sch_1):page150_i103@pure_quanta.q_res(chips)',
 PATH='I103',
 DRAWING='@T6G_MB_LIB.T6G(SCH_1):PAGE348',
 WATTAGE='1/16W',
 TOLERANCE='1%',
 MATERIAL='CHIP',
 PHYS_PAGE='150',
 XY='(-14925,8675)',
 ROT='0',
 VER='1',
 PACK_TYPE='0402LF',
 LOCATION='R3238',
 CDS_LIB='pure_quanta',
 CDS_PART_NAME='Q_RES_0402LF-33.2,1%,1/16W,CHIP,CS03322FB03',
 PART_NUMBER='CS03322FB03',
 VALUE='33.2',
 PRIM_FILE='./archive_libs/logical/q_res/chips/chips.prt';

PART_NAME
 R3239 'Q_RES_0402LF-33.2,1%,1/16W,CHIP,CS03322FB03':;

SECTION_NUMBER 1
 '@T6G_MB_LIB.T6G(SCH_1):PAGE348_I102@PURE_QUANTA.Q_RES(CHIPS)':
 C_PATH='@t6g_mb_lib.t6g(sch_1):page348_i102@pure_quanta.q_res(chips)',
 P_PATH='@t6g_mb_lib.t6g(sch_1):page150_i102@pure_quanta.q_res(chips)',
 PATH='I102',
 DRAWING='@T6G_MB_LIB.T6G(SCH_1):PAGE348',
 WATTAGE='1/16W',
 TOLERANCE='1%',
 MATERIAL='CHIP',
 PHYS_PAGE='150',
 XY='(-14925,8625)',
 ROT='0',
 VER='1',
 PACK_TYPE='0402LF',
 LOCATION='R3239',
 CDS_LIB='pure_quanta',
 CDS_PART_NAME='Q_RES_0402LF-33.2,1%,1/16W,CHIP,CS03322FB03',
 PART_NUMBER='CS03322FB03',
 VALUE='33.2',
 PRIM_FILE='./archive_libs/logical/q_res/chips/chips.prt';

PART_NAME
 R3240 'Q_RES_0402LF-2.2K,5%,1/16W,EMPTY,CS22202JB07':;

SECTION_NUMBER 1
 '@T6G_MB_LIB.T6G(SCH_1):PAGE349_I120@PURE_QUANTA.Q_RES(CHIPS)':
 C_PATH='@t6g_mb_lib.t6g(sch_1):page349_i120@pure_quanta.q_res(chips)',
 P_PATH='@t6g_mb_lib.t6g(sch_1):page151_i120@pure_quanta.q_res(chips)',
 PATH='I120',
 DRAWING='@T6G_MB_LIB.T6G(SCH_1):PAGE349',
 WATTAGE='1/16W',
 TOLERANCE='5%',
 MATERIAL='EMPTY',
 PHYS_PAGE='151',
 XY='(4275,2425)',
 ROT='0',
 VER='1',
 PACK_TYPE='0402LF',
 LOCATION='R3240',
 CDS_LIB='pure_quanta',
 CDS_PART_NAME='Q_RES_0402LF-2.2K,5%,1/16W,EMPTY,CS22202JB07',
 PART_NUMBER='CS22202JB07',
 VALUE='2.2K',
 PRIM_FILE='./archive_libs/logical/q_res/chips/chips.prt';

PART_NAME
 R3241 'Q_RES_0402LF-2.2K,5%,1/16W,EMPTY,CS22202JB07':;

SECTION_NUMBER 1
 '@T6G_MB_LIB.T6G(SCH_1):PAGE349_I149@PURE_QUANTA.Q_RES(CHIPS)':
 C_PATH='@t6g_mb_lib.t6g(sch_1):page349_i149@pure_quanta.q_res(chips)',
 P_PATH='@t6g_mb_lib.t6g(sch_1):page151_i149@pure_quanta.q_res(chips)',
 PATH='I149',
 DRAWING='@T6G_MB_LIB.T6G(SCH_1):PAGE349',
 WATTAGE='1/16W',
 TOLERANCE='5%',
 MATERIAL='EMPTY',
 PHYS_PAGE='151',
 XY='(4275,2375)',
 ROT='0',
 VER='1',
 PACK_TYPE='0402LF',
 LOCATION='R3241',
 CDS_LIB='pure_quanta',
 CDS_PART_NAME='Q_RES_0402LF-2.2K,5%,1/16W,EMPTY,CS22202JB07',
 PART_NUMBER='CS22202JB07',
 VALUE='2.2K',
 PRIM_FILE='./archive_libs/logical/q_res/chips/chips.prt';

PART_NAME
 R3242 'Q_RES_0402LF-2.2K,5%,1/16W,EMPTY,CS22202JB07':;

SECTION_NUMBER 1
 '@T6G_MB_LIB.T6G(SCH_1):PAGE349_I119@PURE_QUANTA.Q_RES(CHIPS)':
 C_PATH='@t6g_mb_lib.t6g(sch_1):page349_i119@pure_quanta.q_res(chips)',
 P_PATH='@t6g_mb_lib.t6g(sch_1):page151_i119@pure_quanta.q_res(chips)',
 PATH='I119',
 DRAWING='@T6G_MB_LIB.T6G(SCH_1):PAGE349',
 WATTAGE='1/16W',
 TOLERANCE='5%',
 MATERIAL='EMPTY',
 PHYS_PAGE='151',
 XY='(4275,2125)',
 ROT='0',
 VER='1',
 PACK_TYPE='0402LF',
 LOCATION='R3242',
 CDS_LIB='pure_quanta',
 CDS_PART_NAME='Q_RES_0402LF-2.2K,5%,1/16W,EMPTY,CS22202JB07',
 PART_NUMBER='CS22202JB07',
 VALUE='2.2K',
 PRIM_FILE='./archive_libs/logical/q_res/chips/chips.prt';

PART_NAME
 R3243 'Q_RES_0402LF-2.2K,5%,1/16W,EMPTY,CS22202JB07':;

SECTION_NUMBER 1
 '@T6G_MB_LIB.T6G(SCH_1):PAGE349_I115@PURE_QUANTA.Q_RES(CHIPS)':
 C_PATH='@t6g_mb_lib.t6g(sch_1):page349_i115@pure_quanta.q_res(chips)',
 P_PATH='@t6g_mb_lib.t6g(sch_1):page151_i115@pure_quanta.q_res(chips)',
 PATH='I115',
 DRAWING='@T6G_MB_LIB.T6G(SCH_1):PAGE349',
 WATTAGE='1/16W',
 TOLERANCE='5%',
 MATERIAL='EMPTY',
 PHYS_PAGE='151',
 XY='(4275,2075)',
 ROT='0',
 VER='1',
 PACK_TYPE='0402LF',
 LOCATION='R3243',
 CDS_LIB='pure_quanta',
 CDS_PART_NAME='Q_RES_0402LF-2.2K,5%,1/16W,EMPTY,CS22202JB07',
 PART_NUMBER='CS22202JB07',
 VALUE='2.2K',
 PRIM_FILE='./archive_libs/logical/q_res/chips/chips.prt';

PART_NAME
 R3244 'Q_RES_0402LF-0,5%,1/16W,CHIP,CS00002JB13':;

SECTION_NUMBER 1
 '@T6G_MB_LIB.T6G(SCH_1):PAGE307_I79@PURE_QUANTA.Q_RES(CHIPS)':
 C_PATH='@t6g_mb_lib.t6g(sch_1):page307_i79@pure_quanta.q_res(chips)',
 P_PATH='@t6g_mb_lib.t6g(sch_1):page138_i79@pure_quanta.q_res(chips)',
 PATH='I79',
 DRAWING='@T6G_MB_LIB.T6G(SCH_1):PAGE307',
 WATTAGE='1/16W',
 TOLERANCE='5%',
 MATERIAL='CHIP',
 PHYS_PAGE='138',
 XY='(3275,2275)',
 ROT='1',
 VER='1',
 PACK_TYPE='0402LF',
 LOCATION='R3244',
 CDS_LIB='pure_quanta',
 CDS_PART_NAME='Q_RES_0402LF-0,5%,1/16W,CHIP,CS00002JB13',
 PART_NUMBER='CS00002JB13',
 VALUE='0',
 PRIM_FILE='./archive_libs/logical/q_res/chips/chips.prt';

PART_NAME
 R3254 'Q_RES_0402LF-0,5%,1/16W,EMPTY,CS00002JB13':;

SECTION_NUMBER 1
 '@T6G_MB_LIB.T6G(SCH_1):PAGE348_I50@PURE_QUANTA.Q_RES(CHIPS)':
 C_PATH='@t6g_mb_lib.t6g(sch_1):page348_i50@pure_quanta.q_res(chips)',
 P_PATH='@t6g_mb_lib.t6g(sch_1):page150_i50@pure_quanta.q_res(chips)',
 PATH='I50',
 DRAWING='@T6G_MB_LIB.T6G(SCH_1):PAGE348',
 WATTAGE='1/16W',
 TOLERANCE='5%',
 MATERIAL='EMPTY',
 PHYS_PAGE='150',
 XY='(-9525,5125)',
 ROT='0',
 VER='1',
 PACK_TYPE='0402LF',
 LOCATION='R3254',
 CDS_LIB='pure_quanta',
 CDS_PART_NAME='Q_RES_0402LF-0,5%,1/16W,EMPTY,CS00002JB13',
 PART_NUMBER='CS00002JB13',
 VALUE='0',
 PRIM_FILE='./archive_libs/logical/q_res/chips/chips.prt';

PART_NAME
 R3263 'Q_RES_0402LF-0,5%,1/16W,EMPTY,CS00002JB13':;

SECTION_NUMBER 1
 '@T6G_MB_LIB.T6G(SCH_1):PAGE248_I35@PURE_QUANTA.Q_RES(CHIPS)':
 C_PATH='@t6g_mb_lib.t6g(sch_1):page248_i35@pure_quanta.q_res(chips)',
 P_PATH='@t6g_mb_lib.t6g(sch_1):page247_i35@pure_quanta.q_res(chips)',
 PATH='I35',
 DRAWING='@T6G_MB_LIB.T6G(SCH_1):PAGE248',
 WATTAGE='1/16W',
 TOLERANCE='5%',
 MATERIAL='EMPTY',
 PHYS_PAGE='247',
 XY='(-3450,4850)',
 ROT='0',
 VER='1',
 PACK_TYPE='0402LF',
 LOCATION='R3263',
 CDS_LIB='pure_quanta',
 CDS_PART_NAME='Q_RES_0402LF-0,5%,1/16W,EMPTY,CS00002JB13',
 PART_NUMBER='CS00002JB13',
 VALUE='0',
 PRIM_FILE='./archive_libs/logical/q_res/chips/chips.prt';

PART_NAME
 R3264 'Q_RES_0402LF-0,5%,1/16W,EMPTY,CS00002JB13':;

SECTION_NUMBER 1
 '@T6G_MB_LIB.T6G(SCH_1):PAGE248_I38@PURE_QUANTA.Q_RES(CHIPS)':
 C_PATH='@t6g_mb_lib.t6g(sch_1):page248_i38@pure_quanta.q_res(chips)',
 P_PATH='@t6g_mb_lib.t6g(sch_1):page247_i38@pure_quanta.q_res(chips)',
 PATH='I38',
 DRAWING='@T6G_MB_LIB.T6G(SCH_1):PAGE248',
 WATTAGE='1/16W',
 TOLERANCE='5%',
 MATERIAL='EMPTY',
 PHYS_PAGE='247',
 XY='(-3375,3025)',
 ROT='0',
 VER='1',
 PACK_TYPE='0402LF',
 LOCATION='R3264',
 CDS_LIB='pure_quanta',
 CDS_PART_NAME='Q_RES_0402LF-0,5%,1/16W,EMPTY,CS00002JB13',
 PART_NUMBER='CS00002JB13',
 VALUE='0',
 PRIM_FILE='./archive_libs/logical/q_res/chips/chips.prt';

PART_NAME
 R3265 'Q_RES_0402LF-4.7K,1%,1/16W,EMPTY,CS24702FB06':
 ROOM='PCIE REDRIVER BOM1';

SECTION_NUMBER 1
 '@T6G_MB_LIB.T6G(SCH_1):PAGE110_I81@PURE_QUANTA.Q_RES(CHIPS)':
 C_PATH='@t6g_mb_lib.t6g(sch_1):page110_i81@pure_quanta.q_res(chips)',
 P_PATH='@t6g_mb_lib.t6g(sch_1):page111_i81@pure_quanta.q_res(chips)',
 PATH='I81',
 DRAWING='@T6G_MB_LIB.T6G(SCH_1):PAGE110',
 WATTAGE='1/16W',
 TOLERANCE='1%',
 MATERIAL='EMPTY',
 PHYS_PAGE='111',
 XY='(9575,3925)',
 ROT='0',
 VER='2',
 PACK_TYPE='0402LF',
 LOCATION='R3265',
 CDS_LIB='pure_quanta',
 CDS_PART_NAME='Q_RES_0402LF-4.7K,1%,1/16W,EMPTY,CS24702FB06',
 ROOM='PCIE REDRIVER BOM1',
 PART_NUMBER='CS24702FB06',
 VALUE='4.7K',
 PRIM_FILE='./archive_libs/logical/q_res/chips/chips.prt';

PART_NAME
 R3266 'Q_RES_0402LF-4.7K,1%,1/16W,CHIP,CS24702FB06':
 ROOM='PCIE REDRIVER BOM1';

SECTION_NUMBER 1
 '@T6G_MB_LIB.T6G(SCH_1):PAGE110_I93@PURE_QUANTA.Q_RES(CHIPS)':
 C_PATH='@t6g_mb_lib.t6g(sch_1):page110_i93@pure_quanta.q_res(chips)',
 P_PATH='@t6g_mb_lib.t6g(sch_1):page111_i93@pure_quanta.q_res(chips)',
 PATH='I93',
 DRAWING='@T6G_MB_LIB.T6G(SCH_1):PAGE110',
 WATTAGE='1/16W',
 TOLERANCE='1%',
 MATERIAL='CHIP',
 PHYS_PAGE='111',
 XY='(9600,5900)',
 ROT='0',
 VER='2',
 PACK_TYPE='0402LF',
 LOCATION='R3266',
 CDS_LIB='pure_quanta',
 CDS_PART_NAME='Q_RES_0402LF-4.7K,1%,1/16W,CHIP,CS24702FB06',
 ROOM='PCIE REDRIVER BOM1',
 PART_NUMBER='CS24702FB06',
 VALUE='4.7K',
 PRIM_FILE='./archive_libs/logical/q_res/chips/chips.prt';

PART_NAME
 R3267 'Q_RES_0402LF-68K,1%,1/16W,EMPTY,CS36802FB04':
 ROOM='PCIE REDRIVER BOM1';

SECTION_NUMBER 1
 '@T6G_MB_LIB.T6G(SCH_1):PAGE110_I8@PURE_QUANTA.Q_RES(CHIPS)':
 C_PATH='@t6g_mb_lib.t6g(sch_1):page110_i8@pure_quanta.q_res(chips)',
 P_PATH='@t6g_mb_lib.t6g(sch_1):page111_i8@pure_quanta.q_res(chips)',
 PATH='I8',
 DRAWING='@T6G_MB_LIB.T6G(SCH_1):PAGE110',
 WATTAGE='1/16W',
 TOLERANCE='1%',
 MATERIAL='EMPTY',
 PHYS_PAGE='111',
 XY='(2000,2725)',
 ROT='0',
 VER='2',
 PACK_TYPE='0402LF',
 LOCATION='R3267',
 CDS_LIB='pure_quanta',
 CDS_PART_NAME='Q_RES_0402LF-68K,1%,1/16W,EMPTY,CS36802FB04',
 ROOM='PCIE REDRIVER BOM1',
 PART_NUMBER='CS36802FB04',
 VALUE='68K',
 PRIM_FILE='./archive_libs/logical/q_res/chips/chips.prt';

PART_NAME
 R3268 'Q_RES_0402LF-68K,1%,1/16W,EMPTY,CS36802FB04':
 ROOM='PCIE REDRIVER BOM1';

SECTION_NUMBER 1
 '@T6G_MB_LIB.T6G(SCH_1):PAGE110_I2@PURE_QUANTA.Q_RES(CHIPS)':
 C_PATH='@t6g_mb_lib.t6g(sch_1):page110_i2@pure_quanta.q_res(chips)',
 P_PATH='@t6g_mb_lib.t6g(sch_1):page111_i2@pure_quanta.q_res(chips)',
 PATH='I2',
 DRAWING='@T6G_MB_LIB.T6G(SCH_1):PAGE110',
 WATTAGE='1/16W',
 TOLERANCE='1%',
 MATERIAL='EMPTY',
 PHYS_PAGE='111',
 XY='(2175,1000)',
 ROT='0',
 VER='2',
 PACK_TYPE='0402LF',
 LOCATION='R3268',
 CDS_LIB='pure_quanta',
 CDS_PART_NAME='Q_RES_0402LF-68K,1%,1/16W,EMPTY,CS36802FB04',
 ROOM='PCIE REDRIVER BOM1',
 PART_NUMBER='CS36802FB04',
 VALUE='68K',
 PRIM_FILE='./archive_libs/logical/q_res/chips/chips.prt';

PART_NAME
 R3269 'Q_RES_0402LF-1K,1%,1/16W,EMPTY,CS21002FB06':
 ROOM='PCIE REDRIVER BOM1';

SECTION_NUMBER 1
 '@T6G_MB_LIB.T6G(SCH_1):PAGE110_I14@PURE_QUANTA.Q_RES(CHIPS)':
 C_PATH='@t6g_mb_lib.t6g(sch_1):page110_i14@pure_quanta.q_res(chips)',
 P_PATH='@t6g_mb_lib.t6g(sch_1):page111_i14@pure_quanta.q_res(chips)',
 PATH='I14',
 DRAWING='@T6G_MB_LIB.T6G(SCH_1):PAGE110',
 WATTAGE='1/16W',
 TOLERANCE='1%',
 MATERIAL='EMPTY',
 PHYS_PAGE='111',
 XY='(2375,3250)',
 ROT='0',
 VER='2',
 PACK_TYPE='0402LF',
 LOCATION='R3269',
 CDS_LIB='pure_quanta',
 CDS_PART_NAME='Q_RES_0402LF-1K,1%,1/16W,EMPTY,CS21002FB06',
 ROOM='PCIE REDRIVER BOM1',
 PART_NUMBER='CS21002FB06',
 VALUE='1K',
 PRIM_FILE='./archive_libs/logical/q_res/chips/chips.prt';

PART_NAME
 R3270 'Q_RES_0402LF-1K,1%,1/16W,EMPTY,CS21002FB06':
 ROOM='PCIE REDRIVER BOM1';

SECTION_NUMBER 1
 '@T6G_MB_LIB.T6G(SCH_1):PAGE110_I9@PURE_QUANTA.Q_RES(CHIPS)':
 C_PATH='@t6g_mb_lib.t6g(sch_1):page110_i9@pure_quanta.q_res(chips)',
 P_PATH='@t6g_mb_lib.t6g(sch_1):page111_i9@pure_quanta.q_res(chips)',
 PATH='I9',
 DRAWING='@T6G_MB_LIB.T6G(SCH_1):PAGE110',
 WATTAGE='1/16W',
 TOLERANCE='1%',
 MATERIAL='EMPTY',
 PHYS_PAGE='111',
 XY='(2375,2725)',
 ROT='0',
 VER='2',
 PACK_TYPE='0402LF',
 LOCATION='R3270',
 CDS_LIB='pure_quanta',
 CDS_PART_NAME='Q_RES_0402LF-1K,1%,1/16W,EMPTY,CS21002FB06',
 ROOM='PCIE REDRIVER BOM1',
 PART_NUMBER='CS21002FB06',
 VALUE='1K',
 PRIM_FILE='./archive_libs/logical/q_res/chips/chips.prt';

PART_NAME
 R3271 'Q_RES_0402LF-1K,1%,1/16W,EMPTY,CS21002FB06':
 ROOM='PCIE REDRIVER BOM1';

SECTION_NUMBER 1
 '@T6G_MB_LIB.T6G(SCH_1):PAGE110_I5@PURE_QUANTA.Q_RES(CHIPS)':
 C_PATH='@t6g_mb_lib.t6g(sch_1):page110_i5@pure_quanta.q_res(chips)',
 P_PATH='@t6g_mb_lib.t6g(sch_1):page111_i5@pure_quanta.q_res(chips)',
 PATH='I5',
 DRAWING='@T6G_MB_LIB.T6G(SCH_1):PAGE110',
 WATTAGE='1/16W',
 TOLERANCE='1%',
 MATERIAL='EMPTY',
 PHYS_PAGE='111',
 XY='(2550,1525)',
 ROT='0',
 VER='2',
 PACK_TYPE='0402LF',
 LOCATION='R3271',
 CDS_LIB='pure_quanta',
 CDS_PART_NAME='Q_RES_0402LF-1K,1%,1/16W,EMPTY,CS21002FB06',
 ROOM='PCIE REDRIVER BOM1',
 PART_NUMBER='CS21002FB06',
 VALUE='1K',
 PRIM_FILE='./archive_libs/logical/q_res/chips/chips.prt';

PART_NAME
 R3272 'Q_RES_0402LF-1K,1%,1/16W,EMPTY,CS21002FB06':
 ROOM='PCIE REDRIVER BOM1';

SECTION_NUMBER 1
 '@T6G_MB_LIB.T6G(SCH_1):PAGE110_I4@PURE_QUANTA.Q_RES(CHIPS)':
 C_PATH='@t6g_mb_lib.t6g(sch_1):page110_i4@pure_quanta.q_res(chips)',
 P_PATH='@t6g_mb_lib.t6g(sch_1):page111_i4@pure_quanta.q_res(chips)',
 PATH='I4',
 DRAWING='@T6G_MB_LIB.T6G(SCH_1):PAGE110',
 WATTAGE='1/16W',
 TOLERANCE='1%',
 MATERIAL='EMPTY',
 PHYS_PAGE='111',
 XY='(2550,1000)',
 ROT='0',
 VER='2',
 PACK_TYPE='0402LF',
 LOCATION='R3272',
 CDS_LIB='pure_quanta',
 CDS_PART_NAME='Q_RES_0402LF-1K,1%,1/16W,EMPTY,CS21002FB06',
 ROOM='PCIE REDRIVER BOM1',
 PART_NUMBER='CS21002FB06',
 VALUE='1K',
 PRIM_FILE='./archive_libs/logical/q_res/chips/chips.prt';

PART_NAME
 R3273 'Q_RES_0402LF-68K,1%,1/16W,EMPTY,CS36802FB04':
 ROOM='PCIE REDRIVER BOM1';

SECTION_NUMBER 1
 '@T6G_MB_LIB.T6G(SCH_1):PAGE110_I12@PURE_QUANTA.Q_RES(CHIPS)':
 C_PATH='@t6g_mb_lib.t6g(sch_1):page110_i12@pure_quanta.q_res(chips)',
 P_PATH='@t6g_mb_lib.t6g(sch_1):page111_i12@pure_quanta.q_res(chips)',
 PATH='I12',
 DRAWING='@T6G_MB_LIB.T6G(SCH_1):PAGE110',
 WATTAGE='1/16W',
 TOLERANCE='1%',
 MATERIAL='EMPTY',
 PHYS_PAGE='111',
 XY='(2850,2700)',
 ROT='0',
 VER='2',
 PACK_TYPE='0402LF',
 LOCATION='R3273',
 CDS_LIB='pure_quanta',
 CDS_PART_NAME='Q_RES_0402LF-68K,1%,1/16W,EMPTY,CS36802FB04',
 ROOM='PCIE REDRIVER BOM1',
 PART_NUMBER='CS36802FB04',
 VALUE='68K',
 PRIM_FILE='./archive_libs/logical/q_res/chips/chips.prt';

PART_NAME
 R3274 'Q_RES_0402LF-68K,1%,1/16W,EMPTY,CS36802FB04':
 ROOM='PCIE REDRIVER BOM1';

SECTION_NUMBER 1
 '@T6G_MB_LIB.T6G(SCH_1):PAGE110_I16@PURE_QUANTA.Q_RES(CHIPS)':
 C_PATH='@t6g_mb_lib.t6g(sch_1):page110_i16@pure_quanta.q_res(chips)',
 P_PATH='@t6g_mb_lib.t6g(sch_1):page111_i16@pure_quanta.q_res(chips)',
 PATH='I16',
 DRAWING='@T6G_MB_LIB.T6G(SCH_1):PAGE110',
 WATTAGE='1/16W',
 TOLERANCE='1%',
 MATERIAL='EMPTY',
 PHYS_PAGE='111',
 XY='(3025,975)',
 ROT='0',
 VER='2',
 PACK_TYPE='0402LF',
 LOCATION='R3274',
 CDS_LIB='pure_quanta',
 CDS_PART_NAME='Q_RES_0402LF-68K,1%,1/16W,EMPTY,CS36802FB04',
 ROOM='PCIE REDRIVER BOM1',
 PART_NUMBER='CS36802FB04',
 VALUE='68K',
 PRIM_FILE='./archive_libs/logical/q_res/chips/chips.prt';

PART_NAME
 R3275 'Q_RES_0402LF-1K,1%,1/16W,EMPTY,CS21002FB06':
 ROOM='PCIE REDRIVER BOM1';

SECTION_NUMBER 1
 '@T6G_MB_LIB.T6G(SCH_1):PAGE110_I32@PURE_QUANTA.Q_RES(CHIPS)':
 C_PATH='@t6g_mb_lib.t6g(sch_1):page110_i32@pure_quanta.q_res(chips)',
 P_PATH='@t6g_mb_lib.t6g(sch_1):page111_i32@pure_quanta.q_res(chips)',
 PATH='I32',
 DRAWING='@T6G_MB_LIB.T6G(SCH_1):PAGE110',
 WATTAGE='1/16W',
 TOLERANCE='1%',
 MATERIAL='EMPTY',
 PHYS_PAGE='111',
 XY='(3250,3250)',
 ROT='0',
 VER='2',
 PACK_TYPE='0402LF',
 LOCATION='R3275',
 CDS_LIB='pure_quanta',
 CDS_PART_NAME='Q_RES_0402LF-1K,1%,1/16W,EMPTY,CS21002FB06',
 ROOM='PCIE REDRIVER BOM1',
 PART_NUMBER='CS21002FB06',
 VALUE='1K',
 PRIM_FILE='./archive_libs/logical/q_res/chips/chips.prt';

PART_NAME
 R3276 'Q_RES_0402LF-1K,1%,1/16W,EMPTY,CS21002FB06':
 ROOM='PCIE REDRIVER BOM1';

SECTION_NUMBER 1
 '@T6G_MB_LIB.T6G(SCH_1):PAGE110_I29@PURE_QUANTA.Q_RES(CHIPS)':
 C_PATH='@t6g_mb_lib.t6g(sch_1):page110_i29@pure_quanta.q_res(chips)',
 P_PATH='@t6g_mb_lib.t6g(sch_1):page111_i29@pure_quanta.q_res(chips)',
 PATH='I29',
 DRAWING='@T6G_MB_LIB.T6G(SCH_1):PAGE110',
 WATTAGE='1/16W',
 TOLERANCE='1%',
 MATERIAL='EMPTY',
 PHYS_PAGE='111',
 XY='(3250,2675)',
 ROT='0',
 VER='2',
 PACK_TYPE='0402LF',
 LOCATION='R3276',
 CDS_LIB='pure_quanta',
 CDS_PART_NAME='Q_RES_0402LF-1K,1%,1/16W,EMPTY,CS21002FB06',
 ROOM='PCIE REDRIVER BOM1',
 PART_NUMBER='CS21002FB06',
 VALUE='1K',
 PRIM_FILE='./archive_libs/logical/q_res/chips/chips.prt';

PART_NAME
 R3277 'Q_RES_0402LF-1K,1%,1/16W,EMPTY,CS21002FB06':
 ROOM='PCIE REDRIVER BOM1';

SECTION_NUMBER 1
 '@T6G_MB_LIB.T6G(SCH_1):PAGE110_I19@PURE_QUANTA.Q_RES(CHIPS)':
 C_PATH='@t6g_mb_lib.t6g(sch_1):page110_i19@pure_quanta.q_res(chips)',
 P_PATH='@t6g_mb_lib.t6g(sch_1):page111_i19@pure_quanta.q_res(chips)',
 PATH='I19',
 DRAWING='@T6G_MB_LIB.T6G(SCH_1):PAGE110',
 WATTAGE='1/16W',
 TOLERANCE='1%',
 MATERIAL='EMPTY',
 PHYS_PAGE='111',
 XY='(3425,1525)',
 ROT='0',
 VER='2',
 PACK_TYPE='0402LF',
 LOCATION='R3277',
 CDS_LIB='pure_quanta',
 CDS_PART_NAME='Q_RES_0402LF-1K,1%,1/16W,EMPTY,CS21002FB06',
 ROOM='PCIE REDRIVER BOM1',
 PART_NUMBER='CS21002FB06',
 VALUE='1K',
 PRIM_FILE='./archive_libs/logical/q_res/chips/chips.prt';

PART_NAME
 R3278 'Q_RES_0402LF-1K,1%,1/16W,CHIP,CS21002FB06':
 ROOM='PCIE REDRIVER BOM1';

SECTION_NUMBER 1
 '@T6G_MB_LIB.T6G(SCH_1):PAGE110_I18@PURE_QUANTA.Q_RES(CHIPS)':
 C_PATH='@t6g_mb_lib.t6g(sch_1):page110_i18@pure_quanta.q_res(chips)',
 P_PATH='@t6g_mb_lib.t6g(sch_1):page111_i18@pure_quanta.q_res(chips)',
 PATH='I18',
 DRAWING='@T6G_MB_LIB.T6G(SCH_1):PAGE110',
 WATTAGE='1/16W',
 TOLERANCE='1%',
 MATERIAL='CHIP',
 PHYS_PAGE='111',
 XY='(3425,950)',
 ROT='0',
 VER='2',
 PACK_TYPE='0402LF',
 LOCATION='R3278',
 CDS_LIB='pure_quanta',
 CDS_PART_NAME='Q_RES_0402LF-1K,1%,1/16W,CHIP,CS21002FB06',
 ROOM='PCIE REDRIVER BOM1',
 PART_NUMBER='CS21002FB06',
 VALUE='1K',
 PRIM_FILE='./archive_libs/logical/q_res/chips/chips.prt';

PART_NAME
 R3279 'Q_RES_0402LF-68K,1%,1/16W,EMPTY,CS36802FB04':
 ROOM='PCIE REDRIVER BOM1';

SECTION_NUMBER 1
 '@T6G_MB_LIB.T6G(SCH_1):PAGE110_I22@PURE_QUANTA.Q_RES(CHIPS)':
 C_PATH='@t6g_mb_lib.t6g(sch_1):page110_i22@pure_quanta.q_res(chips)',
 P_PATH='@t6g_mb_lib.t6g(sch_1):page111_i22@pure_quanta.q_res(chips)',
 PATH='I22',
 DRAWING='@T6G_MB_LIB.T6G(SCH_1):PAGE110',
 WATTAGE='1/16W',
 TOLERANCE='1%',
 MATERIAL='EMPTY',
 PHYS_PAGE='111',
 XY='(4425,975)',
 ROT='0',
 VER='2',
 PACK_TYPE='0402LF',
 LOCATION='R3279',
 CDS_LIB='pure_quanta',
 CDS_PART_NAME='Q_RES_0402LF-68K,1%,1/16W,EMPTY,CS36802FB04',
 ROOM='PCIE REDRIVER BOM1',
 PART_NUMBER='CS36802FB04',
 VALUE='68K',
 PRIM_FILE='./archive_libs/logical/q_res/chips/chips.prt';

PART_NAME
 R3280 'Q_RES_0402LF-1K,1%,1/16W,EMPTY,CS21002FB06':
 ROOM='PCIE REDRIVER BOM1';

SECTION_NUMBER 1
 '@T6G_MB_LIB.T6G(SCH_1):PAGE110_I26@PURE_QUANTA.Q_RES(CHIPS)':
 C_PATH='@t6g_mb_lib.t6g(sch_1):page110_i26@pure_quanta.q_res(chips)',
 P_PATH='@t6g_mb_lib.t6g(sch_1):page111_i26@pure_quanta.q_res(chips)',
 PATH='I26',
 DRAWING='@T6G_MB_LIB.T6G(SCH_1):PAGE110',
 WATTAGE='1/16W',
 TOLERANCE='1%',
 MATERIAL='EMPTY',
 PHYS_PAGE='111',
 XY='(4800,1500)',
 ROT='0',
 VER='2',
 PACK_TYPE='0402LF',
 LOCATION='R3280',
 CDS_LIB='pure_quanta',
 CDS_PART_NAME='Q_RES_0402LF-1K,1%,1/16W,EMPTY,CS21002FB06',
 ROOM='PCIE REDRIVER BOM1',
 PART_NUMBER='CS21002FB06',
 VALUE='1K',
 PRIM_FILE='./archive_libs/logical/q_res/chips/chips.prt';

PART_NAME
 R3281 'Q_RES_0402LF-1K,1%,1/16W,EMPTY,CS21002FB06':
 ROOM='PCIE REDRIVER BOM1';

SECTION_NUMBER 1
 '@T6G_MB_LIB.T6G(SCH_1):PAGE110_I25@PURE_QUANTA.Q_RES(CHIPS)':
 C_PATH='@t6g_mb_lib.t6g(sch_1):page110_i25@pure_quanta.q_res(chips)',
 P_PATH='@t6g_mb_lib.t6g(sch_1):page111_i25@pure_quanta.q_res(chips)',
 PATH='I25',
 DRAWING='@T6G_MB_LIB.T6G(SCH_1):PAGE110',
 WATTAGE='1/16W',
 TOLERANCE='1%',
 MATERIAL='EMPTY',
 PHYS_PAGE='111',
 XY='(4800,975)',
 ROT='0',
 VER='2',
 PACK_TYPE='0402LF',
 LOCATION='R3281',
 CDS_LIB='pure_quanta',
 CDS_PART_NAME='Q_RES_0402LF-1K,1%,1/16W,EMPTY,CS21002FB06',
 ROOM='PCIE REDRIVER BOM1',
 PART_NUMBER='CS21002FB06',
 VALUE='1K',
 PRIM_FILE='./archive_libs/logical/q_res/chips/chips.prt';

PART_NAME
 R3282 'Q_RES_0402LF-68K,1%,1/16W,EMPTY,CS36802FB04':
 ROOM='PCIE REDRIVER BOM1';

SECTION_NUMBER 1
 '@T6G_MB_LIB.T6G(SCH_1):PAGE110_I34@PURE_QUANTA.Q_RES(CHIPS)':
 C_PATH='@t6g_mb_lib.t6g(sch_1):page110_i34@pure_quanta.q_res(chips)',
 P_PATH='@t6g_mb_lib.t6g(sch_1):page111_i34@pure_quanta.q_res(chips)',
 PATH='I34',
 DRAWING='@T6G_MB_LIB.T6G(SCH_1):PAGE110',
 WATTAGE='1/16W',
 TOLERANCE='1%',
 MATERIAL='EMPTY',
 PHYS_PAGE='111',
 XY='(5275,950)',
 ROT='0',
 VER='2',
 PACK_TYPE='0402LF',
 LOCATION='R3282',
 CDS_LIB='pure_quanta',
 CDS_PART_NAME='Q_RES_0402LF-68K,1%,1/16W,EMPTY,CS36802FB04',
 ROOM='PCIE REDRIVER BOM1',
 PART_NUMBER='CS36802FB04',
 VALUE='68K',
 PRIM_FILE='./archive_libs/logical/q_res/chips/chips.prt';

PART_NAME
 R3283 'Q_RES_0402LF-1K,1%,1/16W,EMPTY,CS21002FB06':
 ROOM='PCIE REDRIVER BOM1';

SECTION_NUMBER 1
 '@T6G_MB_LIB.T6G(SCH_1):PAGE110_I37@PURE_QUANTA.Q_RES(CHIPS)':
 C_PATH='@t6g_mb_lib.t6g(sch_1):page110_i37@pure_quanta.q_res(chips)',
 P_PATH='@t6g_mb_lib.t6g(sch_1):page111_i37@pure_quanta.q_res(chips)',
 PATH='I37',
 DRAWING='@T6G_MB_LIB.T6G(SCH_1):PAGE110',
 WATTAGE='1/16W',
 TOLERANCE='1%',
 MATERIAL='EMPTY',
 PHYS_PAGE='111',
 XY='(5675,1500)',
 ROT='0',
 VER='2',
 PACK_TYPE='0402LF',
 LOCATION='R3283',
 CDS_LIB='pure_quanta',
 CDS_PART_NAME='Q_RES_0402LF-1K,1%,1/16W,EMPTY,CS21002FB06',
 ROOM='PCIE REDRIVER BOM1',
 PART_NUMBER='CS21002FB06',
 VALUE='1K',
 PRIM_FILE='./archive_libs/logical/q_res/chips/chips.prt';

PART_NAME
 R3284 'Q_RES_0402LF-1K,1%,1/16W,CHIP,CS21002FB06':
 ROOM='PCIE REDRIVER BOM1';

SECTION_NUMBER 1
 '@T6G_MB_LIB.T6G(SCH_1):PAGE110_I36@PURE_QUANTA.Q_RES(CHIPS)':
 C_PATH='@t6g_mb_lib.t6g(sch_1):page110_i36@pure_quanta.q_res(chips)',
 P_PATH='@t6g_mb_lib.t6g(sch_1):page111_i36@pure_quanta.q_res(chips)',
 PATH='I36',
 DRAWING='@T6G_MB_LIB.T6G(SCH_1):PAGE110',
 WATTAGE='1/16W',
 TOLERANCE='1%',
 MATERIAL='CHIP',
 PHYS_PAGE='111',
 XY='(5675,925)',
 ROT='0',
 VER='2',
 PACK_TYPE='0402LF',
 LOCATION='R3284',
 CDS_LIB='pure_quanta',
 CDS_PART_NAME='Q_RES_0402LF-1K,1%,1/16W,CHIP,CS21002FB06',
 ROOM='PCIE REDRIVER BOM1',
 PART_NUMBER='CS21002FB06',
 VALUE='1K',
 PRIM_FILE='./archive_libs/logical/q_res/chips/chips.prt';

PART_NAME
 R3285 'Q_RES_0402LF-68K,1%,1/16W,EMPTY,CS36802FB04':
 ROOM='PCIE REDRIVER BOM1';

SECTION_NUMBER 1
 '@T6G_MB_LIB.T6G(SCH_1):PAGE110_I42@PURE_QUANTA.Q_RES(CHIPS)':
 C_PATH='@t6g_mb_lib.t6g(sch_1):page110_i42@pure_quanta.q_res(chips)',
 P_PATH='@t6g_mb_lib.t6g(sch_1):page111_i42@pure_quanta.q_res(chips)',
 PATH='I42',
 DRAWING='@T6G_MB_LIB.T6G(SCH_1):PAGE110',
 WATTAGE='1/16W',
 TOLERANCE='1%',
 MATERIAL='EMPTY',
 PHYS_PAGE='111',
 XY='(6450,2725)',
 ROT='0',
 VER='2',
 PACK_TYPE='0402LF',
 LOCATION='R3285',
 CDS_LIB='pure_quanta',
 CDS_PART_NAME='Q_RES_0402LF-68K,1%,1/16W,EMPTY,CS36802FB04',
 ROOM='PCIE REDRIVER BOM1',
 PART_NUMBER='CS36802FB04',
 VALUE='68K',
 PRIM_FILE='./archive_libs/logical/q_res/chips/chips.prt';

PART_NAME
 R3286 'Q_RES_0402LF-1K,1%,1/16W,EMPTY,CS21002FB06':
 ROOM='PCIE REDRIVER BOM1';

SECTION_NUMBER 1
 '@T6G_MB_LIB.T6G(SCH_1):PAGE110_I45@PURE_QUANTA.Q_RES(CHIPS)':
 C_PATH='@t6g_mb_lib.t6g(sch_1):page110_i45@pure_quanta.q_res(chips)',
 P_PATH='@t6g_mb_lib.t6g(sch_1):page111_i45@pure_quanta.q_res(chips)',
 PATH='I45',
 DRAWING='@T6G_MB_LIB.T6G(SCH_1):PAGE110',
 WATTAGE='1/16W',
 TOLERANCE='1%',
 MATERIAL='EMPTY',
 PHYS_PAGE='111',
 XY='(6825,3250)',
 ROT='0',
 VER='2',
 PACK_TYPE='0402LF',
 LOCATION='R3286',
 CDS_LIB='pure_quanta',
 CDS_PART_NAME='Q_RES_0402LF-1K,1%,1/16W,EMPTY,CS21002FB06',
 ROOM='PCIE REDRIVER BOM1',
 PART_NUMBER='CS21002FB06',
 VALUE='1K',
 PRIM_FILE='./archive_libs/logical/q_res/chips/chips.prt';

PART_NAME
 R3287 'Q_RES_0402LF-1K,1%,1/16W,EMPTY,CS21002FB06':
 ROOM='PCIE REDRIVER BOM1';

SECTION_NUMBER 1
 '@T6G_MB_LIB.T6G(SCH_1):PAGE110_I44@PURE_QUANTA.Q_RES(CHIPS)':
 C_PATH='@t6g_mb_lib.t6g(sch_1):page110_i44@pure_quanta.q_res(chips)',
 P_PATH='@t6g_mb_lib.t6g(sch_1):page111_i44@pure_quanta.q_res(chips)',
 PATH='I44',
 DRAWING='@T6G_MB_LIB.T6G(SCH_1):PAGE110',
 WATTAGE='1/16W',
 TOLERANCE='1%',
 MATERIAL='EMPTY',
 PHYS_PAGE='111',
 XY='(6825,2725)',
 ROT='0',
 VER='2',
 PACK_TYPE='0402LF',
 LOCATION='R3287',
 CDS_LIB='pure_quanta',
 CDS_PART_NAME='Q_RES_0402LF-1K,1%,1/16W,EMPTY,CS21002FB06',
 ROOM='PCIE REDRIVER BOM1',
 PART_NUMBER='CS21002FB06',
 VALUE='1K',
 PRIM_FILE='./archive_libs/logical/q_res/chips/chips.prt';

PART_NAME
 R3288 'Q_RES_0402LF-68K,1%,1/16W,EMPTY,CS36802FB04':
 ROOM='PCIE REDRIVER BOM1';

SECTION_NUMBER 1
 '@T6G_MB_LIB.T6G(SCH_1):PAGE110_I74@PURE_QUANTA.Q_RES(CHIPS)':
 C_PATH='@t6g_mb_lib.t6g(sch_1):page110_i74@pure_quanta.q_res(chips)',
 P_PATH='@t6g_mb_lib.t6g(sch_1):page111_i74@pure_quanta.q_res(chips)',
 PATH='I74',
 DRAWING='@T6G_MB_LIB.T6G(SCH_1):PAGE110',
 WATTAGE='1/16W',
 TOLERANCE='1%',
 MATERIAL='EMPTY',
 PHYS_PAGE='111',
 XY='(7300,2700)',
 ROT='0',
 VER='2',
 PACK_TYPE='0402LF',
 LOCATION='R3288',
 CDS_LIB='pure_quanta',
 CDS_PART_NAME='Q_RES_0402LF-68K,1%,1/16W,EMPTY,CS36802FB04',
 ROOM='PCIE REDRIVER BOM1',
 PART_NUMBER='CS36802FB04',
 VALUE='68K',
 PRIM_FILE='./archive_libs/logical/q_res/chips/chips.prt';

PART_NAME
 R3289 'Q_RES_0402LF-1K,1%,1/16W,EMPTY,CS21002FB06':
 ROOM='PCIE REDRIVER BOM1';

SECTION_NUMBER 1
 '@T6G_MB_LIB.T6G(SCH_1):PAGE110_I77@PURE_QUANTA.Q_RES(CHIPS)':
 C_PATH='@t6g_mb_lib.t6g(sch_1):page110_i77@pure_quanta.q_res(chips)',
 P_PATH='@t6g_mb_lib.t6g(sch_1):page111_i77@pure_quanta.q_res(chips)',
 PATH='I77',
 DRAWING='@T6G_MB_LIB.T6G(SCH_1):PAGE110',
 WATTAGE='1/16W',
 TOLERANCE='1%',
 MATERIAL='EMPTY',
 PHYS_PAGE='111',
 XY='(7700,3250)',
 ROT='0',
 VER='2',
 PACK_TYPE='0402LF',
 LOCATION='R3289',
 CDS_LIB='pure_quanta',
 CDS_PART_NAME='Q_RES_0402LF-1K,1%,1/16W,EMPTY,CS21002FB06',
 ROOM='PCIE REDRIVER BOM1',
 PART_NUMBER='CS21002FB06',
 VALUE='1K',
 PRIM_FILE='./archive_libs/logical/q_res/chips/chips.prt';

PART_NAME
 R3290 'Q_RES_0402LF-1K,1%,1/16W,EMPTY,CS21002FB06':
 ROOM='PCIE REDRIVER BOM1';

SECTION_NUMBER 1
 '@T6G_MB_LIB.T6G(SCH_1):PAGE110_I76@PURE_QUANTA.Q_RES(CHIPS)':
 C_PATH='@t6g_mb_lib.t6g(sch_1):page110_i76@pure_quanta.q_res(chips)',
 P_PATH='@t6g_mb_lib.t6g(sch_1):page111_i76@pure_quanta.q_res(chips)',
 PATH='I76',
 DRAWING='@T6G_MB_LIB.T6G(SCH_1):PAGE110',
 WATTAGE='1/16W',
 TOLERANCE='1%',
 MATERIAL='EMPTY',
 PHYS_PAGE='111',
 XY='(7700,2675)',
 ROT='0',
 VER='2',
 PACK_TYPE='0402LF',
 LOCATION='R3290',
 CDS_LIB='pure_quanta',
 CDS_PART_NAME='Q_RES_0402LF-1K,1%,1/16W,EMPTY,CS21002FB06',
 ROOM='PCIE REDRIVER BOM1',
 PART_NUMBER='CS21002FB06',
 VALUE='1K',
 PRIM_FILE='./archive_libs/logical/q_res/chips/chips.prt';

PART_NAME
 R3291 'Q_RES_0402LF-4.7K,1%,1/16W,EMPTY,CS24702FB06':
 ROOM='PCIE REDRIVER BOM1';

SECTION_NUMBER 1
 '@T6G_MB_LIB.T6G(SCH_1):PAGE110_I88@PURE_QUANTA.Q_RES(CHIPS)':
 C_PATH='@t6g_mb_lib.t6g(sch_1):page110_i88@pure_quanta.q_res(chips)',
 P_PATH='@t6g_mb_lib.t6g(sch_1):page111_i88@pure_quanta.q_res(chips)',
 PATH='I88',
 DRAWING='@T6G_MB_LIB.T6G(SCH_1):PAGE110',
 WATTAGE='1/16W',
 TOLERANCE='1%',
 MATERIAL='EMPTY',
 PHYS_PAGE='111',
 XY='(8350,4900)',
 ROT='0',
 VER='2',
 PACK_TYPE='0402LF',
 LOCATION='R3291',
 CDS_LIB='pure_quanta',
 CDS_PART_NAME='Q_RES_0402LF-4.7K,1%,1/16W,EMPTY,CS24702FB06',
 ROOM='PCIE REDRIVER BOM1',
 PART_NUMBER='CS24702FB06',
 VALUE='4.7K',
 PRIM_FILE='./archive_libs/logical/q_res/chips/chips.prt';

PART_NAME
 R3292 'Q_RES_0402LF-4.7K,1%,1/16W,CHIP,CS24702FB06':
 ROOM='PCIE REDRIVER BOM1';

SECTION_NUMBER 1
 '@T6G_MB_LIB.T6G(SCH_1):PAGE110_I89@PURE_QUANTA.Q_RES(CHIPS)':
 C_PATH='@t6g_mb_lib.t6g(sch_1):page110_i89@pure_quanta.q_res(chips)',
 P_PATH='@t6g_mb_lib.t6g(sch_1):page111_i89@pure_quanta.q_res(chips)',
 PATH='I89',
 DRAWING='@T6G_MB_LIB.T6G(SCH_1):PAGE110',
 WATTAGE='1/16W',
 TOLERANCE='1%',
 MATERIAL='CHIP',
 PHYS_PAGE='111',
 XY='(9575,4450)',
 ROT='0',
 VER='2',
 PACK_TYPE='0402LF',
 LOCATION='R3292',
 CDS_LIB='pure_quanta',
 CDS_PART_NAME='Q_RES_0402LF-4.7K,1%,1/16W,CHIP,CS24702FB06',
 ROOM='PCIE REDRIVER BOM1',
 PART_NUMBER='CS24702FB06',
 VALUE='4.7K',
 PRIM_FILE='./archive_libs/logical/q_res/chips/chips.prt';

PART_NAME
 R3293 'Q_RES_0402LF-4.7K,1%,1/16W,EMPTY,CS24702FB06':
 ROOM='PCIE REDRIVER BOM1';

SECTION_NUMBER 1
 '@T6G_MB_LIB.T6G(SCH_1):PAGE110_I92@PURE_QUANTA.Q_RES(CHIPS)':
 C_PATH='@t6g_mb_lib.t6g(sch_1):page110_i92@pure_quanta.q_res(chips)',
 P_PATH='@t6g_mb_lib.t6g(sch_1):page111_i92@pure_quanta.q_res(chips)',
 PATH='I92',
 DRAWING='@T6G_MB_LIB.T6G(SCH_1):PAGE110',
 WATTAGE='1/16W',
 TOLERANCE='1%',
 MATERIAL='EMPTY',
 PHYS_PAGE='111',
 XY='(9600,5375)',
 ROT='0',
 VER='2',
 PACK_TYPE='0402LF',
 LOCATION='R3293',
 CDS_LIB='pure_quanta',
 CDS_PART_NAME='Q_RES_0402LF-4.7K,1%,1/16W,EMPTY,CS24702FB06',
 ROOM='PCIE REDRIVER BOM1',
 PART_NUMBER='CS24702FB06',
 VALUE='4.7K',
 PRIM_FILE='./archive_libs/logical/q_res/chips/chips.prt';

PART_NAME
 R3294 'Q_RES_0402LF-0,5%,1/16W,CHIP,CS00002JB13':;

SECTION_NUMBER 1
 '@T6G_MB_LIB.T6G(SCH_1):PAGE345_I19@PURE_QUANTA.Q_RES(CHIPS)':
 C_PATH='@t6g_mb_lib.t6g(sch_1):page345_i19@pure_quanta.q_res(chips)',
 P_PATH='@t6g_mb_lib.t6g(sch_1):page144_i19@pure_quanta.q_res(chips)',
 PATH='I19',
 DRAWING='@T6G_MB_LIB.T6G(SCH_1):PAGE345',
 WATTAGE='1/16W',
 TOLERANCE='5%',
 MATERIAL='CHIP',
 PHYS_PAGE='144',
 XY='(7025,1150)',
 ROT='0',
 VER='1',
 PACK_TYPE='0402LF',
 LOCATION='R3294',
 CDS_LIB='pure_quanta',
 CDS_PART_NAME='Q_RES_0402LF-0,5%,1/16W,CHIP,CS00002JB13',
 PART_NUMBER='CS00002JB13',
 VALUE='0',
 PRIM_FILE='./archive_libs/logical/q_res/chips/chips.prt';

PART_NAME
 R3295 'Q_RES_0402LF-4.7K,1%,1/16W,CHIP,CS24702FB06':;

SECTION_NUMBER 1
 '@T6G_MB_LIB.T6G(SCH_1):PAGE345_I21@PURE_QUANTA.Q_RES(CHIPS)':
 C_PATH='@t6g_mb_lib.t6g(sch_1):page345_i21@pure_quanta.q_res(chips)',
 P_PATH='@t6g_mb_lib.t6g(sch_1):page144_i21@pure_quanta.q_res(chips)',
 PATH='I21',
 DRAWING='@T6G_MB_LIB.T6G(SCH_1):PAGE345',
 WATTAGE='1/16W',
 TOLERANCE='1%',
 MATERIAL='CHIP',
 PHYS_PAGE='144',
 XY='(7600,1450)',
 ROT='0',
 VER='2',
 PACK_TYPE='0402LF',
 LOCATION='R3295',
 CDS_LIB='pure_quanta',
 CDS_PART_NAME='Q_RES_0402LF-4.7K,1%,1/16W,CHIP,CS24702FB06',
 PART_NUMBER='CS24702FB06',
 VALUE='4.7K',
 PRIM_FILE='./archive_libs/logical/q_res/chips/chips.prt';

PART_NAME
 R3296 'Q_RES_0402LF-4.7K,1%,1/16W,CHIP,CS24702FB06':;

SECTION_NUMBER 1
 '@T6G_MB_LIB.T6G(SCH_1):PAGE345_I51@PURE_QUANTA.Q_RES(CHIPS)':
 C_PATH='@t6g_mb_lib.t6g(sch_1):page345_i51@pure_quanta.q_res(chips)',
 P_PATH='@t6g_mb_lib.t6g(sch_1):page144_i51@pure_quanta.q_res(chips)',
 PATH='I51',
 DRAWING='@T6G_MB_LIB.T6G(SCH_1):PAGE345',
 WATTAGE='1/16W',
 TOLERANCE='1%',
 MATERIAL='CHIP',
 PHYS_PAGE='144',
 XY='(8575,225)',
 ROT='0',
 VER='2',
 PACK_TYPE='0402LF',
 LOCATION='R3296',
 CDS_LIB='pure_quanta',
 CDS_PART_NAME='Q_RES_0402LF-4.7K,1%,1/16W,CHIP,CS24702FB06',
 PART_NUMBER='CS24702FB06',
 VALUE='4.7K',
 PRIM_FILE='./archive_libs/logical/q_res/chips/chips.prt';

PART_NAME
 R3297 'Q_RES_0402LF-10K,1%,1/16W,CHIP,CS31002FB08':;

SECTION_NUMBER 1
 '@T6G_MB_LIB.T6G(SCH_1):PAGE345_I60@PURE_QUANTA.Q_RES(CHIPS)':
 C_PATH='@t6g_mb_lib.t6g(sch_1):page345_i60@pure_quanta.q_res(chips)',
 P_PATH='@t6g_mb_lib.t6g(sch_1):page144_i60@pure_quanta.q_res(chips)',
 PATH='I60',
 DRAWING='@T6G_MB_LIB.T6G(SCH_1):PAGE345',
 WATTAGE='1/16W',
 TOLERANCE='1%',
 MATERIAL='CHIP',
 PHYS_PAGE='144',
 XY='(10250,850)',
 ROT='2',
 VER='2',
 PACK_TYPE='0402LF',
 LOCATION='R3297',
 CDS_LIB='pure_quanta',
 CDS_PART_NAME='Q_RES_0402LF-10K,1%,1/16W,CHIP,CS31002FB08',
 PART_NUMBER='CS31002FB08',
 VALUE='10K',
 PRIM_FILE='./archive_libs/logical/q_res/chips/chips.prt';

PART_NAME
 R3298 'Q_RES_0402LF-10K,1%,1/16W,CHIP,CS31002FB08':;

SECTION_NUMBER 1
 '@T6G_MB_LIB.T6G(SCH_1):PAGE345_I58@PURE_QUANTA.Q_RES(CHIPS)':
 C_PATH='@t6g_mb_lib.t6g(sch_1):page345_i58@pure_quanta.q_res(chips)',
 P_PATH='@t6g_mb_lib.t6g(sch_1):page144_i58@pure_quanta.q_res(chips)',
 PATH='I58',
 DRAWING='@T6G_MB_LIB.T6G(SCH_1):PAGE345',
 WATTAGE='1/16W',
 TOLERANCE='1%',
 MATERIAL='CHIP',
 PHYS_PAGE='144',
 XY='(10675,425)',
 ROT='2',
 VER='2',
 PACK_TYPE='0402LF',
 LOCATION='R3298',
 CDS_LIB='pure_quanta',
 CDS_PART_NAME='Q_RES_0402LF-10K,1%,1/16W,CHIP,CS31002FB08',
 PART_NUMBER='CS31002FB08',
 VALUE='10K',
 PRIM_FILE='./archive_libs/logical/q_res/chips/chips.prt';

PART_NAME
 R3301 'Q_RES_0402LF-33.2,1%,1/16W,CHIP,CS03322FB03':;

SECTION_NUMBER 1
 '@T6G_MB_LIB.T6G(SCH_1):PAGE345_I30@PURE_QUANTA.Q_RES(CHIPS)':
 C_PATH='@t6g_mb_lib.t6g(sch_1):page345_i30@pure_quanta.q_res(chips)',
 P_PATH='@t6g_mb_lib.t6g(sch_1):page144_i30@pure_quanta.q_res(chips)',
 PATH='I30',
 DRAWING='@T6G_MB_LIB.T6G(SCH_1):PAGE345',
 WATTAGE='1/16W',
 TOLERANCE='1%',
 MATERIAL='CHIP',
 PHYS_PAGE='144',
 XY='(6925,3225)',
 ROT='0',
 VER='1',
 PACK_TYPE='0402LF',
 LOCATION='R3301',
 CDS_LIB='pure_quanta',
 CDS_PART_NAME='Q_RES_0402LF-33.2,1%,1/16W,CHIP,CS03322FB03',
 PART_NUMBER='CS03322FB03',
 VALUE='33.2',
 PRIM_FILE='./archive_libs/logical/q_res/chips/chips.prt';

PART_NAME
 R3303 'Q_RES_0402LF-0,5%,1/16W,CHIP,CS00002JB13':;

SECTION_NUMBER 1
 '@T6G_MB_LIB.T6G(SCH_1):PAGE258_I44@PURE_QUANTA.Q_RES(CHIPS)':
 C_PATH='@t6g_mb_lib.t6g(sch_1):page258_i44@pure_quanta.q_res(chips)',
 P_PATH='@t6g_mb_lib.t6g(sch_1):page143_i44@pure_quanta.q_res(chips)',
 PATH='I44',
 DRAWING='@T6G_MB_LIB.T6G(SCH_1):PAGE258',
 WATTAGE='1/16W',
 TOLERANCE='5%',
 MATERIAL='CHIP',
 PHYS_PAGE='143',
 XY='(825,2400)',
 ROT='0',
 VER='1',
 PACK_TYPE='0402LF',
 LOCATION='R3303',
 CDS_LIB='pure_quanta',
 CDS_PART_NAME='Q_RES_0402LF-0,5%,1/16W,CHIP,CS00002JB13',
 PART_NUMBER='CS00002JB13',
 VALUE='0',
 PRIM_FILE='./archive_libs/logical/q_res/chips/chips.prt';

PART_NAME
 R3304 'Q_RES_0402LF-0,5%,1/16W,CHIP,CS00002JB13':;

SECTION_NUMBER 1
 '@T6G_MB_LIB.T6G(SCH_1):PAGE258_I45@PURE_QUANTA.Q_RES(CHIPS)':
 C_PATH='@t6g_mb_lib.t6g(sch_1):page258_i45@pure_quanta.q_res(chips)',
 P_PATH='@t6g_mb_lib.t6g(sch_1):page143_i45@pure_quanta.q_res(chips)',
 PATH='I45',
 DRAWING='@T6G_MB_LIB.T6G(SCH_1):PAGE258',
 WATTAGE='1/16W',
 TOLERANCE='5%',
 MATERIAL='CHIP',
 PHYS_PAGE='143',
 XY='(625,1550)',
 ROT='0',
 VER='1',
 PACK_TYPE='0402LF',
 LOCATION='R3304',
 CDS_LIB='pure_quanta',
 CDS_PART_NAME='Q_RES_0402LF-0,5%,1/16W,CHIP,CS00002JB13',
 PART_NUMBER='CS00002JB13',
 VALUE='0',
 PRIM_FILE='./archive_libs/logical/q_res/chips/chips.prt';

PART_NAME
 R3305 'Q_RES_0402LF-0,5%,1/16W,CHIP,CS00002JB13':;

SECTION_NUMBER 1
 '@T6G_MB_LIB.T6G(SCH_1):PAGE258_I50@PURE_QUANTA.Q_RES(CHIPS)':
 C_PATH='@t6g_mb_lib.t6g(sch_1):page258_i50@pure_quanta.q_res(chips)',
 P_PATH='@t6g_mb_lib.t6g(sch_1):page143_i50@pure_quanta.q_res(chips)',
 PATH='I50',
 DRAWING='@T6G_MB_LIB.T6G(SCH_1):PAGE258',
 WATTAGE='1/16W',
 TOLERANCE='5%',
 MATERIAL='CHIP',
 PHYS_PAGE='143',
 XY='(625,1450)',
 ROT='0',
 VER='1',
 PACK_TYPE='0402LF',
 LOCATION='R3305',
 CDS_LIB='pure_quanta',
 CDS_PART_NAME='Q_RES_0402LF-0,5%,1/16W,CHIP,CS00002JB13',
 PART_NUMBER='CS00002JB13',
 VALUE='0',
 PRIM_FILE='./archive_libs/logical/q_res/chips/chips.prt';

PART_NAME
 R3306 'Q_RES_0402LF-0,5%,1/16W,CHIP,CS00002JB13':;

SECTION_NUMBER 1
 '@T6G_MB_LIB.T6G(SCH_1):PAGE258_I47@PURE_QUANTA.Q_RES(CHIPS)':
 C_PATH='@t6g_mb_lib.t6g(sch_1):page258_i47@pure_quanta.q_res(chips)',
 P_PATH='@t6g_mb_lib.t6g(sch_1):page143_i47@pure_quanta.q_res(chips)',
 PATH='I47',
 DRAWING='@T6G_MB_LIB.T6G(SCH_1):PAGE258',
 WATTAGE='1/16W',
 TOLERANCE='5%',
 MATERIAL='CHIP',
 PHYS_PAGE='143',
 XY='(800,-575)',
 ROT='0',
 VER='1',
 PACK_TYPE='0402LF',
 LOCATION='R3306',
 CDS_LIB='pure_quanta',
 CDS_PART_NAME='Q_RES_0402LF-0,5%,1/16W,CHIP,CS00002JB13',
 PART_NUMBER='CS00002JB13',
 VALUE='0',
 PRIM_FILE='./archive_libs/logical/q_res/chips/chips.prt';

PART_NAME
 R3307 'Q_RES_0402LF-0,5%,1/16W,CHIP,CS00002JB13':;

SECTION_NUMBER 1
 '@T6G_MB_LIB.T6G(SCH_1):PAGE258_I52@PURE_QUANTA.Q_RES(CHIPS)':
 C_PATH='@t6g_mb_lib.t6g(sch_1):page258_i52@pure_quanta.q_res(chips)',
 P_PATH='@t6g_mb_lib.t6g(sch_1):page143_i52@pure_quanta.q_res(chips)',
 PATH='I52',
 DRAWING='@T6G_MB_LIB.T6G(SCH_1):PAGE258',
 WATTAGE='1/16W',
 TOLERANCE='5%',
 MATERIAL='CHIP',
 PHYS_PAGE='143',
 XY='(800,-675)',
 ROT='0',
 VER='1',
 PACK_TYPE='0402LF',
 LOCATION='R3307',
 CDS_LIB='pure_quanta',
 CDS_PART_NAME='Q_RES_0402LF-0,5%,1/16W,CHIP,CS00002JB13',
 PART_NUMBER='CS00002JB13',
 VALUE='0',
 PRIM_FILE='./archive_libs/logical/q_res/chips/chips.prt';

PART_NAME
 R3308 'Q_RES_0402LF-0,5%,1/16W,CHIP,CS00002JB13':;

SECTION_NUMBER 1
 '@T6G_MB_LIB.T6G(SCH_1):PAGE258_I46@PURE_QUANTA.Q_RES(CHIPS)':
 C_PATH='@t6g_mb_lib.t6g(sch_1):page258_i46@pure_quanta.q_res(chips)',
 P_PATH='@t6g_mb_lib.t6g(sch_1):page143_i46@pure_quanta.q_res(chips)',
 PATH='I46',
 DRAWING='@T6G_MB_LIB.T6G(SCH_1):PAGE258',
 WATTAGE='1/16W',
 TOLERANCE='5%',
 MATERIAL='CHIP',
 PHYS_PAGE='143',
 XY='(825,275)',
 ROT='0',
 VER='1',
 PACK_TYPE='0402LF',
 LOCATION='R3308',
 CDS_LIB='pure_quanta',
 CDS_PART_NAME='Q_RES_0402LF-0,5%,1/16W,CHIP,CS00002JB13',
 PART_NUMBER='CS00002JB13',
 VALUE='0',
 PRIM_FILE='./archive_libs/logical/q_res/chips/chips.prt';

PART_NAME
 R3315 'Q_RES_0402LF-33.2,1%,1/16W,CHIP,CS03322FB03':;

SECTION_NUMBER 1
 '@T6G_MB_LIB.T6G(SCH_1):PAGE256_I181@PURE_QUANTA.Q_RES(CHIPS)':
 C_PATH='@t6g_mb_lib.t6g(sch_1):page256_i181@pure_quanta.q_res(chips)',
 P_PATH='@t6g_mb_lib.t6g(sch_1):page130_i181@pure_quanta.q_res(chips)',
 PATH='I181',
 DRAWING='@T6G_MB_LIB.T6G(SCH_1):PAGE256',
 WATTAGE='1/16W',
 TOLERANCE='1%',
 MATERIAL='CHIP',
 PHYS_PAGE='130',
 XY='(2900,-525)',
 ROT='0',
 VER='1',
 PACK_TYPE='0402LF',
 LOCATION='R3315',
 CDS_LIB='pure_quanta',
 CDS_PART_NAME='Q_RES_0402LF-33.2,1%,1/16W,CHIP,CS03322FB03',
 PART_NUMBER='CS03322FB03',
 VALUE='33.2',
 PRIM_FILE='./archive_libs/logical/q_res/chips/chips.prt';

PART_NAME
 R3317 'Q_RES_0402LF-4.7K,5%,1/16W,EMPTY,CS24702JB10':;

SECTION_NUMBER 1
 '@T6G_MB_LIB.T6G(SCH_1):PAGE256_I190@PURE_QUANTA.Q_RES(CHIPS)':
 C_PATH='@t6g_mb_lib.t6g(sch_1):page256_i190@pure_quanta.q_res(chips)',
 P_PATH='@t6g_mb_lib.t6g(sch_1):page130_i190@pure_quanta.q_res(chips)',
 PATH='I190',
 DRAWING='@T6G_MB_LIB.T6G(SCH_1):PAGE256',
 WATTAGE='1/16W',
 TOLERANCE='5%',
 MATERIAL='EMPTY',
 PHYS_PAGE='130',
 XY='(2650,-325)',
 ROT='0',
 VER='2',
 PACK_TYPE='0402LF',
 LOCATION='R3317',
 CDS_LIB='pure_quanta',
 CDS_PART_NAME='Q_RES_0402LF-4.7K,5%,1/16W,EMPTY,CS24702JB10',
 PART_NUMBER='CS24702JB10',
 VALUE='4.7K',
 PRIM_FILE='./archive_libs/logical/q_res/chips/chips.prt';

PART_NAME
 R3318 'Q_RES_0402LF-100K,1%,1/16W,EMPTY,CS41002FB09':;

SECTION_NUMBER 1
 '@T6G_MB_LIB.T6G(SCH_1):PAGE333_I171@PURE_QUANTA.Q_RES(CHIPS)':
 C_PATH='@t6g_mb_lib.t6g(sch_1):page333_i171@pure_quanta.q_res(chips)',
 P_PATH='@t6g_mb_lib.t6g(sch_1):page127_i171@pure_quanta.q_res(chips)',
 PATH='I171',
 DRAWING='@T6G_MB_LIB.T6G(SCH_1):PAGE333',
 WATTAGE='1/16W',
 TOLERANCE='1%',
 MATERIAL='EMPTY',
 PHYS_PAGE='127',
 XY='(-175,3400)',
 ROT='0',
 VER='2',
 PACK_TYPE='0402LF',
 LOCATION='R3318',
 CDS_LIB='pure_quanta',
 CDS_PART_NAME='Q_RES_0402LF-100K,1%,1/16W,EMPTY,CS41002FB09',
 PART_NUMBER='CS41002FB09',
 VALUE='100K',
 PRIM_FILE='./archive_libs/logical/q_res/chips/chips.prt';

PART_NAME
 R3320 'Q_RES_0402LF-4.7K,5%,1/16W,CHIP,CS24702JB10':;

SECTION_NUMBER 1
 '@T6G_MB_LIB.T6G(SCH_1):PAGE333_I162@PURE_QUANTA.Q_RES(CHIPS)':
 C_PATH='@t6g_mb_lib.t6g(sch_1):page333_i162@pure_quanta.q_res(chips)',
 P_PATH='@t6g_mb_lib.t6g(sch_1):page127_i162@pure_quanta.q_res(chips)',
 PATH='I162',
 DRAWING='@T6G_MB_LIB.T6G(SCH_1):PAGE333',
 WATTAGE='1/16W',
 TOLERANCE='5%',
 MATERIAL='CHIP',
 PHYS_PAGE='127',
 XY='(1075,3700)',
 ROT='0',
 VER='2',
 PACK_TYPE='0402LF',
 LOCATION='R3320',
 CDS_LIB='pure_quanta',
 CDS_PART_NAME='Q_RES_0402LF-4.7K,5%,1/16W,CHIP,CS24702JB10',
 PART_NUMBER='CS24702JB10',
 VALUE='4.7K',
 PRIM_FILE='./archive_libs/logical/q_res/chips/chips.prt';

PART_NAME
 R3321 'Q_RES_0402LF-100K,1%,1/16W,CHIP,CS41002FB09':;

SECTION_NUMBER 1
 '@T6G_MB_LIB.T6G(SCH_1):PAGE333_I158@PURE_QUANTA.Q_RES(CHIPS)':
 C_PATH='@t6g_mb_lib.t6g(sch_1):page333_i158@pure_quanta.q_res(chips)',
 P_PATH='@t6g_mb_lib.t6g(sch_1):page127_i158@pure_quanta.q_res(chips)',
 PATH='I158',
 DRAWING='@T6G_MB_LIB.T6G(SCH_1):PAGE333',
 WATTAGE='1/16W',
 TOLERANCE='1%',
 MATERIAL='CHIP',
 PHYS_PAGE='127',
 XY='(2000,3950)',
 ROT='0',
 VER='2',
 PACK_TYPE='0402LF',
 LOCATION='R3321',
 CDS_LIB='pure_quanta',
 CDS_PART_NAME='Q_RES_0402LF-100K,1%,1/16W,CHIP,CS41002FB09',
 PART_NUMBER='CS41002FB09',
 VALUE='100K',
 PRIM_FILE='./archive_libs/logical/q_res/chips/chips.prt';

PART_NAME
 R3322 'Q_RES_0402LF-1K,1%,1/16W,CHIP,CS21002FB06':;

SECTION_NUMBER 1
 '@T6G_MB_LIB.T6G(SCH_1):PAGE232_I74@PURE_QUANTA.Q_RES(CHIPS)':
 C_PATH='@t6g_mb_lib.t6g(sch_1):page232_i74@pure_quanta.q_res(chips)',
 P_PATH='@t6g_mb_lib.t6g(sch_1):page233_i74@pure_quanta.q_res(chips)',
 PATH='I74',
 DRAWING='@T6G_MB_LIB.T6G(SCH_1):PAGE232',
 WATTAGE='1/16W',
 TOLERANCE='1%',
 MATERIAL='CHIP',
 PHYS_PAGE='233',
 XY='(-6325,1800)',
 ROT='0',
 VER='2',
 PACK_TYPE='0402LF',
 LOCATION='R3322',
 CDS_LIB='pure_quanta',
 CDS_PART_NAME='Q_RES_0402LF-1K,1%,1/16W,CHIP,CS21002FB06',
 PART_NUMBER='CS21002FB06',
 VALUE='1K',
 PRIM_FILE='./archive_libs/logical/q_res/chips/chips.prt';

PART_NAME
 R3324 'Q_RES_0402LF-33.2,1%,1/16W,CHIP,CS03322FB03':;

SECTION_NUMBER 1
 '@T6G_MB_LIB.T6G(SCH_1):PAGE80_I276@PURE_QUANTA.Q_RES(CHIPS)':
 C_PATH='@t6g_mb_lib.t6g(sch_1):page80_i276@pure_quanta.q_res(chips)',
 P_PATH='@t6g_mb_lib.t6g(sch_1):page81_i276@pure_quanta.q_res(chips)',
 PATH='I276',
 DRAWING='@T6G_MB_LIB.T6G(SCH_1):PAGE80',
 WATTAGE='1/16W',
 TOLERANCE='1%',
 MATERIAL='CHIP',
 PHYS_PAGE='81',
 XY='(-2300,1375)',
 ROT='0',
 VER='1',
 PACK_TYPE='0402LF',
 LOCATION='R3324',
 CDS_LIB='pure_quanta',
 CDS_PART_NAME='Q_RES_0402LF-33.2,1%,1/16W,CHIP,CS03322FB03',
 PART_NUMBER='CS03322FB03',
 VALUE='33.2',
 PRIM_FILE='./archive_libs/logical/q_res/chips/chips.prt';

PART_NAME
 R3326 'Q_RES_0402LF-0,5%,1/16W,CHIP,CS00002JB13':;

SECTION_NUMBER 1
 '@T6G_MB_LIB.T6G(SCH_1):PAGE232_I7@PURE_QUANTA.Q_RES(CHIPS)':
 C_PATH='@t6g_mb_lib.t6g(sch_1):page232_i7@pure_quanta.q_res(chips)',
 P_PATH='@t6g_mb_lib.t6g(sch_1):page233_i7@pure_quanta.q_res(chips)',
 PATH='I7',
 DRAWING='@T6G_MB_LIB.T6G(SCH_1):PAGE232',
 WATTAGE='1/16W',
 TOLERANCE='5%',
 MATERIAL='CHIP',
 PHYS_PAGE='233',
 XY='(-6625,1500)',
 ROT='0',
 VER='1',
 PACK_TYPE='0402LF',
 LOCATION='R3326',
 CDS_LIB='pure_quanta',
 CDS_PART_NAME='Q_RES_0402LF-0,5%,1/16W,CHIP,CS00002JB13',
 PART_NUMBER='CS00002JB13',
 VALUE='0',
 PRIM_FILE='./archive_libs/logical/q_res/chips/chips.prt';

PART_NAME
 R3327 'Q_RES_0402LF-0,5%,1/16W,CHIP,CS00002JB13':;

SECTION_NUMBER 1
 '@T6G_MB_LIB.T6G(SCH_1):PAGE232_I6@PURE_QUANTA.Q_RES(CHIPS)':
 C_PATH='@t6g_mb_lib.t6g(sch_1):page232_i6@pure_quanta.q_res(chips)',
 P_PATH='@t6g_mb_lib.t6g(sch_1):page233_i6@pure_quanta.q_res(chips)',
 PATH='I6',
 DRAWING='@T6G_MB_LIB.T6G(SCH_1):PAGE232',
 WATTAGE='1/16W',
 TOLERANCE='5%',
 MATERIAL='CHIP',
 PHYS_PAGE='233',
 XY='(-6625,1400)',
 ROT='0',
 VER='1',
 PACK_TYPE='0402LF',
 LOCATION='R3327',
 CDS_LIB='pure_quanta',
 CDS_PART_NAME='Q_RES_0402LF-0,5%,1/16W,CHIP,CS00002JB13',
 PART_NUMBER='CS00002JB13',
 VALUE='0',
 PRIM_FILE='./archive_libs/logical/q_res/chips/chips.prt';

PART_NAME
 R3335 'Q_RES_0402LF-0,5%,1/16W,CHIP,CS00002JB13':;

SECTION_NUMBER 1
 '@T6G_MB_LIB.T6G(SCH_1):PAGE232_I53@PURE_QUANTA.Q_RES(CHIPS)':
 C_PATH='@t6g_mb_lib.t6g(sch_1):page232_i53@pure_quanta.q_res(chips)',
 P_PATH='@t6g_mb_lib.t6g(sch_1):page233_i53@pure_quanta.q_res(chips)',
 PATH='I53',
 DRAWING='@T6G_MB_LIB.T6G(SCH_1):PAGE232',
 WATTAGE='1/16W',
 TOLERANCE='5%',
 MATERIAL='CHIP',
 PHYS_PAGE='233',
 XY='(-2725,3950)',
 ROT='0',
 VER='1',
 PACK_TYPE='0402LF',
 LOCATION='R3335',
 CDS_LIB='pure_quanta',
 CDS_PART_NAME='Q_RES_0402LF-0,5%,1/16W,CHIP,CS00002JB13',
 PART_NUMBER='CS00002JB13',
 VALUE='0',
 PRIM_FILE='./archive_libs/logical/q_res/chips/chips.prt';

PART_NAME
 R3336 'Q_RES_0402LF-0,5%,1/16W,CHIP,CS00002JB13':;

SECTION_NUMBER 1
 '@T6G_MB_LIB.T6G(SCH_1):PAGE232_I52@PURE_QUANTA.Q_RES(CHIPS)':
 C_PATH='@t6g_mb_lib.t6g(sch_1):page232_i52@pure_quanta.q_res(chips)',
 P_PATH='@t6g_mb_lib.t6g(sch_1):page233_i52@pure_quanta.q_res(chips)',
 PATH='I52',
 DRAWING='@T6G_MB_LIB.T6G(SCH_1):PAGE232',
 WATTAGE='1/16W',
 TOLERANCE='5%',
 MATERIAL='CHIP',
 PHYS_PAGE='233',
 XY='(-2725,3900)',
 ROT='0',
 VER='1',
 PACK_TYPE='0402LF',
 LOCATION='R3336',
 CDS_LIB='pure_quanta',
 CDS_PART_NAME='Q_RES_0402LF-0,5%,1/16W,CHIP,CS00002JB13',
 PART_NUMBER='CS00002JB13',
 VALUE='0',
 PRIM_FILE='./archive_libs/logical/q_res/chips/chips.prt';

PART_NAME
 R3337 'Q_RES_0402LF-0,5%,1/16W,CHIP,CS00002JB13':;

SECTION_NUMBER 1
 '@T6G_MB_LIB.T6G(SCH_1):PAGE232_I51@PURE_QUANTA.Q_RES(CHIPS)':
 C_PATH='@t6g_mb_lib.t6g(sch_1):page232_i51@pure_quanta.q_res(chips)',
 P_PATH='@t6g_mb_lib.t6g(sch_1):page233_i51@pure_quanta.q_res(chips)',
 PATH='I51',
 DRAWING='@T6G_MB_LIB.T6G(SCH_1):PAGE232',
 WATTAGE='1/16W',
 TOLERANCE='5%',
 MATERIAL='CHIP',
 PHYS_PAGE='233',
 XY='(-2725,3800)',
 ROT='0',
 VER='1',
 PACK_TYPE='0402LF',
 LOCATION='R3337',
 CDS_LIB='pure_quanta',
 CDS_PART_NAME='Q_RES_0402LF-0,5%,1/16W,CHIP,CS00002JB13',
 PART_NUMBER='CS00002JB13',
 VALUE='0',
 PRIM_FILE='./archive_libs/logical/q_res/chips/chips.prt';

PART_NAME
 R3338 'Q_RES_0402LF-0,5%,1/16W,CHIP,CS00002JB13':;

SECTION_NUMBER 1
 '@T6G_MB_LIB.T6G(SCH_1):PAGE232_I50@PURE_QUANTA.Q_RES(CHIPS)':
 C_PATH='@t6g_mb_lib.t6g(sch_1):page232_i50@pure_quanta.q_res(chips)',
 P_PATH='@t6g_mb_lib.t6g(sch_1):page233_i50@pure_quanta.q_res(chips)',
 PATH='I50',
 DRAWING='@T6G_MB_LIB.T6G(SCH_1):PAGE232',
 WATTAGE='1/16W',
 TOLERANCE='5%',
 MATERIAL='CHIP',
 PHYS_PAGE='233',
 XY='(-2725,3750)',
 ROT='0',
 VER='1',
 PACK_TYPE='0402LF',
 LOCATION='R3338',
 CDS_LIB='pure_quanta',
 CDS_PART_NAME='Q_RES_0402LF-0,5%,1/16W,CHIP,CS00002JB13',
 PART_NUMBER='CS00002JB13',
 VALUE='0',
 PRIM_FILE='./archive_libs/logical/q_res/chips/chips.prt';

PART_NAME
 R3340 'Q_RES_0402LF-33.2,1%,1/16W,CHIP,CS03322FB03':;

SECTION_NUMBER 1
 '@T6G_MB_LIB.T6G(SCH_1):PAGE349_I81@PURE_QUANTA.Q_RES(CHIPS)':
 C_PATH='@t6g_mb_lib.t6g(sch_1):page349_i81@pure_quanta.q_res(chips)',
 P_PATH='@t6g_mb_lib.t6g(sch_1):page151_i81@pure_quanta.q_res(chips)',
 PATH='I81',
 DRAWING='@T6G_MB_LIB.T6G(SCH_1):PAGE349',
 WATTAGE='1/16W',
 TOLERANCE='1%',
 MATERIAL='CHIP',
 PHYS_PAGE='151',
 XY='(1750,5775)',
 ROT='0',
 VER='1',
 PACK_TYPE='0402LF',
 LOCATION='R3340',
 CDS_LIB='pure_quanta',
 CDS_PART_NAME='Q_RES_0402LF-33.2,1%,1/16W,CHIP,CS03322FB03',
 PART_NUMBER='CS03322FB03',
 VALUE='33.2',
 PRIM_FILE='./archive_libs/logical/q_res/chips/chips.prt';

PART_NAME
 R3341 'Q_RES_0402LF-33.2,1%,1/16W,CHIP,CS03322FB03':;

SECTION_NUMBER 1
 '@T6G_MB_LIB.T6G(SCH_1):PAGE349_I82@PURE_QUANTA.Q_RES(CHIPS)':
 C_PATH='@t6g_mb_lib.t6g(sch_1):page349_i82@pure_quanta.q_res(chips)',
 P_PATH='@t6g_mb_lib.t6g(sch_1):page151_i82@pure_quanta.q_res(chips)',
 PATH='I82',
 DRAWING='@T6G_MB_LIB.T6G(SCH_1):PAGE349',
 WATTAGE='1/16W',
 TOLERANCE='1%',
 MATERIAL='CHIP',
 PHYS_PAGE='151',
 XY='(1750,5725)',
 ROT='0',
 VER='1',
 PACK_TYPE='0402LF',
 LOCATION='R3341',
 CDS_LIB='pure_quanta',
 CDS_PART_NAME='Q_RES_0402LF-33.2,1%,1/16W,CHIP,CS03322FB03',
 PART_NUMBER='CS03322FB03',
 VALUE='33.2',
 PRIM_FILE='./archive_libs/logical/q_res/chips/chips.prt';

PART_NAME
 R3352 'Q_RES_0402LF-0,5%,1/16W,CHIP,CS00002JB13':;

SECTION_NUMBER 1
 '@T6G_MB_LIB.T6G(SCH_1):PAGE55_I302@PURE_QUANTA.Q_RES(CHIPS)':
 C_PATH='@t6g_mb_lib.t6g(sch_1):page55_i302@pure_quanta.q_res(chips)',
 P_PATH='@t6g_mb_lib.t6g(sch_1):page55_i302@pure_quanta.q_res(chips)',
 PATH='I302',
 DRAWING='@T6G_MB_LIB.T6G(SCH_1):PAGE55',
 WATTAGE='1/16W',
 TOLERANCE='5%',
 MATERIAL='CHIP',
 PHYS_PAGE='55',
 XY='(-2000,4175)',
 ROT='0',
 VER='1',
 PACK_TYPE='0402LF',
 LOCATION='R3352',
 CDS_LIB='pure_quanta',
 CDS_PART_NAME='Q_RES_0402LF-0,5%,1/16W,CHIP,CS00002JB13',
 PART_NUMBER='CS00002JB13',
 VALUE='0',
 PRIM_FILE='./archive_libs/logical/q_res/chips/chips.prt';

PART_NAME
 R3353 'Q_RES_0402LF-0,5%,1/16W,CHIP,CS00002JB13':;

SECTION_NUMBER 1
 '@T6G_MB_LIB.T6G(SCH_1):PAGE55_I303@PURE_QUANTA.Q_RES(CHIPS)':
 C_PATH='@t6g_mb_lib.t6g(sch_1):page55_i303@pure_quanta.q_res(chips)',
 P_PATH='@t6g_mb_lib.t6g(sch_1):page55_i303@pure_quanta.q_res(chips)',
 PATH='I303',
 DRAWING='@T6G_MB_LIB.T6G(SCH_1):PAGE55',
 WATTAGE='1/16W',
 TOLERANCE='5%',
 MATERIAL='CHIP',
 PHYS_PAGE='55',
 XY='(-2000,4125)',
 ROT='0',
 VER='1',
 PACK_TYPE='0402LF',
 LOCATION='R3353',
 CDS_LIB='pure_quanta',
 CDS_PART_NAME='Q_RES_0402LF-0,5%,1/16W,CHIP,CS00002JB13',
 PART_NUMBER='CS00002JB13',
 VALUE='0',
 PRIM_FILE='./archive_libs/logical/q_res/chips/chips.prt';

PART_NAME
 R3354 'Q_RES_0402LF-0,5%,1/16W,CHIP,CS00002JB13':;

SECTION_NUMBER 1
 '@T6G_MB_LIB.T6G(SCH_1):PAGE55_I307@PURE_QUANTA.Q_RES(CHIPS)':
 C_PATH='@t6g_mb_lib.t6g(sch_1):page55_i307@pure_quanta.q_res(chips)',
 P_PATH='@t6g_mb_lib.t6g(sch_1):page55_i307@pure_quanta.q_res(chips)',
 PATH='I307',
 DRAWING='@T6G_MB_LIB.T6G(SCH_1):PAGE55',
 WATTAGE='1/16W',
 TOLERANCE='5%',
 MATERIAL='CHIP',
 PHYS_PAGE='55',
 XY='(-2000,4925)',
 ROT='0',
 VER='1',
 PACK_TYPE='0402LF',
 LOCATION='R3354',
 CDS_LIB='pure_quanta',
 CDS_PART_NAME='Q_RES_0402LF-0,5%,1/16W,CHIP,CS00002JB13',
 PART_NUMBER='CS00002JB13',
 VALUE='0',
 PRIM_FILE='./archive_libs/logical/q_res/chips/chips.prt';

PART_NAME
 R3355 'Q_RES_0402LF-0,5%,1/16W,CHIP,CS00002JB13':;

SECTION_NUMBER 1
 '@T6G_MB_LIB.T6G(SCH_1):PAGE55_I306@PURE_QUANTA.Q_RES(CHIPS)':
 C_PATH='@t6g_mb_lib.t6g(sch_1):page55_i306@pure_quanta.q_res(chips)',
 P_PATH='@t6g_mb_lib.t6g(sch_1):page55_i306@pure_quanta.q_res(chips)',
 PATH='I306',
 DRAWING='@T6G_MB_LIB.T6G(SCH_1):PAGE55',
 WATTAGE='1/16W',
 TOLERANCE='5%',
 MATERIAL='CHIP',
 PHYS_PAGE='55',
 XY='(-2000,4875)',
 ROT='0',
 VER='1',
 PACK_TYPE='0402LF',
 LOCATION='R3355',
 CDS_LIB='pure_quanta',
 CDS_PART_NAME='Q_RES_0402LF-0,5%,1/16W,CHIP,CS00002JB13',
 PART_NUMBER='CS00002JB13',
 VALUE='0',
 PRIM_FILE='./archive_libs/logical/q_res/chips/chips.prt';

PART_NAME
 R3390 'Q_RES_0402LF-49.9,1%,1/16W,CHIP,CS04992FB07':;

SECTION_NUMBER 1
 '@T6G_MB_LIB.T6G(SCH_1):PAGE334_I162@PURE_QUANTA.Q_RES(CHIPS)':
 C_PATH='@t6g_mb_lib.t6g(sch_1):page334_i162@pure_quanta.q_res(chips)',
 P_PATH='@t6g_mb_lib.t6g(sch_1):page128_i162@pure_quanta.q_res(chips)',
 PATH='I162',
 DRAWING='@T6G_MB_LIB.T6G(SCH_1):PAGE334',
 WATTAGE='1/16W',
 TOLERANCE='1%',
 MATERIAL='CHIP',
 PHYS_PAGE='128',
 XY='(-4750,4125)',
 ROT='0',
 VER='1',
 PACK_TYPE='0402LF',
 LOCATION='R3390',
 CDS_LIB='pure_quanta',
 CDS_PART_NAME='Q_RES_0402LF-49.9,1%,1/16W,CHIP,CS04992FB07',
 PART_NUMBER='CS04992FB07',
 VALUE='49.9',
 PRIM_FILE='./archive_libs/logical/q_res/chips/chips.prt';

PART_NAME
 R3391 'Q_RES_0402LF-49.9,1%,1/16W,CHIP,CS04992FB07':;

SECTION_NUMBER 1
 '@T6G_MB_LIB.T6G(SCH_1):PAGE334_I140@PURE_QUANTA.Q_RES(CHIPS)':
 C_PATH='@t6g_mb_lib.t6g(sch_1):page334_i140@pure_quanta.q_res(chips)',
 P_PATH='@t6g_mb_lib.t6g(sch_1):page128_i140@pure_quanta.q_res(chips)',
 PATH='I140',
 DRAWING='@T6G_MB_LIB.T6G(SCH_1):PAGE334',
 WATTAGE='1/16W',
 TOLERANCE='1%',
 MATERIAL='CHIP',
 PHYS_PAGE='128',
 XY='(-4625,1250)',
 ROT='0',
 VER='1',
 PACK_TYPE='0402LF',
 LOCATION='R3391',
 CDS_LIB='pure_quanta',
 CDS_PART_NAME='Q_RES_0402LF-49.9,1%,1/16W,CHIP,CS04992FB07',
 PART_NUMBER='CS04992FB07',
 VALUE='49.9',
 PRIM_FILE='./archive_libs/logical/q_res/chips/chips.prt';

PART_NAME
 R3392 'Q_RES_0402LF-49.9,1%,1/16W,CHIP,CS04992FB07':;

SECTION_NUMBER 1
 '@T6G_MB_LIB.T6G(SCH_1):PAGE334_I62@PURE_QUANTA.Q_RES(CHIPS)':
 C_PATH='@t6g_mb_lib.t6g(sch_1):page334_i62@pure_quanta.q_res(chips)',
 P_PATH='@t6g_mb_lib.t6g(sch_1):page128_i62@pure_quanta.q_res(chips)',
 PATH='I62',
 DRAWING='@T6G_MB_LIB.T6G(SCH_1):PAGE334',
 WATTAGE='1/16W',
 TOLERANCE='1%',
 MATERIAL='CHIP',
 PHYS_PAGE='128',
 XY='(-4625,3000)',
 ROT='0',
 VER='1',
 PACK_TYPE='0402LF',
 LOCATION='R3392',
 CDS_LIB='pure_quanta',
 CDS_PART_NAME='Q_RES_0402LF-49.9,1%,1/16W,CHIP,CS04992FB07',
 PART_NUMBER='CS04992FB07',
 VALUE='49.9',
 PRIM_FILE='./archive_libs/logical/q_res/chips/chips.prt';

PART_NAME
 R3393 'Q_RES_0402LF-0,5%,1/16W,CHIP,CS00002JB13':;

SECTION_NUMBER 1
 '@T6G_MB_LIB.T6G(SCH_1):PAGE252_I27@PURE_QUANTA.Q_RES(CHIPS)':
 C_PATH='@t6g_mb_lib.t6g(sch_1):page252_i27@pure_quanta.q_res(chips)',
 P_PATH='@t6g_mb_lib.t6g(sch_1):page250_i27@pure_quanta.q_res(chips)',
 PATH='I27',
 DRAWING='@T6G_MB_LIB.T6G(SCH_1):PAGE252',
 SEC_TYPE='0402LF',
 WATTAGE='1/16W',
 TOLERANCE='5%',
 MATERIAL='CHIP',
 PHYS_PAGE='250',
 XY='(-5400,4425)',
 ROT='2',
 VER='1',
 PACK_TYPE='0402LF',
 LOCATION='R3393',
 SEC='1',
 CDS_LIB='pure_quanta',
 CDS_PART_NAME='Q_RES_0402LF-0,5%,1/16W,CHIP,CS00002JB13',
 PART_NUMBER='CS00002JB13',
 VALUE='0',
 PRIM_FILE='./archive_libs/logical/q_res/chips/chips.prt';

PART_NAME
 R3394 'Q_RES_0402LF-0,5%,1/16W,CHIP,CS00002JB13':;

SECTION_NUMBER 1
 '@T6G_MB_LIB.T6G(SCH_1):PAGE252_I29@PURE_QUANTA.Q_RES(CHIPS)':
 C_PATH='@t6g_mb_lib.t6g(sch_1):page252_i29@pure_quanta.q_res(chips)',
 P_PATH='@t6g_mb_lib.t6g(sch_1):page250_i29@pure_quanta.q_res(chips)',
 PATH='I29',
 DRAWING='@T6G_MB_LIB.T6G(SCH_1):PAGE252',
 WATTAGE='1/16W',
 TOLERANCE='5%',
 MATERIAL='CHIP',
 PHYS_PAGE='250',
 XY='(-5400,4475)',
 ROT='2',
 VER='1',
 PACK_TYPE='0402LF',
 LOCATION='R3394',
 CDS_LIB='pure_quanta',
 CDS_PART_NAME='Q_RES_0402LF-0,5%,1/16W,CHIP,CS00002JB13',
 PART_NUMBER='CS00002JB13',
 VALUE='0',
 PRIM_FILE='./archive_libs/logical/q_res/chips/chips.prt';

PART_NAME
 R3395 'Q_RES_0402LF-2.2K,5%,1/16W,CHIP,CS22202JB07':;

SECTION_NUMBER 1
 '@T6G_MB_LIB.T6G(SCH_1):PAGE252_I47@PURE_QUANTA.Q_RES(CHIPS)':
 C_PATH='@t6g_mb_lib.t6g(sch_1):page252_i47@pure_quanta.q_res(chips)',
 P_PATH='@t6g_mb_lib.t6g(sch_1):page250_i47@pure_quanta.q_res(chips)',
 PATH='I47',
 DRAWING='@T6G_MB_LIB.T6G(SCH_1):PAGE252',
 WATTAGE='1/16W',
 TOLERANCE='5%',
 MATERIAL='CHIP',
 PHYS_PAGE='250',
 XY='(-2150,2450)',
 ROT='0',
 VER='1',
 PACK_TYPE='0402LF',
 LOCATION='R3395',
 CDS_LIB='pure_quanta',
 CDS_PART_NAME='Q_RES_0402LF-2.2K,5%,1/16W,CHIP,CS22202JB07',
 PART_NUMBER='CS22202JB07',
 VALUE='2.2K',
 PRIM_FILE='./archive_libs/logical/q_res/chips/chips.prt';

PART_NAME
 R3396 'Q_RES_0402LF-2.2K,5%,1/16W,CHIP,CS22202JB07':;

SECTION_NUMBER 1
 '@T6G_MB_LIB.T6G(SCH_1):PAGE252_I48@PURE_QUANTA.Q_RES(CHIPS)':
 C_PATH='@t6g_mb_lib.t6g(sch_1):page252_i48@pure_quanta.q_res(chips)',
 P_PATH='@t6g_mb_lib.t6g(sch_1):page250_i48@pure_quanta.q_res(chips)',
 PATH='I48',
 DRAWING='@T6G_MB_LIB.T6G(SCH_1):PAGE252',
 WATTAGE='1/16W',
 TOLERANCE='5%',
 MATERIAL='CHIP',
 PHYS_PAGE='250',
 XY='(-2150,2400)',
 ROT='0',
 VER='1',
 PACK_TYPE='0402LF',
 LOCATION='R3396',
 CDS_LIB='pure_quanta',
 CDS_PART_NAME='Q_RES_0402LF-2.2K,5%,1/16W,CHIP,CS22202JB07',
 PART_NUMBER='CS22202JB07',
 VALUE='2.2K',
 PRIM_FILE='./archive_libs/logical/q_res/chips/chips.prt';

PART_NAME
 R3397 'Q_RES_0402LF-33.2,1%,1/16W,CHIP,CS03322FB03':;

SECTION_NUMBER 1
 '@T6G_MB_LIB.T6G(SCH_1):PAGE255_I37@PURE_QUANTA.Q_RES(CHIPS)':
 C_PATH='@t6g_mb_lib.t6g(sch_1):page255_i37@pure_quanta.q_res(chips)',
 P_PATH='@t6g_mb_lib.t6g(sch_1):page129_i37@pure_quanta.q_res(chips)',
 PATH='I37',
 DRAWING='@T6G_MB_LIB.T6G(SCH_1):PAGE255',
 WATTAGE='1/16W',
 TOLERANCE='1%',
 MATERIAL='CHIP',
 PHYS_PAGE='129',
 XY='(2100,4300)',
 ROT='0',
 VER='1',
 PACK_TYPE='0402LF',
 LOCATION='R3397',
 CDS_LIB='pure_quanta',
 CDS_PART_NAME='Q_RES_0402LF-33.2,1%,1/16W,CHIP,CS03322FB03',
 PART_NUMBER='CS03322FB03',
 VALUE='33.2',
 PRIM_FILE='./archive_libs/logical/q_res/chips/chips.prt';

PART_NAME
 R3428 'Q_RES_0402LF-100K,1%,1/16W,EMPTY,CS41002FB09':;

SECTION_NUMBER 1
 '@T6G_MB_LIB.T6G(SCH_1):PAGE299_I17@PURE_QUANTA.Q_RES(CHIPS)':
 C_PATH='@t6g_mb_lib.t6g(sch_1):page299_i17@pure_quanta.q_res(chips)',
 P_PATH='@t6g_mb_lib.t6g(sch_1):page126_i17@pure_quanta.q_res(chips)',
 PATH='I17',
 DRAWING='@T6G_MB_LIB.T6G(SCH_1):PAGE299',
 WATTAGE='1/16W',
 TOLERANCE='1%',
 MATERIAL='EMPTY',
 PHYS_PAGE='126',
 XY='(-2975,3525)',
 ROT='0',
 VER='2',
 PACK_TYPE='0402LF',
 LOCATION='R3428',
 CDS_LIB='pure_quanta',
 CDS_PART_NAME='Q_RES_0402LF-100K,1%,1/16W,EMPTY,CS41002FB09',
 PART_NUMBER='CS41002FB09',
 VALUE='100K',
 PRIM_FILE='./archive_libs/logical/q_res/chips/chips.prt';

PART_NAME
 R3429 'Q_RES_0402LF-100K,1%,1/16W,EMPTY,CS41002FB09':;

SECTION_NUMBER 1
 '@T6G_MB_LIB.T6G(SCH_1):PAGE299_I130@PURE_QUANTA.Q_RES(CHIPS)':
 C_PATH='@t6g_mb_lib.t6g(sch_1):page299_i130@pure_quanta.q_res(chips)',
 P_PATH='@t6g_mb_lib.t6g(sch_1):page126_i130@pure_quanta.q_res(chips)',
 PATH='I130',
 DRAWING='@T6G_MB_LIB.T6G(SCH_1):PAGE299',
 WATTAGE='1/16W',
 TOLERANCE='1%',
 MATERIAL='EMPTY',
 PHYS_PAGE='126',
 XY='(-2975,2600)',
 ROT='0',
 VER='2',
 PACK_TYPE='0402LF',
 LOCATION='R3429',
 CDS_LIB='pure_quanta',
 CDS_PART_NAME='Q_RES_0402LF-100K,1%,1/16W,EMPTY,CS41002FB09',
 PART_NUMBER='CS41002FB09',
 VALUE='100K',
 PRIM_FILE='./archive_libs/logical/q_res/chips/chips.prt';

PART_NAME
 R3430 'Q_RES_0402LF-100K,1%,1/16W,EMPTY,CS41002FB09':;

SECTION_NUMBER 1
 '@T6G_MB_LIB.T6G(SCH_1):PAGE299_I3@PURE_QUANTA.Q_RES(CHIPS)':
 C_PATH='@t6g_mb_lib.t6g(sch_1):page299_i3@pure_quanta.q_res(chips)',
 P_PATH='@t6g_mb_lib.t6g(sch_1):page126_i3@pure_quanta.q_res(chips)',
 PATH='I3',
 DRAWING='@T6G_MB_LIB.T6G(SCH_1):PAGE299',
 WATTAGE='1/16W',
 TOLERANCE='1%',
 MATERIAL='EMPTY',
 PHYS_PAGE='126',
 XY='(-2950,-800)',
 ROT='0',
 VER='2',
 PACK_TYPE='0402LF',
 LOCATION='R3430',
 CDS_LIB='pure_quanta',
 CDS_PART_NAME='Q_RES_0402LF-100K,1%,1/16W,EMPTY,CS41002FB09',
 PART_NUMBER='CS41002FB09',
 VALUE='100K',
 PRIM_FILE='./archive_libs/logical/q_res/chips/chips.prt';

PART_NAME
 R3431 'Q_RES_0402LF-100K,1%,1/16W,EMPTY,CS41002FB09':;

SECTION_NUMBER 1
 '@T6G_MB_LIB.T6G(SCH_1):PAGE299_I133@PURE_QUANTA.Q_RES(CHIPS)':
 C_PATH='@t6g_mb_lib.t6g(sch_1):page299_i133@pure_quanta.q_res(chips)',
 P_PATH='@t6g_mb_lib.t6g(sch_1):page126_i133@pure_quanta.q_res(chips)',
 PATH='I133',
 DRAWING='@T6G_MB_LIB.T6G(SCH_1):PAGE299',
 WATTAGE='1/16W',
 TOLERANCE='1%',
 MATERIAL='EMPTY',
 PHYS_PAGE='126',
 XY='(-2900,775)',
 ROT='0',
 VER='2',
 PACK_TYPE='0402LF',
 LOCATION='R3431',
 CDS_LIB='pure_quanta',
 CDS_PART_NAME='Q_RES_0402LF-100K,1%,1/16W,EMPTY,CS41002FB09',
 PART_NUMBER='CS41002FB09',
 VALUE='100K',
 PRIM_FILE='./archive_libs/logical/q_res/chips/chips.prt';

PART_NAME
 R3432 'Q_RES_0402LF-4.7K,5%,1/16W,CHIP,CS24702JB10':;

SECTION_NUMBER 1
 '@T6G_MB_LIB.T6G(SCH_1):PAGE299_I53@PURE_QUANTA.Q_RES(CHIPS)':
 C_PATH='@t6g_mb_lib.t6g(sch_1):page299_i53@pure_quanta.q_res(chips)',
 P_PATH='@t6g_mb_lib.t6g(sch_1):page126_i53@pure_quanta.q_res(chips)',
 PATH='I53',
 DRAWING='@T6G_MB_LIB.T6G(SCH_1):PAGE299',
 WATTAGE='1/16W',
 TOLERANCE='5%',
 MATERIAL='CHIP',
 PHYS_PAGE='126',
 XY='(-1825,4375)',
 ROT='0',
 VER='2',
 PACK_TYPE='0402LF',
 LOCATION='R3432',
 CDS_LIB='pure_quanta',
 CDS_PART_NAME='Q_RES_0402LF-4.7K,5%,1/16W,CHIP,CS24702JB10',
 PART_NUMBER='CS24702JB10',
 VALUE='4.7K',
 PRIM_FILE='./archive_libs/logical/q_res/chips/chips.prt';

PART_NAME
 R3433 'Q_RES_0402LF-4.7K,5%,1/16W,CHIP,CS24702JB10':;

SECTION_NUMBER 1
 '@T6G_MB_LIB.T6G(SCH_1):PAGE299_I49@PURE_QUANTA.Q_RES(CHIPS)':
 C_PATH='@t6g_mb_lib.t6g(sch_1):page299_i49@pure_quanta.q_res(chips)',
 P_PATH='@t6g_mb_lib.t6g(sch_1):page126_i49@pure_quanta.q_res(chips)',
 PATH='I49',
 DRAWING='@T6G_MB_LIB.T6G(SCH_1):PAGE299',
 WATTAGE='1/16W',
 TOLERANCE='5%',
 MATERIAL='CHIP',
 PHYS_PAGE='126',
 XY='(-1775,2825)',
 ROT='0',
 VER='2',
 PACK_TYPE='0402LF',
 LOCATION='R3433',
 CDS_LIB='pure_quanta',
 CDS_PART_NAME='Q_RES_0402LF-4.7K,5%,1/16W,CHIP,CS24702JB10',
 PART_NUMBER='CS24702JB10',
 VALUE='4.7K',
 PRIM_FILE='./archive_libs/logical/q_res/chips/chips.prt';

PART_NAME
 R3434 'Q_RES_0402LF-4.7K,5%,1/16W,CHIP,CS24702JB10':;

SECTION_NUMBER 1
 '@T6G_MB_LIB.T6G(SCH_1):PAGE299_I39@PURE_QUANTA.Q_RES(CHIPS)':
 C_PATH='@t6g_mb_lib.t6g(sch_1):page299_i39@pure_quanta.q_res(chips)',
 P_PATH='@t6g_mb_lib.t6g(sch_1):page126_i39@pure_quanta.q_res(chips)',
 PATH='I39',
 DRAWING='@T6G_MB_LIB.T6G(SCH_1):PAGE299',
 WATTAGE='1/16W',
 TOLERANCE='5%',
 MATERIAL='CHIP',
 PHYS_PAGE='126',
 XY='(-1750,1475)',
 ROT='0',
 VER='2',
 PACK_TYPE='0402LF',
 LOCATION='R3434',
 CDS_LIB='pure_quanta',
 CDS_PART_NAME='Q_RES_0402LF-4.7K,5%,1/16W,CHIP,CS24702JB10',
 PART_NUMBER='CS24702JB10',
 VALUE='4.7K',
 PRIM_FILE='./archive_libs/logical/q_res/chips/chips.prt';

PART_NAME
 R3435 'Q_RES_0402LF-4.7K,5%,1/16W,CHIP,CS24702JB10':;

SECTION_NUMBER 1
 '@T6G_MB_LIB.T6G(SCH_1):PAGE299_I23@PURE_QUANTA.Q_RES(CHIPS)':
 C_PATH='@t6g_mb_lib.t6g(sch_1):page299_i23@pure_quanta.q_res(chips)',
 P_PATH='@t6g_mb_lib.t6g(sch_1):page126_i23@pure_quanta.q_res(chips)',
 PATH='I23',
 DRAWING='@T6G_MB_LIB.T6G(SCH_1):PAGE299',
 WATTAGE='1/16W',
 TOLERANCE='5%',
 MATERIAL='CHIP',
 PHYS_PAGE='126',
 XY='(-1725,-75)',
 ROT='0',
 VER='2',
 PACK_TYPE='0402LF',
 LOCATION='R3435',
 CDS_LIB='pure_quanta',
 CDS_PART_NAME='Q_RES_0402LF-4.7K,5%,1/16W,CHIP,CS24702JB10',
 PART_NUMBER='CS24702JB10',
 VALUE='4.7K',
 PRIM_FILE='./archive_libs/logical/q_res/chips/chips.prt';

PART_NAME
 R3436 'Q_RES_0402LF-100K,1%,1/16W,CHIP,CS41002FB09':;

SECTION_NUMBER 1
 '@T6G_MB_LIB.T6G(SCH_1):PAGE299_I45@PURE_QUANTA.Q_RES(CHIPS)':
 C_PATH='@t6g_mb_lib.t6g(sch_1):page299_i45@pure_quanta.q_res(chips)',
 P_PATH='@t6g_mb_lib.t6g(sch_1):page126_i45@pure_quanta.q_res(chips)',
 PATH='I45',
 DRAWING='@T6G_MB_LIB.T6G(SCH_1):PAGE299',
 WATTAGE='1/16W',
 TOLERANCE='1%',
 MATERIAL='CHIP',
 PHYS_PAGE='126',
 XY='(-800,1725)',
 ROT='0',
 VER='2',
 PACK_TYPE='0402LF',
 LOCATION='R3436',
 CDS_LIB='pure_quanta',
 CDS_PART_NAME='Q_RES_0402LF-100K,1%,1/16W,CHIP,CS41002FB09',
 PART_NUMBER='CS41002FB09',
 VALUE='100K',
 PRIM_FILE='./archive_libs/logical/q_res/chips/chips.prt';

PART_NAME
 R3437 'Q_RES_0402LF-100K,1%,1/16W,CHIP,CS41002FB09':;

SECTION_NUMBER 1
 '@T6G_MB_LIB.T6G(SCH_1):PAGE299_I27@PURE_QUANTA.Q_RES(CHIPS)':
 C_PATH='@t6g_mb_lib.t6g(sch_1):page299_i27@pure_quanta.q_res(chips)',
 P_PATH='@t6g_mb_lib.t6g(sch_1):page126_i27@pure_quanta.q_res(chips)',
 PATH='I27',
 DRAWING='@T6G_MB_LIB.T6G(SCH_1):PAGE299',
 WATTAGE='1/16W',
 TOLERANCE='1%',
 MATERIAL='CHIP',
 PHYS_PAGE='126',
 XY='(-800,175)',
 ROT='0',
 VER='2',
 PACK_TYPE='0402LF',
 LOCATION='R3437',
 CDS_LIB='pure_quanta',
 CDS_PART_NAME='Q_RES_0402LF-100K,1%,1/16W,CHIP,CS41002FB09',
 PART_NUMBER='CS41002FB09',
 VALUE='100K',
 PRIM_FILE='./archive_libs/logical/q_res/chips/chips.prt';

PART_NAME
 R3438 'Q_RES_0402LF-100K,1%,1/16W,CHIP,CS41002FB09':;

SECTION_NUMBER 1
 '@T6G_MB_LIB.T6G(SCH_1):PAGE299_I55@PURE_QUANTA.Q_RES(CHIPS)':
 C_PATH='@t6g_mb_lib.t6g(sch_1):page299_i55@pure_quanta.q_res(chips)',
 P_PATH='@t6g_mb_lib.t6g(sch_1):page126_i55@pure_quanta.q_res(chips)',
 PATH='I55',
 DRAWING='@T6G_MB_LIB.T6G(SCH_1):PAGE299',
 WATTAGE='1/16W',
 TOLERANCE='1%',
 MATERIAL='CHIP',
 PHYS_PAGE='126',
 XY='(-775,3100)',
 ROT='0',
 VER='2',
 PACK_TYPE='0402LF',
 LOCATION='R3438',
 CDS_LIB='pure_quanta',
 CDS_PART_NAME='Q_RES_0402LF-100K,1%,1/16W,CHIP,CS41002FB09',
 PART_NUMBER='CS41002FB09',
 VALUE='100K',
 PRIM_FILE='./archive_libs/logical/q_res/chips/chips.prt';

PART_NAME
 R3439 'Q_RES_0402LF-100K,1%,1/16W,CHIP,CS41002FB09':;

SECTION_NUMBER 1
 '@T6G_MB_LIB.T6G(SCH_1):PAGE299_I59@PURE_QUANTA.Q_RES(CHIPS)':
 C_PATH='@t6g_mb_lib.t6g(sch_1):page299_i59@pure_quanta.q_res(chips)',
 P_PATH='@t6g_mb_lib.t6g(sch_1):page126_i59@pure_quanta.q_res(chips)',
 PATH='I59',
 DRAWING='@T6G_MB_LIB.T6G(SCH_1):PAGE299',
 WATTAGE='1/16W',
 TOLERANCE='1%',
 MATERIAL='CHIP',
 PHYS_PAGE='126',
 XY='(-675,4500)',
 ROT='2',
 VER='2',
 PACK_TYPE='0402LF',
 LOCATION='R3439',
 CDS_LIB='pure_quanta',
 CDS_PART_NAME='Q_RES_0402LF-100K,1%,1/16W,CHIP,CS41002FB09',
 PART_NUMBER='CS41002FB09',
 VALUE='100K',
 PRIM_FILE='./archive_libs/logical/q_res/chips/chips.prt';

PART_NAME
 R3440 'Q_RES_0402LF-0,5%,1/16W,EMPTY,CS00002JB13':;

SECTION_NUMBER 1
 '@T6G_MB_LIB.T6G(SCH_1):PAGE330_I65@PURE_QUANTA.Q_RES(CHIPS)':
 C_PATH='@t6g_mb_lib.t6g(sch_1):page330_i65@pure_quanta.q_res(chips)',
 P_PATH='@t6g_mb_lib.t6g(sch_1):page123_i65@pure_quanta.q_res(chips)',
 PATH='I65',
 DRAWING='@T6G_MB_LIB.T6G(SCH_1):PAGE330',
 WATTAGE='1/16W',
 TOLERANCE='5%',
 MATERIAL='EMPTY',
 PHYS_PAGE='123',
 XY='(650,3950)',
 ROT='0',
 VER='1',
 PACK_TYPE='0402LF',
 LOCATION='R3440',
 CDS_LIB='pure_quanta',
 CDS_PART_NAME='Q_RES_0402LF-0,5%,1/16W,EMPTY,CS00002JB13',
 PART_NUMBER='CS00002JB13',
 VALUE='0',
 PRIM_FILE='./archive_libs/logical/q_res/chips/chips.prt';

PART_NAME
 R3441 'Q_RES_0402LF-0,5%,1/16W,CHIP,CS00002JB13':;

SECTION_NUMBER 1
 '@T6G_MB_LIB.T6G(SCH_1):PAGE330_I64@PURE_QUANTA.Q_RES(CHIPS)':
 C_PATH='@t6g_mb_lib.t6g(sch_1):page330_i64@pure_quanta.q_res(chips)',
 P_PATH='@t6g_mb_lib.t6g(sch_1):page123_i64@pure_quanta.q_res(chips)',
 PATH='I64',
 DRAWING='@T6G_MB_LIB.T6G(SCH_1):PAGE330',
 WATTAGE='1/16W',
 TOLERANCE='5%',
 MATERIAL='CHIP',
 PHYS_PAGE='123',
 XY='(650,3750)',
 ROT='0',
 VER='1',
 PACK_TYPE='0402LF',
 LOCATION='R3441',
 CDS_LIB='pure_quanta',
 CDS_PART_NAME='Q_RES_0402LF-0,5%,1/16W,CHIP,CS00002JB13',
 PART_NUMBER='CS00002JB13',
 VALUE='0',
 PRIM_FILE='./archive_libs/logical/q_res/chips/chips.prt';

PART_NAME
 R3442 'Q_RES_0402LF-0,5%,1/16W,CHIP,CS00002JB13':;

SECTION_NUMBER 1
 '@T6G_MB_LIB.T6G(SCH_1):PAGE330_I67@PURE_QUANTA.Q_RES(CHIPS)':
 C_PATH='@t6g_mb_lib.t6g(sch_1):page330_i67@pure_quanta.q_res(chips)',
 P_PATH='@t6g_mb_lib.t6g(sch_1):page123_i67@pure_quanta.q_res(chips)',
 PATH='I67',
 DRAWING='@T6G_MB_LIB.T6G(SCH_1):PAGE330',
 WATTAGE='1/16W',
 TOLERANCE='5%',
 MATERIAL='CHIP',
 PHYS_PAGE='123',
 XY='(650,3550)',
 ROT='0',
 VER='1',
 PACK_TYPE='0402LF',
 LOCATION='R3442',
 CDS_LIB='pure_quanta',
 CDS_PART_NAME='Q_RES_0402LF-0,5%,1/16W,CHIP,CS00002JB13',
 PART_NUMBER='CS00002JB13',
 VALUE='0',
 PRIM_FILE='./archive_libs/logical/q_res/chips/chips.prt';

PART_NAME
 R3443 'Q_RES_0402LF-0,5%,1/16W,CHIP,CS00002JB13':;

SECTION_NUMBER 1
 '@T6G_MB_LIB.T6G(SCH_1):PAGE330_I66@PURE_QUANTA.Q_RES(CHIPS)':
 C_PATH='@t6g_mb_lib.t6g(sch_1):page330_i66@pure_quanta.q_res(chips)',
 P_PATH='@t6g_mb_lib.t6g(sch_1):page123_i66@pure_quanta.q_res(chips)',
 PATH='I66',
 DRAWING='@T6G_MB_LIB.T6G(SCH_1):PAGE330',
 WATTAGE='1/16W',
 TOLERANCE='5%',
 MATERIAL='CHIP',
 PHYS_PAGE='123',
 XY='(650,3350)',
 ROT='0',
 VER='1',
 PACK_TYPE='0402LF',
 LOCATION='R3443',
 CDS_LIB='pure_quanta',
 CDS_PART_NAME='Q_RES_0402LF-0,5%,1/16W,CHIP,CS00002JB13',
 PART_NUMBER='CS00002JB13',
 VALUE='0',
 PRIM_FILE='./archive_libs/logical/q_res/chips/chips.prt';

PART_NAME
 R3448 'Q_RES_0402LF-4.7K,5%,1/16W,EMPTY,CS24702JB10':;

SECTION_NUMBER 1
 '@T6G_MB_LIB.T6G(SCH_1):PAGE334_I168@PURE_QUANTA.Q_RES(CHIPS)':
 C_PATH='@t6g_mb_lib.t6g(sch_1):page334_i168@pure_quanta.q_res(chips)',
 P_PATH='@t6g_mb_lib.t6g(sch_1):page128_i168@pure_quanta.q_res(chips)',
 PATH='I168',
 DRAWING='@T6G_MB_LIB.T6G(SCH_1):PAGE334',
 WATTAGE='1/16W',
 TOLERANCE='5%',
 MATERIAL='EMPTY',
 PHYS_PAGE='128',
 XY='(-7600,4400)',
 ROT='0',
 VER='2',
 PACK_TYPE='0402LF',
 LOCATION='R3448',
 CDS_LIB='pure_quanta',
 CDS_PART_NAME='Q_RES_0402LF-4.7K,5%,1/16W,EMPTY,CS24702JB10',
 PART_NUMBER='CS24702JB10',
 VALUE='4.7K',
 PRIM_FILE='./archive_libs/logical/q_res/chips/chips.prt';

PART_NAME
 R3449 'Q_RES_0402LF-100K,1%,1/16W,CHIP,CS41002FB09':;

SECTION_NUMBER 1
 '@T6G_MB_LIB.T6G(SCH_1):PAGE334_I170@PURE_QUANTA.Q_RES(CHIPS)':
 C_PATH='@t6g_mb_lib.t6g(sch_1):page334_i170@pure_quanta.q_res(chips)',
 P_PATH='@t6g_mb_lib.t6g(sch_1):page128_i170@pure_quanta.q_res(chips)',
 PATH='I170',
 DRAWING='@T6G_MB_LIB.T6G(SCH_1):PAGE334',
 WATTAGE='1/16W',
 TOLERANCE='1%',
 MATERIAL='CHIP',
 PHYS_PAGE='128',
 XY='(-7575,3925)',
 ROT='0',
 VER='2',
 PACK_TYPE='0402LF',
 LOCATION='R3449',
 CDS_LIB='pure_quanta',
 CDS_PART_NAME='Q_RES_0402LF-100K,1%,1/16W,CHIP,CS41002FB09',
 PART_NUMBER='CS41002FB09',
 VALUE='100K',
 PRIM_FILE='./archive_libs/logical/q_res/chips/chips.prt';

PART_NAME
 R3451 'Q_RES_0402LF-4.7K,5%,1/16W,EMPTY,CS24702JB10':;

SECTION_NUMBER 1
 '@T6G_MB_LIB.T6G(SCH_1):PAGE334_I127@PURE_QUANTA.Q_RES(CHIPS)':
 C_PATH='@t6g_mb_lib.t6g(sch_1):page334_i127@pure_quanta.q_res(chips)',
 P_PATH='@t6g_mb_lib.t6g(sch_1):page128_i127@pure_quanta.q_res(chips)',
 PATH='I127',
 DRAWING='@T6G_MB_LIB.T6G(SCH_1):PAGE334',
 WATTAGE='1/16W',
 TOLERANCE='5%',
 MATERIAL='EMPTY',
 PHYS_PAGE='128',
 XY='(-7600,3350)',
 ROT='0',
 VER='2',
 PACK_TYPE='0402LF',
 LOCATION='R3451',
 CDS_LIB='pure_quanta',
 CDS_PART_NAME='Q_RES_0402LF-4.7K,5%,1/16W,EMPTY,CS24702JB10',
 PART_NUMBER='CS24702JB10',
 VALUE='4.7K',
 PRIM_FILE='./archive_libs/logical/q_res/chips/chips.prt';

PART_NAME
 R3452 'Q_RES_0402LF-100K,1%,1/16W,CHIP,CS41002FB09':;

SECTION_NUMBER 1
 '@T6G_MB_LIB.T6G(SCH_1):PAGE334_I95@PURE_QUANTA.Q_RES(CHIPS)':
 C_PATH='@t6g_mb_lib.t6g(sch_1):page334_i95@pure_quanta.q_res(chips)',
 P_PATH='@t6g_mb_lib.t6g(sch_1):page128_i95@pure_quanta.q_res(chips)',
 PATH='I95',
 DRAWING='@T6G_MB_LIB.T6G(SCH_1):PAGE334',
 WATTAGE='1/16W',
 TOLERANCE='1%',
 MATERIAL='CHIP',
 PHYS_PAGE='128',
 XY='(-7575,2875)',
 ROT='0',
 VER='2',
 PACK_TYPE='0402LF',
 LOCATION='R3452',
 CDS_LIB='pure_quanta',
 CDS_PART_NAME='Q_RES_0402LF-100K,1%,1/16W,CHIP,CS41002FB09',
 PART_NUMBER='CS41002FB09',
 VALUE='100K',
 PRIM_FILE='./archive_libs/logical/q_res/chips/chips.prt';

PART_NAME
 R3453 'Q_RES_0402LF-100K,1%,1/16W,EMPTY,CS41002FB09':;

SECTION_NUMBER 1
 '@T6G_MB_LIB.T6G(SCH_1):PAGE334_I164@PURE_QUANTA.Q_RES(CHIPS)':
 C_PATH='@t6g_mb_lib.t6g(sch_1):page334_i164@pure_quanta.q_res(chips)',
 P_PATH='@t6g_mb_lib.t6g(sch_1):page128_i164@pure_quanta.q_res(chips)',
 PATH='I164',
 DRAWING='@T6G_MB_LIB.T6G(SCH_1):PAGE334',
 WATTAGE='1/16W',
 TOLERANCE='1%',
 MATERIAL='EMPTY',
 PHYS_PAGE='128',
 XY='(-5000,4425)',
 ROT='0',
 VER='2',
 PACK_TYPE='0402LF',
 LOCATION='R3453',
 CDS_LIB='pure_quanta',
 CDS_PART_NAME='Q_RES_0402LF-100K,1%,1/16W,EMPTY,CS41002FB09',
 PART_NUMBER='CS41002FB09',
 VALUE='100K',
 PRIM_FILE='./archive_libs/logical/q_res/chips/chips.prt';

PART_NAME
 R3454 'Q_RES_0402LF-1K,1%,1/16W,CHIP,CS21002FB06':;

SECTION_NUMBER 1
 '@T6G_MB_LIB.T6G(SCH_1):PAGE334_I165@PURE_QUANTA.Q_RES(CHIPS)':
 C_PATH='@t6g_mb_lib.t6g(sch_1):page334_i165@pure_quanta.q_res(chips)',
 P_PATH='@t6g_mb_lib.t6g(sch_1):page128_i165@pure_quanta.q_res(chips)',
 PATH='I165',
 DRAWING='@T6G_MB_LIB.T6G(SCH_1):PAGE334',
 WATTAGE='1/16W',
 TOLERANCE='1%',
 MATERIAL='CHIP',
 PHYS_PAGE='128',
 XY='(-4975,3825)',
 ROT='0',
 VER='2',
 PACK_TYPE='0402LF',
 LOCATION='R3454',
 CDS_LIB='pure_quanta',
 CDS_PART_NAME='Q_RES_0402LF-1K,1%,1/16W,CHIP,CS21002FB06',
 PART_NUMBER='CS21002FB06',
 VALUE='1K',
 PRIM_FILE='./archive_libs/logical/q_res/chips/chips.prt';

PART_NAME
 R3455 'Q_RES_0402LF-10K,1%,1/16W,CHIP,CS31002FB08':;

SECTION_NUMBER 1
 '@T6G_MB_LIB.T6G(SCH_1):PAGE334_I139@PURE_QUANTA.Q_RES(CHIPS)':
 C_PATH='@t6g_mb_lib.t6g(sch_1):page334_i139@pure_quanta.q_res(chips)',
 P_PATH='@t6g_mb_lib.t6g(sch_1):page128_i139@pure_quanta.q_res(chips)',
 PATH='I139',
 DRAWING='@T6G_MB_LIB.T6G(SCH_1):PAGE334',
 WATTAGE='1/16W',
 TOLERANCE='1%',
 MATERIAL='CHIP',
 PHYS_PAGE='128',
 XY='(-4950,975)',
 ROT='0',
 VER='2',
 PACK_TYPE='0402LF',
 LOCATION='R3455',
 CDS_LIB='pure_quanta',
 CDS_PART_NAME='Q_RES_0402LF-10K,1%,1/16W,CHIP,CS31002FB08',
 PART_NUMBER='CS31002FB08',
 VALUE='10K',
 PRIM_FILE='./archive_libs/logical/q_res/chips/chips.prt';

PART_NAME
 R3456 'Q_RES_0402LF-100K,1%,1/16W,EMPTY,CS41002FB09':;

SECTION_NUMBER 1
 '@T6G_MB_LIB.T6G(SCH_1):PAGE334_I124@PURE_QUANTA.Q_RES(CHIPS)':
 C_PATH='@t6g_mb_lib.t6g(sch_1):page334_i124@pure_quanta.q_res(chips)',
 P_PATH='@t6g_mb_lib.t6g(sch_1):page128_i124@pure_quanta.q_res(chips)',
 PATH='I124',
 DRAWING='@T6G_MB_LIB.T6G(SCH_1):PAGE334',
 WATTAGE='1/16W',
 TOLERANCE='1%',
 MATERIAL='EMPTY',
 PHYS_PAGE='128',
 XY='(-4975,3225)',
 ROT='0',
 VER='2',
 PACK_TYPE='0402LF',
 LOCATION='R3456',
 CDS_LIB='pure_quanta',
 CDS_PART_NAME='Q_RES_0402LF-100K,1%,1/16W,EMPTY,CS41002FB09',
 PART_NUMBER='CS41002FB09',
 VALUE='100K',
 PRIM_FILE='./archive_libs/logical/q_res/chips/chips.prt';

PART_NAME
 R3457 'Q_RES_0402LF-10K,1%,1/16W,CHIP,CS31002FB08':;

SECTION_NUMBER 1
 '@T6G_MB_LIB.T6G(SCH_1):PAGE334_I123@PURE_QUANTA.Q_RES(CHIPS)':
 C_PATH='@t6g_mb_lib.t6g(sch_1):page334_i123@pure_quanta.q_res(chips)',
 P_PATH='@t6g_mb_lib.t6g(sch_1):page128_i123@pure_quanta.q_res(chips)',
 PATH='I123',
 DRAWING='@T6G_MB_LIB.T6G(SCH_1):PAGE334',
 WATTAGE='1/16W',
 TOLERANCE='1%',
 MATERIAL='CHIP',
 PHYS_PAGE='128',
 XY='(-4950,2725)',
 ROT='0',
 VER='2',
 PACK_TYPE='0402LF',
 LOCATION='R3457',
 CDS_LIB='pure_quanta',
 CDS_PART_NAME='Q_RES_0402LF-10K,1%,1/16W,CHIP,CS31002FB08',
 PART_NUMBER='CS31002FB08',
 VALUE='10K',
 PRIM_FILE='./archive_libs/logical/q_res/chips/chips.prt';

PART_NAME
 R3459 'Q_RES_0402LF-1K,1%,1/16W,CHIP,CS21002FB06':;

SECTION_NUMBER 1
 '@T6G_MB_LIB.T6G(SCH_1):PAGE255_I75@PURE_QUANTA.Q_RES(CHIPS)':
 C_PATH='@t6g_mb_lib.t6g(sch_1):page255_i75@pure_quanta.q_res(chips)',
 P_PATH='@t6g_mb_lib.t6g(sch_1):page129_i75@pure_quanta.q_res(chips)',
 PATH='I75',
 DRAWING='@T6G_MB_LIB.T6G(SCH_1):PAGE255',
 WATTAGE='1/16W',
 TOLERANCE='1%',
 MATERIAL='CHIP',
 PHYS_PAGE='129',
 XY='(-650,4575)',
 ROT='0',
 VER='2',
 PACK_TYPE='0402LF',
 LOCATION='R3459',
 CDS_LIB='pure_quanta',
 CDS_PART_NAME='Q_RES_0402LF-1K,1%,1/16W,CHIP,CS21002FB06',
 PART_NUMBER='CS21002FB06',
 VALUE='1K',
 PRIM_FILE='./archive_libs/logical/q_res/chips/chips.prt';

PART_NAME
 R3460 'Q_RES_0402LF-100K,1%,1/16W,EMPTY,CS41002FB09':;

SECTION_NUMBER 1
 '@T6G_MB_LIB.T6G(SCH_1):PAGE255_I31@PURE_QUANTA.Q_RES(CHIPS)':
 C_PATH='@t6g_mb_lib.t6g(sch_1):page255_i31@pure_quanta.q_res(chips)',
 P_PATH='@t6g_mb_lib.t6g(sch_1):page129_i31@pure_quanta.q_res(chips)',
 PATH='I31',
 DRAWING='@T6G_MB_LIB.T6G(SCH_1):PAGE255',
 WATTAGE='1/16W',
 TOLERANCE='1%',
 MATERIAL='EMPTY',
 PHYS_PAGE='129',
 XY='(-625,4100)',
 ROT='0',
 VER='2',
 PACK_TYPE='0402LF',
 LOCATION='R3460',
 CDS_LIB='pure_quanta',
 CDS_PART_NAME='Q_RES_0402LF-100K,1%,1/16W,EMPTY,CS41002FB09',
 PART_NUMBER='CS41002FB09',
 VALUE='100K',
 PRIM_FILE='./archive_libs/logical/q_res/chips/chips.prt';

PART_NAME
 R3461 'Q_RES_0402LF-54.9K,1%,1/16W,CHIP,CS35492FB03':;

SECTION_NUMBER 1
 '@T6G_MB_LIB.T6G(SCH_1):PAGE255_I35@PURE_QUANTA.Q_RES(CHIPS)':
 C_PATH='@t6g_mb_lib.t6g(sch_1):page255_i35@pure_quanta.q_res(chips)',
 P_PATH='@t6g_mb_lib.t6g(sch_1):page129_i35@pure_quanta.q_res(chips)',
 PATH='I35',
 DRAWING='@T6G_MB_LIB.T6G(SCH_1):PAGE255',
 WATTAGE='1/16W',
 TOLERANCE='1%',
 MATERIAL='CHIP',
 PHYS_PAGE='129',
 XY='(1850,4600)',
 ROT='0',
 VER='2',
 PACK_TYPE='0402LF',
 LOCATION='R3461',
 CDS_LIB='pure_quanta',
 CDS_PART_NAME='Q_RES_0402LF-54.9K,1%,1/16W,CHIP,CS35492FB03',
 PART_NUMBER='CS35492FB03',
 VALUE='54.9K',
 PRIM_FILE='./archive_libs/logical/q_res/chips/chips.prt';

PART_NAME
 R3462 'Q_RES_0402LF-100K,1%,1/16W,EMPTY,CS41002FB09':;

SECTION_NUMBER 1
 '@T6G_MB_LIB.T6G(SCH_1):PAGE255_I33@PURE_QUANTA.Q_RES(CHIPS)':
 C_PATH='@t6g_mb_lib.t6g(sch_1):page255_i33@pure_quanta.q_res(chips)',
 P_PATH='@t6g_mb_lib.t6g(sch_1):page129_i33@pure_quanta.q_res(chips)',
 PATH='I33',
 DRAWING='@T6G_MB_LIB.T6G(SCH_1):PAGE255',
 WATTAGE='1/16W',
 TOLERANCE='1%',
 MATERIAL='EMPTY',
 PHYS_PAGE='129',
 XY='(1875,4000)',
 ROT='0',
 VER='2',
 PACK_TYPE='0402LF',
 LOCATION='R3462',
 CDS_LIB='pure_quanta',
 CDS_PART_NAME='Q_RES_0402LF-100K,1%,1/16W,EMPTY,CS41002FB09',
 PART_NUMBER='CS41002FB09',
 VALUE='100K',
 PRIM_FILE='./archive_libs/logical/q_res/chips/chips.prt';

PART_NAME
 R3463 'Q_RES_0402LF-54.9K,1%,1/16W,CHIP,CS35492FB03':;

SECTION_NUMBER 1
 '@T6G_MB_LIB.T6G(SCH_1):PAGE299_I131@PURE_QUANTA.Q_RES(CHIPS)':
 C_PATH='@t6g_mb_lib.t6g(sch_1):page299_i131@pure_quanta.q_res(chips)',
 P_PATH='@t6g_mb_lib.t6g(sch_1):page126_i131@pure_quanta.q_res(chips)',
 PATH='I131',
 DRAWING='@T6G_MB_LIB.T6G(SCH_1):PAGE299',
 WATTAGE='1/16W',
 TOLERANCE='1%',
 MATERIAL='CHIP',
 PHYS_PAGE='126',
 XY='(-2950,2125)',
 ROT='0',
 VER='2',
 PACK_TYPE='0402LF',
 LOCATION='R3463',
 CDS_LIB='pure_quanta',
 CDS_PART_NAME='Q_RES_0402LF-54.9K,1%,1/16W,CHIP,CS35492FB03',
 PART_NUMBER='CS35492FB03',
 VALUE='54.9K',
 PRIM_FILE='./archive_libs/logical/q_res/chips/chips.prt';

PART_NAME
 R3464 'Q_RES_0402LF-54.9K,1%,1/16W,CHIP,CS35492FB03':;

SECTION_NUMBER 1
 '@T6G_MB_LIB.T6G(SCH_1):PAGE299_I134@PURE_QUANTA.Q_RES(CHIPS)':
 C_PATH='@t6g_mb_lib.t6g(sch_1):page299_i134@pure_quanta.q_res(chips)',
 P_PATH='@t6g_mb_lib.t6g(sch_1):page126_i134@pure_quanta.q_res(chips)',
 PATH='I134',
 DRAWING='@T6G_MB_LIB.T6G(SCH_1):PAGE299',
 WATTAGE='1/16W',
 TOLERANCE='1%',
 MATERIAL='CHIP',
 PHYS_PAGE='126',
 XY='(-2975,-375)',
 ROT='0',
 VER='2',
 PACK_TYPE='0402LF',
 LOCATION='R3464',
 CDS_LIB='pure_quanta',
 CDS_PART_NAME='Q_RES_0402LF-54.9K,1%,1/16W,CHIP,CS35492FB03',
 PART_NUMBER='CS35492FB03',
 VALUE='54.9K',
 PRIM_FILE='./archive_libs/logical/q_res/chips/chips.prt';

PART_NAME
 R3465 'Q_RES_0402LF-10K,1%,1/16W,CHIP,CS31002FB08':;

SECTION_NUMBER 1
 '@T6G_MB_LIB.T6G(SCH_1):PAGE299_I132@PURE_QUANTA.Q_RES(CHIPS)':
 C_PATH='@t6g_mb_lib.t6g(sch_1):page299_i132@pure_quanta.q_res(chips)',
 P_PATH='@t6g_mb_lib.t6g(sch_1):page126_i132@pure_quanta.q_res(chips)',
 PATH='I132',
 DRAWING='@T6G_MB_LIB.T6G(SCH_1):PAGE299',
 WATTAGE='1/16W',
 TOLERANCE='1%',
 MATERIAL='CHIP',
 PHYS_PAGE='126',
 XY='(-2925,1250)',
 ROT='0',
 VER='2',
 PACK_TYPE='0402LF',
 LOCATION='R3465',
 CDS_LIB='pure_quanta',
 CDS_PART_NAME='Q_RES_0402LF-10K,1%,1/16W,CHIP,CS31002FB08',
 PART_NUMBER='CS31002FB08',
 VALUE='10K',
 PRIM_FILE='./archive_libs/logical/q_res/chips/chips.prt';

PART_NAME
 R3466 'Q_RES_0402LF-10K,1%,1/16W,CHIP,CS31002FB08':;

SECTION_NUMBER 1
 '@T6G_MB_LIB.T6G(SCH_1):PAGE334_I184@PURE_QUANTA.Q_RES(CHIPS)':
 C_PATH='@t6g_mb_lib.t6g(sch_1):page334_i184@pure_quanta.q_res(chips)',
 P_PATH='@t6g_mb_lib.t6g(sch_1):page128_i184@pure_quanta.q_res(chips)',
 PATH='I184',
 DRAWING='@T6G_MB_LIB.T6G(SCH_1):PAGE334',
 WATTAGE='1/16W',
 TOLERANCE='1%',
 MATERIAL='CHIP',
 PHYS_PAGE='128',
 XY='(-4975,-175)',
 ROT='0',
 VER='2',
 PACK_TYPE='0402LF',
 LOCATION='R3466',
 CDS_LIB='pure_quanta',
 CDS_PART_NAME='Q_RES_0402LF-10K,1%,1/16W,CHIP,CS31002FB08',
 PART_NUMBER='CS31002FB08',
 VALUE='10K',
 PRIM_FILE='./archive_libs/logical/q_res/chips/chips.prt';

PART_NAME
 R3467 'Q_RES_0402LF-10K,1%,1/16W,CHIP,CS31002FB08':;

SECTION_NUMBER 1
 '@T6G_MB_LIB.T6G(SCH_1):PAGE334_I181@PURE_QUANTA.Q_RES(CHIPS)':
 C_PATH='@t6g_mb_lib.t6g(sch_1):page334_i181@pure_quanta.q_res(chips)',
 P_PATH='@t6g_mb_lib.t6g(sch_1):page128_i181@pure_quanta.q_res(chips)',
 PATH='I181',
 DRAWING='@T6G_MB_LIB.T6G(SCH_1):PAGE334',
 WATTAGE='1/16W',
 TOLERANCE='1%',
 MATERIAL='CHIP',
 PHYS_PAGE='128',
 XY='(-4950,1625)',
 ROT='0',
 VER='2',
 PACK_TYPE='0402LF',
 LOCATION='R3467',
 CDS_LIB='pure_quanta',
 CDS_PART_NAME='Q_RES_0402LF-10K,1%,1/16W,CHIP,CS31002FB08',
 PART_NUMBER='CS31002FB08',
 VALUE='10K',
 PRIM_FILE='./archive_libs/logical/q_res/chips/chips.prt';

PART_NAME
 R3468 'Q_RES_0402LF-49.9,1%,1/16W,CHIP,CS04992FB07':;

SECTION_NUMBER 1
 '@T6G_MB_LIB.T6G(SCH_1):PAGE334_I183@PURE_QUANTA.Q_RES(CHIPS)':
 C_PATH='@t6g_mb_lib.t6g(sch_1):page334_i183@pure_quanta.q_res(chips)',
 P_PATH='@t6g_mb_lib.t6g(sch_1):page128_i183@pure_quanta.q_res(chips)',
 PATH='I183',
 DRAWING='@T6G_MB_LIB.T6G(SCH_1):PAGE334',
 WATTAGE='1/16W',
 TOLERANCE='1%',
 MATERIAL='CHIP',
 PHYS_PAGE='128',
 XY='(-4650,100)',
 ROT='0',
 VER='1',
 PACK_TYPE='0402LF',
 LOCATION='R3468',
 CDS_LIB='pure_quanta',
 CDS_PART_NAME='Q_RES_0402LF-49.9,1%,1/16W,CHIP,CS04992FB07',
 PART_NUMBER='CS04992FB07',
 VALUE='49.9',
 PRIM_FILE='./archive_libs/logical/q_res/chips/chips.prt';

PART_NAME
 R3469 'Q_RES_0402LF-49.9,1%,1/16W,CHIP,CS04992FB07':;

SECTION_NUMBER 1
 '@T6G_MB_LIB.T6G(SCH_1):PAGE334_I180@PURE_QUANTA.Q_RES(CHIPS)':
 C_PATH='@t6g_mb_lib.t6g(sch_1):page334_i180@pure_quanta.q_res(chips)',
 P_PATH='@t6g_mb_lib.t6g(sch_1):page128_i180@pure_quanta.q_res(chips)',
 PATH='I180',
 DRAWING='@T6G_MB_LIB.T6G(SCH_1):PAGE334',
 WATTAGE='1/16W',
 TOLERANCE='1%',
 MATERIAL='CHIP',
 PHYS_PAGE='128',
 XY='(-4625,1900)',
 ROT='0',
 VER='1',
 PACK_TYPE='0402LF',
 LOCATION='R3469',
 CDS_LIB='pure_quanta',
 CDS_PART_NAME='Q_RES_0402LF-49.9,1%,1/16W,CHIP,CS04992FB07',
 PART_NUMBER='CS04992FB07',
 VALUE='49.9',
 PRIM_FILE='./archive_libs/logical/q_res/chips/chips.prt';

PART_NAME
 R3470 'Q_RES_0402LF-1K,1%,1/16W,CHIP,CS21002FB06':;

SECTION_NUMBER 1
 '@T6G_MB_LIB.T6G(SCH_1):PAGE299_I202@PURE_QUANTA.Q_RES(CHIPS)':
 C_PATH='@t6g_mb_lib.t6g(sch_1):page299_i202@pure_quanta.q_res(chips)',
 P_PATH='@t6g_mb_lib.t6g(sch_1):page126_i202@pure_quanta.q_res(chips)',
 PATH='I202',
 DRAWING='@T6G_MB_LIB.T6G(SCH_1):PAGE299',
 WATTAGE='1/16W',
 TOLERANCE='1%',
 MATERIAL='CHIP',
 PHYS_PAGE='126',
 XY='(1575,3600)',
 ROT='0',
 VER='2',
 PACK_TYPE='0402LF',
 LOCATION='R3470',
 CDS_LIB='pure_quanta',
 CDS_PART_NAME='Q_RES_0402LF-1K,1%,1/16W,CHIP,CS21002FB06',
 PART_NUMBER='CS21002FB06',
 VALUE='1K',
 PRIM_FILE='./archive_libs/logical/q_res/chips/chips.prt';

PART_NAME
 R3471 'Q_RES_0402LF-10K,1%,1/16W,EMPTY,CS31002FB08':;

SECTION_NUMBER 1
 '@T6G_MB_LIB.T6G(SCH_1):PAGE299_I187@PURE_QUANTA.Q_RES(CHIPS)':
 C_PATH='@t6g_mb_lib.t6g(sch_1):page299_i187@pure_quanta.q_res(chips)',
 P_PATH='@t6g_mb_lib.t6g(sch_1):page126_i187@pure_quanta.q_res(chips)',
 PATH='I187',
 DRAWING='@T6G_MB_LIB.T6G(SCH_1):PAGE299',
 WATTAGE='1/16W',
 TOLERANCE='1%',
 MATERIAL='EMPTY',
 PHYS_PAGE='126',
 XY='(1600,3050)',
 ROT='0',
 VER='2',
 PACK_TYPE='0402LF',
 LOCATION='R3471',
 CDS_LIB='pure_quanta',
 CDS_PART_NAME='Q_RES_0402LF-10K,1%,1/16W,EMPTY,CS31002FB08',
 PART_NUMBER='CS31002FB08',
 VALUE='10K',
 PRIM_FILE='./archive_libs/logical/q_res/chips/chips.prt';

PART_NAME
 R3472 'Q_RES_0402LF-0,5%,1/16W,EMPTY,CS00002JB13':;

SECTION_NUMBER 1
 '@T6G_MB_LIB.T6G(SCH_1):PAGE299_I198@PURE_QUANTA.Q_RES(CHIPS)':
 C_PATH='@t6g_mb_lib.t6g(sch_1):page299_i198@pure_quanta.q_res(chips)',
 P_PATH='@t6g_mb_lib.t6g(sch_1):page126_i198@pure_quanta.q_res(chips)',
 PATH='I198',
 DRAWING='@T6G_MB_LIB.T6G(SCH_1):PAGE299',
 WATTAGE='1/16W',
 TOLERANCE='5%',
 MATERIAL='EMPTY',
 PHYS_PAGE='126',
 XY='(4600,3675)',
 ROT='1',
 VER='1',
 PACK_TYPE='0402LF',
 LOCATION='R3472',
 CDS_LIB='pure_quanta',
 CDS_PART_NAME='Q_RES_0402LF-0,5%,1/16W,EMPTY,CS00002JB13',
 PART_NUMBER='CS00002JB13',
 VALUE='0',
 PRIM_FILE='./archive_libs/logical/q_res/chips/chips.prt';

PART_NAME
 R3473 'Q_RES_0402LF-100K,1%,1/16W,EMPTY,CS41002FB09':;

SECTION_NUMBER 1
 '@T6G_MB_LIB.T6G(SCH_1):PAGE299_I163@PURE_QUANTA.Q_RES(CHIPS)':
 C_PATH='@t6g_mb_lib.t6g(sch_1):page299_i163@pure_quanta.q_res(chips)',
 P_PATH='@t6g_mb_lib.t6g(sch_1):page126_i163@pure_quanta.q_res(chips)',
 PATH='I163',
 DRAWING='@T6G_MB_LIB.T6G(SCH_1):PAGE299',
 WATTAGE='1/16W',
 TOLERANCE='1%',
 MATERIAL='EMPTY',
 PHYS_PAGE='126',
 XY='(1725,1200)',
 ROT='0',
 VER='2',
 PACK_TYPE='0402LF',
 LOCATION='R3473',
 CDS_LIB='pure_quanta',
 CDS_PART_NAME='Q_RES_0402LF-100K,1%,1/16W,EMPTY,CS41002FB09',
 PART_NUMBER='CS41002FB09',
 VALUE='100K',
 PRIM_FILE='./archive_libs/logical/q_res/chips/chips.prt';

PART_NAME
 R3474 'Q_RES_0402LF-4.7K,5%,1/16W,CHIP,CS24702JB10':;

SECTION_NUMBER 1
 '@T6G_MB_LIB.T6G(SCH_1):PAGE299_I158@PURE_QUANTA.Q_RES(CHIPS)':
 C_PATH='@t6g_mb_lib.t6g(sch_1):page299_i158@pure_quanta.q_res(chips)',
 P_PATH='@t6g_mb_lib.t6g(sch_1):page126_i158@pure_quanta.q_res(chips)',
 PATH='I158',
 DRAWING='@T6G_MB_LIB.T6G(SCH_1):PAGE299',
 WATTAGE='1/16W',
 TOLERANCE='5%',
 MATERIAL='CHIP',
 PHYS_PAGE='126',
 XY='(2950,1925)',
 ROT='0',
 VER='2',
 PACK_TYPE='0402LF',
 LOCATION='R3474',
 CDS_LIB='pure_quanta',
 CDS_PART_NAME='Q_RES_0402LF-4.7K,5%,1/16W,CHIP,CS24702JB10',
 PART_NUMBER='CS24702JB10',
 VALUE='4.7K',
 PRIM_FILE='./archive_libs/logical/q_res/chips/chips.prt';

PART_NAME
 R3475 'Q_RES_0402LF-100K,1%,1/16W,CHIP,CS41002FB09':;

SECTION_NUMBER 1
 '@T6G_MB_LIB.T6G(SCH_1):PAGE299_I154@PURE_QUANTA.Q_RES(CHIPS)':
 C_PATH='@t6g_mb_lib.t6g(sch_1):page299_i154@pure_quanta.q_res(chips)',
 P_PATH='@t6g_mb_lib.t6g(sch_1):page126_i154@pure_quanta.q_res(chips)',
 PATH='I154',
 DRAWING='@T6G_MB_LIB.T6G(SCH_1):PAGE299',
 WATTAGE='1/16W',
 TOLERANCE='1%',
 MATERIAL='CHIP',
 PHYS_PAGE='126',
 XY='(3875,2175)',
 ROT='0',
 VER='2',
 PACK_TYPE='0402LF',
 LOCATION='R3475',
 CDS_LIB='pure_quanta',
 CDS_PART_NAME='Q_RES_0402LF-100K,1%,1/16W,CHIP,CS41002FB09',
 PART_NUMBER='CS41002FB09',
 VALUE='100K',
 PRIM_FILE='./archive_libs/logical/q_res/chips/chips.prt';

PART_NAME
 R3476 'Q_RES_0402LF-33.2,1%,1/16W,CHIP,CS03322FB03':;

SECTION_NUMBER 1
 '@T6G_MB_LIB.T6G(SCH_1):PAGE80_I250@PURE_QUANTA.Q_RES(CHIPS)':
 C_PATH='@t6g_mb_lib.t6g(sch_1):page80_i250@pure_quanta.q_res(chips)',
 P_PATH='@t6g_mb_lib.t6g(sch_1):page81_i250@pure_quanta.q_res(chips)',
 PATH='I250',
 DRAWING='@T6G_MB_LIB.T6G(SCH_1):PAGE80',
 WATTAGE='1/16W',
 TOLERANCE='1%',
 MATERIAL='CHIP',
 PHYS_PAGE='81',
 XY='(-2300,2225)',
 ROT='0',
 VER='1',
 PACK_TYPE='0402LF',
 LOCATION='R3476',
 CDS_LIB='pure_quanta',
 CDS_PART_NAME='Q_RES_0402LF-33.2,1%,1/16W,CHIP,CS03322FB03',
 PART_NUMBER='CS03322FB03',
 VALUE='33.2',
 PRIM_FILE='./archive_libs/logical/q_res/chips/chips.prt';

PART_NAME
 R3477 'Q_RES_0402LF-33.2,1%,1/16W,CHIP,CS03322FB03':;

SECTION_NUMBER 1
 '@T6G_MB_LIB.T6G(SCH_1):PAGE80_I286@PURE_QUANTA.Q_RES(CHIPS)':
 C_PATH='@t6g_mb_lib.t6g(sch_1):page80_i286@pure_quanta.q_res(chips)',
 P_PATH='@t6g_mb_lib.t6g(sch_1):page81_i286@pure_quanta.q_res(chips)',
 PATH='I286',
 DRAWING='@T6G_MB_LIB.T6G(SCH_1):PAGE80',
 WATTAGE='1/16W',
 TOLERANCE='1%',
 MATERIAL='CHIP',
 PHYS_PAGE='81',
 XY='(-6725,3125)',
 ROT='0',
 VER='1',
 PACK_TYPE='0402LF',
 LOCATION='R3477',
 CDS_LIB='pure_quanta',
 CDS_PART_NAME='Q_RES_0402LF-33.2,1%,1/16W,CHIP,CS03322FB03',
 PART_NUMBER='CS03322FB03',
 VALUE='33.2',
 PRIM_FILE='./archive_libs/logical/q_res/chips/chips.prt';

PART_NAME
 R3478 'Q_RES_0402LF-33.2,1%,1/16W,CHIP,CS03322FB03':;

SECTION_NUMBER 1
 '@T6G_MB_LIB.T6G(SCH_1):PAGE80_I288@PURE_QUANTA.Q_RES(CHIPS)':
 C_PATH='@t6g_mb_lib.t6g(sch_1):page80_i288@pure_quanta.q_res(chips)',
 P_PATH='@t6g_mb_lib.t6g(sch_1):page81_i288@pure_quanta.q_res(chips)',
 PATH='I288',
 DRAWING='@T6G_MB_LIB.T6G(SCH_1):PAGE80',
 WATTAGE='1/16W',
 TOLERANCE='1%',
 MATERIAL='CHIP',
 PHYS_PAGE='81',
 XY='(-6725,2775)',
 ROT='0',
 VER='1',
 PACK_TYPE='0402LF',
 LOCATION='R3478',
 CDS_LIB='pure_quanta',
 CDS_PART_NAME='Q_RES_0402LF-33.2,1%,1/16W,CHIP,CS03322FB03',
 PART_NUMBER='CS03322FB03',
 VALUE='33.2',
 PRIM_FILE='./archive_libs/logical/q_res/chips/chips.prt';

PART_NAME
 R3479 'Q_RES_0402LF-33.2,1%,1/16W,CHIP,CS03322FB03':;

SECTION_NUMBER 1
 '@T6G_MB_LIB.T6G(SCH_1):PAGE80_I281@PURE_QUANTA.Q_RES(CHIPS)':
 C_PATH='@t6g_mb_lib.t6g(sch_1):page80_i281@pure_quanta.q_res(chips)',
 P_PATH='@t6g_mb_lib.t6g(sch_1):page81_i281@pure_quanta.q_res(chips)',
 PATH='I281',
 DRAWING='@T6G_MB_LIB.T6G(SCH_1):PAGE80',
 WATTAGE='1/16W',
 TOLERANCE='1%',
 MATERIAL='CHIP',
 PHYS_PAGE='81',
 XY='(-2300,1075)',
 ROT='0',
 VER='1',
 PACK_TYPE='0402LF',
 LOCATION='R3479',
 CDS_LIB='pure_quanta',
 CDS_PART_NAME='Q_RES_0402LF-33.2,1%,1/16W,CHIP,CS03322FB03',
 PART_NUMBER='CS03322FB03',
 VALUE='33.2',
 PRIM_FILE='./archive_libs/logical/q_res/chips/chips.prt';

PART_NAME
 R3480 'Q_RES_0402LF-33.2,1%,1/16W,CHIP,CS03322FB03':;

SECTION_NUMBER 1
 '@T6G_MB_LIB.T6G(SCH_1):PAGE80_I247@PURE_QUANTA.Q_RES(CHIPS)':
 C_PATH='@t6g_mb_lib.t6g(sch_1):page80_i247@pure_quanta.q_res(chips)',
 P_PATH='@t6g_mb_lib.t6g(sch_1):page81_i247@pure_quanta.q_res(chips)',
 PATH='I247',
 DRAWING='@T6G_MB_LIB.T6G(SCH_1):PAGE80',
 WATTAGE='1/16W',
 TOLERANCE='1%',
 MATERIAL='CHIP',
 PHYS_PAGE='81',
 XY='(-2300,2175)',
 ROT='0',
 VER='1',
 PACK_TYPE='0402LF',
 LOCATION='R3480',
 CDS_LIB='pure_quanta',
 CDS_PART_NAME='Q_RES_0402LF-33.2,1%,1/16W,CHIP,CS03322FB03',
 PART_NUMBER='CS03322FB03',
 VALUE='33.2',
 PRIM_FILE='./archive_libs/logical/q_res/chips/chips.prt';

PART_NAME
 R3481 'Q_RES_0402LF-33.2,1%,1/16W,CHIP,CS03322FB03':;

SECTION_NUMBER 1
 '@T6G_MB_LIB.T6G(SCH_1):PAGE80_I251@PURE_QUANTA.Q_RES(CHIPS)':
 C_PATH='@t6g_mb_lib.t6g(sch_1):page80_i251@pure_quanta.q_res(chips)',
 P_PATH='@t6g_mb_lib.t6g(sch_1):page81_i251@pure_quanta.q_res(chips)',
 PATH='I251',
 DRAWING='@T6G_MB_LIB.T6G(SCH_1):PAGE80',
 WATTAGE='1/16W',
 TOLERANCE='1%',
 MATERIAL='CHIP',
 PHYS_PAGE='81',
 XY='(-2300,2125)',
 ROT='0',
 VER='1',
 PACK_TYPE='0402LF',
 LOCATION='R3481',
 CDS_LIB='pure_quanta',
 CDS_PART_NAME='Q_RES_0402LF-33.2,1%,1/16W,CHIP,CS03322FB03',
 PART_NUMBER='CS03322FB03',
 VALUE='33.2',
 PRIM_FILE='./archive_libs/logical/q_res/chips/chips.prt';

PART_NAME
 R3482 'Q_RES_0402LF-33.2,1%,1/16W,CHIP,CS03322FB03':;

SECTION_NUMBER 1
 '@T6G_MB_LIB.T6G(SCH_1):PAGE80_I278@PURE_QUANTA.Q_RES(CHIPS)':
 C_PATH='@t6g_mb_lib.t6g(sch_1):page80_i278@pure_quanta.q_res(chips)',
 P_PATH='@t6g_mb_lib.t6g(sch_1):page81_i278@pure_quanta.q_res(chips)',
 PATH='I278',
 DRAWING='@T6G_MB_LIB.T6G(SCH_1):PAGE80',
 WATTAGE='1/16W',
 TOLERANCE='1%',
 MATERIAL='CHIP',
 PHYS_PAGE='81',
 XY='(-2300,1275)',
 ROT='0',
 VER='1',
 PACK_TYPE='0402LF',
 LOCATION='R3482',
 CDS_LIB='pure_quanta',
 CDS_PART_NAME='Q_RES_0402LF-33.2,1%,1/16W,CHIP,CS03322FB03',
 PART_NUMBER='CS03322FB03',
 VALUE='33.2',
 PRIM_FILE='./archive_libs/logical/q_res/chips/chips.prt';

PART_NAME
 R3483 'Q_RES_0402LF-33.2,1%,1/16W,CHIP,CS03322FB03':;

SECTION_NUMBER 1
 '@T6G_MB_LIB.T6G(SCH_1):PAGE80_I290@PURE_QUANTA.Q_RES(CHIPS)':
 C_PATH='@t6g_mb_lib.t6g(sch_1):page80_i290@pure_quanta.q_res(chips)',
 P_PATH='@t6g_mb_lib.t6g(sch_1):page81_i290@pure_quanta.q_res(chips)',
 PATH='I290',
 DRAWING='@T6G_MB_LIB.T6G(SCH_1):PAGE80',
 WATTAGE='1/16W',
 TOLERANCE='1%',
 MATERIAL='CHIP',
 PHYS_PAGE='81',
 XY='(-6725,2575)',
 ROT='0',
 VER='1',
 PACK_TYPE='0402LF',
 LOCATION='R3483',
 CDS_LIB='pure_quanta',
 CDS_PART_NAME='Q_RES_0402LF-33.2,1%,1/16W,CHIP,CS03322FB03',
 PART_NUMBER='CS03322FB03',
 VALUE='33.2',
 PRIM_FILE='./archive_libs/logical/q_res/chips/chips.prt';

PART_NAME
 R3484 'Q_RES_0402LF-33.2,1%,1/16W,CHIP,CS03322FB03':;

SECTION_NUMBER 1
 '@T6G_MB_LIB.T6G(SCH_1):PAGE80_I254@PURE_QUANTA.Q_RES(CHIPS)':
 C_PATH='@t6g_mb_lib.t6g(sch_1):page80_i254@pure_quanta.q_res(chips)',
 P_PATH='@t6g_mb_lib.t6g(sch_1):page81_i254@pure_quanta.q_res(chips)',
 PATH='I254',
 DRAWING='@T6G_MB_LIB.T6G(SCH_1):PAGE80',
 WATTAGE='1/16W',
 TOLERANCE='1%',
 MATERIAL='CHIP',
 PHYS_PAGE='81',
 XY='(-2300,2075)',
 ROT='0',
 VER='1',
 PACK_TYPE='0402LF',
 LOCATION='R3484',
 CDS_LIB='pure_quanta',
 CDS_PART_NAME='Q_RES_0402LF-33.2,1%,1/16W,CHIP,CS03322FB03',
 PART_NUMBER='CS03322FB03',
 VALUE='33.2',
 PRIM_FILE='./archive_libs/logical/q_res/chips/chips.prt';

PART_NAME
 R3485 'Q_RES_0402LF-33.2,1%,1/16W,CHIP,CS03322FB03':;

SECTION_NUMBER 1
 '@T6G_MB_LIB.T6G(SCH_1):PAGE80_I255@PURE_QUANTA.Q_RES(CHIPS)':
 C_PATH='@t6g_mb_lib.t6g(sch_1):page80_i255@pure_quanta.q_res(chips)',
 P_PATH='@t6g_mb_lib.t6g(sch_1):page81_i255@pure_quanta.q_res(chips)',
 PATH='I255',
 DRAWING='@T6G_MB_LIB.T6G(SCH_1):PAGE80',
 WATTAGE='1/16W',
 TOLERANCE='1%',
 MATERIAL='CHIP',
 PHYS_PAGE='81',
 XY='(-2300,2025)',
 ROT='0',
 VER='1',
 PACK_TYPE='0402LF',
 LOCATION='R3485',
 CDS_LIB='pure_quanta',
 CDS_PART_NAME='Q_RES_0402LF-33.2,1%,1/16W,CHIP,CS03322FB03',
 PART_NUMBER='CS03322FB03',
 VALUE='33.2',
 PRIM_FILE='./archive_libs/logical/q_res/chips/chips.prt';

PART_NAME
 R3486 'Q_RES_0402LF-33.2,1%,1/16W,CHIP,CS03322FB03':;

SECTION_NUMBER 1
 '@T6G_MB_LIB.T6G(SCH_1):PAGE80_I258@PURE_QUANTA.Q_RES(CHIPS)':
 C_PATH='@t6g_mb_lib.t6g(sch_1):page80_i258@pure_quanta.q_res(chips)',
 P_PATH='@t6g_mb_lib.t6g(sch_1):page81_i258@pure_quanta.q_res(chips)',
 PATH='I258',
 DRAWING='@T6G_MB_LIB.T6G(SCH_1):PAGE80',
 WATTAGE='1/16W',
 TOLERANCE='1%',
 MATERIAL='CHIP',
 PHYS_PAGE='81',
 XY='(-2300,1975)',
 ROT='0',
 VER='1',
 PACK_TYPE='0402LF',
 LOCATION='R3486',
 CDS_LIB='pure_quanta',
 CDS_PART_NAME='Q_RES_0402LF-33.2,1%,1/16W,CHIP,CS03322FB03',
 PART_NUMBER='CS03322FB03',
 VALUE='33.2',
 PRIM_FILE='./archive_libs/logical/q_res/chips/chips.prt';

PART_NAME
 R3487 'Q_RES_0402LF-10K,1%,1/16W,CHIP,CS31002FB08':;

SECTION_NUMBER 1
 '@T6G_MB_LIB.T6G(SCH_1):PAGE299_I166@PURE_QUANTA.Q_RES(CHIPS)':
 C_PATH='@t6g_mb_lib.t6g(sch_1):page299_i166@pure_quanta.q_res(chips)',
 P_PATH='@t6g_mb_lib.t6g(sch_1):page126_i166@pure_quanta.q_res(chips)',
 PATH='I166',
 DRAWING='@T6G_MB_LIB.T6G(SCH_1):PAGE299',
 WATTAGE='1/16W',
 TOLERANCE='1%',
 MATERIAL='CHIP',
 PHYS_PAGE='126',
 XY='(1700,1625)',
 ROT='0',
 VER='2',
 PACK_TYPE='0402LF',
 LOCATION='R3487',
 CDS_LIB='pure_quanta',
 CDS_PART_NAME='Q_RES_0402LF-10K,1%,1/16W,CHIP,CS31002FB08',
 PART_NUMBER='CS31002FB08',
 VALUE='10K',
 PRIM_FILE='./archive_libs/logical/q_res/chips/chips.prt';

PART_NAME
 R3488 'Q_RES_0402LF-1K,1%,1/16W,CHIP,CS21002FB06':;

SECTION_NUMBER 1
 '@T6G_MB_LIB.T6G(SCH_1):PAGE255_I40@PURE_QUANTA.Q_RES(CHIPS)':
 C_PATH='@t6g_mb_lib.t6g(sch_1):page255_i40@pure_quanta.q_res(chips)',
 P_PATH='@t6g_mb_lib.t6g(sch_1):page129_i40@pure_quanta.q_res(chips)',
 PATH='I40',
 DRAWING='@T6G_MB_LIB.T6G(SCH_1):PAGE255',
 WATTAGE='1/16W',
 TOLERANCE='1%',
 MATERIAL='CHIP',
 PHYS_PAGE='129',
 XY='(-650,3425)',
 ROT='0',
 VER='2',
 PACK_TYPE='0402LF',
 LOCATION='R3488',
 CDS_LIB='pure_quanta',
 CDS_PART_NAME='Q_RES_0402LF-1K,1%,1/16W,CHIP,CS21002FB06',
 PART_NUMBER='CS21002FB06',
 VALUE='1K',
 PRIM_FILE='./archive_libs/logical/q_res/chips/chips.prt';

PART_NAME
 R3489 'Q_RES_0402LF-100K,1%,1/16W,EMPTY,CS41002FB09':;

SECTION_NUMBER 1
 '@T6G_MB_LIB.T6G(SCH_1):PAGE255_I42@PURE_QUANTA.Q_RES(CHIPS)':
 C_PATH='@t6g_mb_lib.t6g(sch_1):page255_i42@pure_quanta.q_res(chips)',
 P_PATH='@t6g_mb_lib.t6g(sch_1):page129_i42@pure_quanta.q_res(chips)',
 PATH='I42',
 DRAWING='@T6G_MB_LIB.T6G(SCH_1):PAGE255',
 WATTAGE='1/16W',
 TOLERANCE='1%',
 MATERIAL='EMPTY',
 PHYS_PAGE='129',
 XY='(-625,2950)',
 ROT='0',
 VER='2',
 PACK_TYPE='0402LF',
 LOCATION='R3489',
 CDS_LIB='pure_quanta',
 CDS_PART_NAME='Q_RES_0402LF-100K,1%,1/16W,EMPTY,CS41002FB09',
 PART_NUMBER='CS41002FB09',
 VALUE='100K',
 PRIM_FILE='./archive_libs/logical/q_res/chips/chips.prt';

PART_NAME
 R3490 'Q_RES_0402LF-1K,1%,1/16W,CHIP,CS21002FB06':;

SECTION_NUMBER 1
 '@T6G_MB_LIB.T6G(SCH_1):PAGE255_I57@PURE_QUANTA.Q_RES(CHIPS)':
 C_PATH='@t6g_mb_lib.t6g(sch_1):page255_i57@pure_quanta.q_res(chips)',
 P_PATH='@t6g_mb_lib.t6g(sch_1):page129_i57@pure_quanta.q_res(chips)',
 PATH='I57',
 DRAWING='@T6G_MB_LIB.T6G(SCH_1):PAGE255',
 WATTAGE='1/16W',
 TOLERANCE='1%',
 MATERIAL='CHIP',
 PHYS_PAGE='129',
 XY='(-650,2075)',
 ROT='0',
 VER='2',
 PACK_TYPE='0402LF',
 LOCATION='R3490',
 CDS_LIB='pure_quanta',
 CDS_PART_NAME='Q_RES_0402LF-1K,1%,1/16W,CHIP,CS21002FB06',
 PART_NUMBER='CS21002FB06',
 VALUE='1K',
 PRIM_FILE='./archive_libs/logical/q_res/chips/chips.prt';

PART_NAME
 R3491 'Q_RES_0402LF-100K,1%,1/16W,EMPTY,CS41002FB09':;

SECTION_NUMBER 1
 '@T6G_MB_LIB.T6G(SCH_1):PAGE255_I70@PURE_QUANTA.Q_RES(CHIPS)':
 C_PATH='@t6g_mb_lib.t6g(sch_1):page255_i70@pure_quanta.q_res(chips)',
 P_PATH='@t6g_mb_lib.t6g(sch_1):page129_i70@pure_quanta.q_res(chips)',
 PATH='I70',
 DRAWING='@T6G_MB_LIB.T6G(SCH_1):PAGE255',
 WATTAGE='1/16W',
 TOLERANCE='1%',
 MATERIAL='EMPTY',
 PHYS_PAGE='129',
 XY='(-600,1600)',
 ROT='0',
 VER='2',
 PACK_TYPE='0402LF',
 LOCATION='R3491',
 CDS_LIB='pure_quanta',
 CDS_PART_NAME='Q_RES_0402LF-100K,1%,1/16W,EMPTY,CS41002FB09',
 PART_NUMBER='CS41002FB09',
 VALUE='100K',
 PRIM_FILE='./archive_libs/logical/q_res/chips/chips.prt';

PART_NAME
 R3492 'Q_RES_0402LF-54.9K,1%,1/16W,CHIP,CS35492FB03':;

SECTION_NUMBER 1
 '@T6G_MB_LIB.T6G(SCH_1):PAGE255_I47@PURE_QUANTA.Q_RES(CHIPS)':
 C_PATH='@t6g_mb_lib.t6g(sch_1):page255_i47@pure_quanta.q_res(chips)',
 P_PATH='@t6g_mb_lib.t6g(sch_1):page129_i47@pure_quanta.q_res(chips)',
 PATH='I47',
 DRAWING='@T6G_MB_LIB.T6G(SCH_1):PAGE255',
 WATTAGE='1/16W',
 TOLERANCE='1%',
 MATERIAL='CHIP',
 PHYS_PAGE='129',
 XY='(1900,3400)',
 ROT='0',
 VER='2',
 PACK_TYPE='0402LF',
 LOCATION='R3492',
 CDS_LIB='pure_quanta',
 CDS_PART_NAME='Q_RES_0402LF-54.9K,1%,1/16W,CHIP,CS35492FB03',
 PART_NUMBER='CS35492FB03',
 VALUE='54.9K',
 PRIM_FILE='./archive_libs/logical/q_res/chips/chips.prt';

PART_NAME
 R3493 'Q_RES_0402LF-100K,1%,1/16W,EMPTY,CS41002FB09':;

SECTION_NUMBER 1
 '@T6G_MB_LIB.T6G(SCH_1):PAGE255_I48@PURE_QUANTA.Q_RES(CHIPS)':
 C_PATH='@t6g_mb_lib.t6g(sch_1):page255_i48@pure_quanta.q_res(chips)',
 P_PATH='@t6g_mb_lib.t6g(sch_1):page129_i48@pure_quanta.q_res(chips)',
 PATH='I48',
 DRAWING='@T6G_MB_LIB.T6G(SCH_1):PAGE255',
 WATTAGE='1/16W',
 TOLERANCE='1%',
 MATERIAL='EMPTY',
 PHYS_PAGE='129',
 XY='(1925,2800)',
 ROT='0',
 VER='2',
 PACK_TYPE='0402LF',
 LOCATION='R3493',
 CDS_LIB='pure_quanta',
 CDS_PART_NAME='Q_RES_0402LF-100K,1%,1/16W,EMPTY,CS41002FB09',
 PART_NUMBER='CS41002FB09',
 VALUE='100K',
 PRIM_FILE='./archive_libs/logical/q_res/chips/chips.prt';

PART_NAME
 R3494 'Q_RES_0402LF-54.9K,1%,1/16W,CHIP,CS35492FB03':;

SECTION_NUMBER 1
 '@T6G_MB_LIB.T6G(SCH_1):PAGE255_I55@PURE_QUANTA.Q_RES(CHIPS)':
 C_PATH='@t6g_mb_lib.t6g(sch_1):page255_i55@pure_quanta.q_res(chips)',
 P_PATH='@t6g_mb_lib.t6g(sch_1):page129_i55@pure_quanta.q_res(chips)',
 PATH='I55',
 DRAWING='@T6G_MB_LIB.T6G(SCH_1):PAGE255',
 WATTAGE='1/16W',
 TOLERANCE='1%',
 MATERIAL='CHIP',
 PHYS_PAGE='129',
 XY='(2075,2100)',
 ROT='0',
 VER='2',
 PACK_TYPE='0402LF',
 LOCATION='R3494',
 CDS_LIB='pure_quanta',
 CDS_PART_NAME='Q_RES_0402LF-54.9K,1%,1/16W,CHIP,CS35492FB03',
 PART_NUMBER='CS35492FB03',
 VALUE='54.9K',
 PRIM_FILE='./archive_libs/logical/q_res/chips/chips.prt';

PART_NAME
 R3495 'Q_RES_0402LF-100K,1%,1/16W,EMPTY,CS41002FB09':;

SECTION_NUMBER 1
 '@T6G_MB_LIB.T6G(SCH_1):PAGE255_I62@PURE_QUANTA.Q_RES(CHIPS)':
 C_PATH='@t6g_mb_lib.t6g(sch_1):page255_i62@pure_quanta.q_res(chips)',
 P_PATH='@t6g_mb_lib.t6g(sch_1):page129_i62@pure_quanta.q_res(chips)',
 PATH='I62',
 DRAWING='@T6G_MB_LIB.T6G(SCH_1):PAGE255',
 WATTAGE='1/16W',
 TOLERANCE='1%',
 MATERIAL='EMPTY',
 PHYS_PAGE='129',
 XY='(2100,1500)',
 ROT='0',
 VER='2',
 PACK_TYPE='0402LF',
 LOCATION='R3495',
 CDS_LIB='pure_quanta',
 CDS_PART_NAME='Q_RES_0402LF-100K,1%,1/16W,EMPTY,CS41002FB09',
 PART_NUMBER='CS41002FB09',
 VALUE='100K',
 PRIM_FILE='./archive_libs/logical/q_res/chips/chips.prt';

PART_NAME
 R3496 'Q_RES_0402LF-33.2,1%,1/16W,CHIP,CS03322FB03':;

SECTION_NUMBER 1
 '@T6G_MB_LIB.T6G(SCH_1):PAGE255_I45@PURE_QUANTA.Q_RES(CHIPS)':
 C_PATH='@t6g_mb_lib.t6g(sch_1):page255_i45@pure_quanta.q_res(chips)',
 P_PATH='@t6g_mb_lib.t6g(sch_1):page129_i45@pure_quanta.q_res(chips)',
 PATH='I45',
 DRAWING='@T6G_MB_LIB.T6G(SCH_1):PAGE255',
 WATTAGE='1/16W',
 TOLERANCE='1%',
 MATERIAL='CHIP',
 PHYS_PAGE='129',
 XY='(2150,3100)',
 ROT='0',
 VER='1',
 PACK_TYPE='0402LF',
 LOCATION='R3496',
 CDS_LIB='pure_quanta',
 CDS_PART_NAME='Q_RES_0402LF-33.2,1%,1/16W,CHIP,CS03322FB03',
 PART_NUMBER='CS03322FB03',
 VALUE='33.2',
 PRIM_FILE='./archive_libs/logical/q_res/chips/chips.prt';

PART_NAME
 R3497 'Q_RES_0402LF-33.2,1%,1/16W,CHIP,CS03322FB03':;

SECTION_NUMBER 1
 '@T6G_MB_LIB.T6G(SCH_1):PAGE255_I53@PURE_QUANTA.Q_RES(CHIPS)':
 C_PATH='@t6g_mb_lib.t6g(sch_1):page255_i53@pure_quanta.q_res(chips)',
 P_PATH='@t6g_mb_lib.t6g(sch_1):page129_i53@pure_quanta.q_res(chips)',
 PATH='I53',
 DRAWING='@T6G_MB_LIB.T6G(SCH_1):PAGE255',
 WATTAGE='1/16W',
 TOLERANCE='1%',
 MATERIAL='CHIP',
 PHYS_PAGE='129',
 XY='(2325,1800)',
 ROT='0',
 VER='1',
 PACK_TYPE='0402LF',
 LOCATION='R3497',
 CDS_LIB='pure_quanta',
 CDS_PART_NAME='Q_RES_0402LF-33.2,1%,1/16W,CHIP,CS03322FB03',
 PART_NUMBER='CS03322FB03',
 VALUE='33.2',
 PRIM_FILE='./archive_libs/logical/q_res/chips/chips.prt';

PART_NAME
 R3498 'Q_RES_0402LF-54.9K,1%,1/16W,CHIP,CS35492FB03':;

SECTION_NUMBER 1
 '@T6G_MB_LIB.T6G(SCH_1):PAGE299_I167@PURE_QUANTA.Q_RES(CHIPS)':
 C_PATH='@t6g_mb_lib.t6g(sch_1):page299_i167@pure_quanta.q_res(chips)',
 P_PATH='@t6g_mb_lib.t6g(sch_1):page126_i167@pure_quanta.q_res(chips)',
 PATH='I167',
 DRAWING='@T6G_MB_LIB.T6G(SCH_1):PAGE299',
 WATTAGE='1/16W',
 TOLERANCE='1%',
 MATERIAL='CHIP',
 PHYS_PAGE='126',
 XY='(-3000,4000)',
 ROT='0',
 VER='2',
 PACK_TYPE='0402LF',
 LOCATION='R3498',
 CDS_LIB='pure_quanta',
 CDS_PART_NAME='Q_RES_0402LF-54.9K,1%,1/16W,CHIP,CS35492FB03',
 PART_NUMBER='CS35492FB03',
 VALUE='54.9K',
 PRIM_FILE='./archive_libs/logical/q_res/chips/chips.prt';

PART_NAME
 R3499 'Q_RES_0402LF-0,5%,1/16W,CHIP,CS00002JB13':;

SECTION_NUMBER 1
 '@T6G_MB_LIB.T6G(SCH_1):PAGE246_I57@PURE_QUANTA.Q_RES(CHIPS)':
 C_PATH='@t6g_mb_lib.t6g(sch_1):page246_i57@pure_quanta.q_res(chips)',
 P_PATH='@t6g_mb_lib.t6g(sch_1):page245_i57@pure_quanta.q_res(chips)',
 PATH='I57',
 DRAWING='@T6G_MB_LIB.T6G(SCH_1):PAGE246',
 WATTAGE='1/16W',
 TOLERANCE='5%',
 MATERIAL='CHIP',
 PHYS_PAGE='245',
 XY='(-3525,2850)',
 ROT='0',
 VER='1',
 PACK_TYPE='0402LF',
 LOCATION='R3499',
 CDS_LIB='pure_quanta',
 CDS_PART_NAME='Q_RES_0402LF-0,5%,1/16W,CHIP,CS00002JB13',
 PART_NUMBER='CS00002JB13',
 VALUE='0',
 PRIM_FILE='./archive_libs/logical/q_res/chips/chips.prt';

PART_NAME
 R3500 'Q_RES_0402LF-4.7K,5%,1/16W,CHIP,CS24702JB10':;

SECTION_NUMBER 1
 '@T6G_MB_LIB.T6G(SCH_1):PAGE248_I27@PURE_QUANTA.Q_RES(CHIPS)':
 C_PATH='@t6g_mb_lib.t6g(sch_1):page248_i27@pure_quanta.q_res(chips)',
 P_PATH='@t6g_mb_lib.t6g(sch_1):page247_i27@pure_quanta.q_res(chips)',
 PATH='I27',
 DRAWING='@T6G_MB_LIB.T6G(SCH_1):PAGE248',
 WATTAGE='1/16W',
 TOLERANCE='5%',
 MATERIAL='CHIP',
 PHYS_PAGE='247',
 XY='(-3025,5450)',
 ROT='0',
 VER='2',
 PACK_TYPE='0402LF',
 LOCATION='R3500',
 CDS_LIB='pure_quanta',
 CDS_PART_NAME='Q_RES_0402LF-4.7K,5%,1/16W,CHIP,CS24702JB10',
 PART_NUMBER='CS24702JB10',
 VALUE='4.7K',
 PRIM_FILE='./archive_libs/logical/q_res/chips/chips.prt';

PART_NAME
 R3501 'Q_RES_0402LF-4.7K,5%,1/16W,CHIP,CS24702JB10':;

SECTION_NUMBER 1
 '@T6G_MB_LIB.T6G(SCH_1):PAGE248_I31@PURE_QUANTA.Q_RES(CHIPS)':
 C_PATH='@t6g_mb_lib.t6g(sch_1):page248_i31@pure_quanta.q_res(chips)',
 P_PATH='@t6g_mb_lib.t6g(sch_1):page247_i31@pure_quanta.q_res(chips)',
 PATH='I31',
 DRAWING='@T6G_MB_LIB.T6G(SCH_1):PAGE248',
 WATTAGE='1/16W',
 TOLERANCE='5%',
 MATERIAL='CHIP',
 PHYS_PAGE='247',
 XY='(-2775,5450)',
 ROT='0',
 VER='2',
 PACK_TYPE='0402LF',
 LOCATION='R3501',
 CDS_LIB='pure_quanta',
 CDS_PART_NAME='Q_RES_0402LF-4.7K,5%,1/16W,CHIP,CS24702JB10',
 PART_NUMBER='CS24702JB10',
 VALUE='4.7K',
 PRIM_FILE='./archive_libs/logical/q_res/chips/chips.prt';

PART_NAME
 R3502 'Q_RES_0402LF-100K,1%,1/16W,EMPTY,CS41002FB09':;

SECTION_NUMBER 1
 '@T6G_MB_LIB.T6G(SCH_1):PAGE299_I181@PURE_QUANTA.Q_RES(CHIPS)':
 C_PATH='@t6g_mb_lib.t6g(sch_1):page299_i181@pure_quanta.q_res(chips)',
 P_PATH='@t6g_mb_lib.t6g(sch_1):page126_i181@pure_quanta.q_res(chips)',
 PATH='I181',
 DRAWING='@T6G_MB_LIB.T6G(SCH_1):PAGE299',
 WATTAGE='1/16W',
 TOLERANCE='1%',
 MATERIAL='EMPTY',
 PHYS_PAGE='126',
 XY='(1750,-525)',
 ROT='0',
 VER='2',
 PACK_TYPE='0402LF',
 LOCATION='R3502',
 CDS_LIB='pure_quanta',
 CDS_PART_NAME='Q_RES_0402LF-100K,1%,1/16W,EMPTY,CS41002FB09',
 PART_NUMBER='CS41002FB09',
 VALUE='100K',
 PRIM_FILE='./archive_libs/logical/q_res/chips/chips.prt';

PART_NAME
 R3503 'Q_RES_0402LF-4.7K,5%,1/16W,CHIP,CS24702JB10':;

SECTION_NUMBER 1
 '@T6G_MB_LIB.T6G(SCH_1):PAGE299_I177@PURE_QUANTA.Q_RES(CHIPS)':
 C_PATH='@t6g_mb_lib.t6g(sch_1):page299_i177@pure_quanta.q_res(chips)',
 P_PATH='@t6g_mb_lib.t6g(sch_1):page126_i177@pure_quanta.q_res(chips)',
 PATH='I177',
 DRAWING='@T6G_MB_LIB.T6G(SCH_1):PAGE299',
 WATTAGE='1/16W',
 TOLERANCE='5%',
 MATERIAL='CHIP',
 PHYS_PAGE='126',
 XY='(2975,200)',
 ROT='0',
 VER='2',
 PACK_TYPE='0402LF',
 LOCATION='R3503',
 CDS_LIB='pure_quanta',
 CDS_PART_NAME='Q_RES_0402LF-4.7K,5%,1/16W,CHIP,CS24702JB10',
 PART_NUMBER='CS24702JB10',
 VALUE='4.7K',
 PRIM_FILE='./archive_libs/logical/q_res/chips/chips.prt';

PART_NAME
 R3504 'Q_RES_0402LF-100K,1%,1/16W,CHIP,CS41002FB09':;

SECTION_NUMBER 1
 '@T6G_MB_LIB.T6G(SCH_1):PAGE299_I174@PURE_QUANTA.Q_RES(CHIPS)':
 C_PATH='@t6g_mb_lib.t6g(sch_1):page299_i174@pure_quanta.q_res(chips)',
 P_PATH='@t6g_mb_lib.t6g(sch_1):page126_i174@pure_quanta.q_res(chips)',
 PATH='I174',
 DRAWING='@T6G_MB_LIB.T6G(SCH_1):PAGE299',
 WATTAGE='1/16W',
 TOLERANCE='1%',
 MATERIAL='CHIP',
 PHYS_PAGE='126',
 XY='(3900,450)',
 ROT='0',
 VER='2',
 PACK_TYPE='0402LF',
 LOCATION='R3504',
 CDS_LIB='pure_quanta',
 CDS_PART_NAME='Q_RES_0402LF-100K,1%,1/16W,CHIP,CS41002FB09',
 PART_NUMBER='CS41002FB09',
 VALUE='100K',
 PRIM_FILE='./archive_libs/logical/q_res/chips/chips.prt';

PART_NAME
 R3505 'Q_RES_0402LF-33.2,1%,1/16W,CHIP,CS03322FB03':;

SECTION_NUMBER 1
 '@T6G_MB_LIB.T6G(SCH_1):PAGE80_I259@PURE_QUANTA.Q_RES(CHIPS)':
 C_PATH='@t6g_mb_lib.t6g(sch_1):page80_i259@pure_quanta.q_res(chips)',
 P_PATH='@t6g_mb_lib.t6g(sch_1):page81_i259@pure_quanta.q_res(chips)',
 PATH='I259',
 DRAWING='@T6G_MB_LIB.T6G(SCH_1):PAGE80',
 WATTAGE='1/16W',
 TOLERANCE='1%',
 MATERIAL='CHIP',
 PHYS_PAGE='81',
 XY='(-2300,1925)',
 ROT='0',
 VER='1',
 PACK_TYPE='0402LF',
 LOCATION='R3505',
 CDS_LIB='pure_quanta',
 CDS_PART_NAME='Q_RES_0402LF-33.2,1%,1/16W,CHIP,CS03322FB03',
 PART_NUMBER='CS03322FB03',
 VALUE='33.2',
 PRIM_FILE='./archive_libs/logical/q_res/chips/chips.prt';

PART_NAME
 R3506 'Q_RES_0402LF-4.7K,5%,1/16W,EMPTY,CS24702JB10':;

SECTION_NUMBER 1
 '@T6G_MB_LIB.T6G(SCH_1):PAGE256_I193@PURE_QUANTA.Q_RES(CHIPS)':
 C_PATH='@t6g_mb_lib.t6g(sch_1):page256_i193@pure_quanta.q_res(chips)',
 P_PATH='@t6g_mb_lib.t6g(sch_1):page130_i193@pure_quanta.q_res(chips)',
 PATH='I193',
 DRAWING='@T6G_MB_LIB.T6G(SCH_1):PAGE256',
 WATTAGE='1/16W',
 TOLERANCE='5%',
 MATERIAL='EMPTY',
 PHYS_PAGE='130',
 XY='(0,-250)',
 ROT='0',
 VER='2',
 PACK_TYPE='0402LF',
 LOCATION='R3506',
 CDS_LIB='pure_quanta',
 CDS_PART_NAME='Q_RES_0402LF-4.7K,5%,1/16W,EMPTY,CS24702JB10',
 PART_NUMBER='CS24702JB10',
 VALUE='4.7K',
 PRIM_FILE='./archive_libs/logical/q_res/chips/chips.prt';

PART_NAME
 R3507 'Q_RES_0402LF-10K,1%,1/16W,CHIP,CS31002FB08':;

SECTION_NUMBER 1
 '@T6G_MB_LIB.T6G(SCH_1):PAGE256_I192@PURE_QUANTA.Q_RES(CHIPS)':
 C_PATH='@t6g_mb_lib.t6g(sch_1):page256_i192@pure_quanta.q_res(chips)',
 P_PATH='@t6g_mb_lib.t6g(sch_1):page130_i192@pure_quanta.q_res(chips)',
 PATH='I192',
 DRAWING='@T6G_MB_LIB.T6G(SCH_1):PAGE256',
 WATTAGE='1/16W',
 TOLERANCE='1%',
 MATERIAL='CHIP',
 PHYS_PAGE='130',
 XY='(25,-725)',
 ROT='0',
 VER='2',
 PACK_TYPE='0402LF',
 LOCATION='R3507',
 CDS_LIB='pure_quanta',
 CDS_PART_NAME='Q_RES_0402LF-10K,1%,1/16W,CHIP,CS31002FB08',
 PART_NUMBER='CS31002FB08',
 VALUE='10K',
 PRIM_FILE='./archive_libs/logical/q_res/chips/chips.prt';

PART_NAME
 R3508 'Q_RES_0402LF-54.9K,1%,1/16W,CHIP,CS35492FB03':;

SECTION_NUMBER 1
 '@T6G_MB_LIB.T6G(SCH_1):PAGE256_I194@PURE_QUANTA.Q_RES(CHIPS)':
 C_PATH='@t6g_mb_lib.t6g(sch_1):page256_i194@pure_quanta.q_res(chips)',
 P_PATH='@t6g_mb_lib.t6g(sch_1):page130_i194@pure_quanta.q_res(chips)',
 PATH='I194',
 DRAWING='@T6G_MB_LIB.T6G(SCH_1):PAGE256',
 WATTAGE='1/16W',
 TOLERANCE='1%',
 MATERIAL='CHIP',
 PHYS_PAGE='130',
 XY='(2625,325)',
 ROT='0',
 VER='2',
 PACK_TYPE='0402LF',
 LOCATION='R3508',
 CDS_LIB='pure_quanta',
 CDS_PART_NAME='Q_RES_0402LF-54.9K,1%,1/16W,CHIP,CS35492FB03',
 PART_NUMBER='CS35492FB03',
 VALUE='54.9K',
 PRIM_FILE='./archive_libs/logical/q_res/chips/chips.prt';

PART_NAME
 R3509 'Q_RES_0402LF-10K,1%,1/16W,CHIP,CS31002FB08':;

SECTION_NUMBER 1
 '@T6G_MB_LIB.T6G(SCH_1):PAGE256_I191@PURE_QUANTA.Q_RES(CHIPS)':
 C_PATH='@t6g_mb_lib.t6g(sch_1):page256_i191@pure_quanta.q_res(chips)',
 P_PATH='@t6g_mb_lib.t6g(sch_1):page130_i191@pure_quanta.q_res(chips)',
 PATH='I191',
 DRAWING='@T6G_MB_LIB.T6G(SCH_1):PAGE256',
 WATTAGE='1/16W',
 TOLERANCE='1%',
 MATERIAL='CHIP',
 PHYS_PAGE='130',
 XY='(2650,-800)',
 ROT='0',
 VER='2',
 PACK_TYPE='0402LF',
 LOCATION='R3509',
 CDS_LIB='pure_quanta',
 CDS_PART_NAME='Q_RES_0402LF-10K,1%,1/16W,CHIP,CS31002FB08',
 PART_NUMBER='CS31002FB08',
 VALUE='10K',
 PRIM_FILE='./archive_libs/logical/q_res/chips/chips.prt';

PART_NAME
 R3510 'Q_RES_0402LF-54.9K,1%,1/16W,CHIP,CS35492FB03':;

SECTION_NUMBER 1
 '@T6G_MB_LIB.T6G(SCH_1):PAGE333_I176@PURE_QUANTA.Q_RES(CHIPS)':
 C_PATH='@t6g_mb_lib.t6g(sch_1):page333_i176@pure_quanta.q_res(chips)',
 P_PATH='@t6g_mb_lib.t6g(sch_1):page127_i176@pure_quanta.q_res(chips)',
 PATH='I176',
 DRAWING='@T6G_MB_LIB.T6G(SCH_1):PAGE333',
 WATTAGE='1/16W',
 TOLERANCE='1%',
 MATERIAL='CHIP',
 PHYS_PAGE='127',
 XY='(-4675,3250)',
 ROT='0',
 VER='2',
 PACK_TYPE='0402LF',
 LOCATION='R3510',
 CDS_LIB='pure_quanta',
 CDS_PART_NAME='Q_RES_0402LF-54.9K,1%,1/16W,CHIP,CS35492FB03',
 PART_NUMBER='CS35492FB03',
 VALUE='54.9K',
 PRIM_FILE='./archive_libs/logical/q_res/chips/chips.prt';

PART_NAME
 R3511 'Q_RES_0402LF-54.9K,1%,1/16W,CHIP,CS35492FB03':;

SECTION_NUMBER 1
 '@T6G_MB_LIB.T6G(SCH_1):PAGE333_I172@PURE_QUANTA.Q_RES(CHIPS)':
 C_PATH='@t6g_mb_lib.t6g(sch_1):page333_i172@pure_quanta.q_res(chips)',
 P_PATH='@t6g_mb_lib.t6g(sch_1):page127_i172@pure_quanta.q_res(chips)',
 PATH='I172',
 DRAWING='@T6G_MB_LIB.T6G(SCH_1):PAGE333',
 WATTAGE='1/16W',
 TOLERANCE='1%',
 MATERIAL='CHIP',
 PHYS_PAGE='127',
 XY='(-150,2975)',
 ROT='0',
 VER='2',
 PACK_TYPE='0402LF',
 LOCATION='R3511',
 CDS_LIB='pure_quanta',
 CDS_PART_NAME='Q_RES_0402LF-54.9K,1%,1/16W,CHIP,CS35492FB03',
 PART_NUMBER='CS35492FB03',
 VALUE='54.9K',
 PRIM_FILE='./archive_libs/logical/q_res/chips/chips.prt';

PART_NAME
 R3512 'Q_RES_0402LF-100K,1%,1/16W,EMPTY,CS41002FB09':;

SECTION_NUMBER 1
 '@T6G_MB_LIB.T6G(SCH_1):PAGE333_I174@PURE_QUANTA.Q_RES(CHIPS)':
 C_PATH='@t6g_mb_lib.t6g(sch_1):page333_i174@pure_quanta.q_res(chips)',
 P_PATH='@t6g_mb_lib.t6g(sch_1):page127_i174@pure_quanta.q_res(chips)',
 PATH='I174',
 DRAWING='@T6G_MB_LIB.T6G(SCH_1):PAGE333',
 WATTAGE='1/16W',
 TOLERANCE='1%',
 MATERIAL='EMPTY',
 PHYS_PAGE='127',
 XY='(-150,6325)',
 ROT='0',
 VER='2',
 PACK_TYPE='0402LF',
 LOCATION='R3512',
 CDS_LIB='pure_quanta',
 CDS_PART_NAME='Q_RES_0402LF-100K,1%,1/16W,EMPTY,CS41002FB09',
 PART_NUMBER='CS41002FB09',
 VALUE='100K',
 PRIM_FILE='./archive_libs/logical/q_res/chips/chips.prt';

PART_NAME
 R3513 'Q_RES_0402LF-54.9K,1%,1/16W,CHIP,CS35492FB03':;

SECTION_NUMBER 1
 '@T6G_MB_LIB.T6G(SCH_1):PAGE333_I173@PURE_QUANTA.Q_RES(CHIPS)':
 C_PATH='@t6g_mb_lib.t6g(sch_1):page333_i173@pure_quanta.q_res(chips)',
 P_PATH='@t6g_mb_lib.t6g(sch_1):page127_i173@pure_quanta.q_res(chips)',
 PATH='I173',
 DRAWING='@T6G_MB_LIB.T6G(SCH_1):PAGE333',
 WATTAGE='1/16W',
 TOLERANCE='1%',
 MATERIAL='CHIP',
 PHYS_PAGE='127',
 XY='(-125,5900)',
 ROT='0',
 VER='2',
 PACK_TYPE='0402LF',
 LOCATION='R3513',
 CDS_LIB='pure_quanta',
 CDS_PART_NAME='Q_RES_0402LF-54.9K,1%,1/16W,CHIP,CS35492FB03',
 PART_NUMBER='CS35492FB03',
 VALUE='54.9K',
 PRIM_FILE='./archive_libs/logical/q_res/chips/chips.prt';

PART_NAME
 R3514 'Q_RES_0402LF-54.9K,1%,1/16W,CHIP,CS35492FB03':;

SECTION_NUMBER 1
 '@T6G_MB_LIB.T6G(SCH_1):PAGE333_I175@PURE_QUANTA.Q_RES(CHIPS)':
 C_PATH='@t6g_mb_lib.t6g(sch_1):page333_i175@pure_quanta.q_res(chips)',
 P_PATH='@t6g_mb_lib.t6g(sch_1):page127_i175@pure_quanta.q_res(chips)',
 PATH='I175',
 DRAWING='@T6G_MB_LIB.T6G(SCH_1):PAGE333',
 WATTAGE='1/16W',
 TOLERANCE='1%',
 MATERIAL='CHIP',
 PHYS_PAGE='127',
 XY='(-125,4950)',
 ROT='0',
 VER='2',
 PACK_TYPE='0402LF',
 LOCATION='R3514',
 CDS_LIB='pure_quanta',
 CDS_PART_NAME='Q_RES_0402LF-54.9K,1%,1/16W,CHIP,CS35492FB03',
 PART_NUMBER='CS35492FB03',
 VALUE='54.9K',
 PRIM_FILE='./archive_libs/logical/q_res/chips/chips.prt';

PART_NAME
 R3515 'Q_RES_0402LF-49.9,1%,1/16W,CHIP,CS04992FB07':;

SECTION_NUMBER 1
 '@T6G_MB_LIB.T6G(SCH_1):PAGE334_I193@PURE_QUANTA.Q_RES(CHIPS)':
 C_PATH='@t6g_mb_lib.t6g(sch_1):page334_i193@pure_quanta.q_res(chips)',
 P_PATH='@t6g_mb_lib.t6g(sch_1):page128_i193@pure_quanta.q_res(chips)',
 PATH='I193',
 DRAWING='@T6G_MB_LIB.T6G(SCH_1):PAGE334',
 WATTAGE='1/16W',
 TOLERANCE='1%',
 MATERIAL='CHIP',
 PHYS_PAGE='128',
 XY='(-3925,-525)',
 ROT='0',
 VER='1',
 PACK_TYPE='0402LF',
 LOCATION='R3515',
 CDS_LIB='pure_quanta',
 CDS_PART_NAME='Q_RES_0402LF-49.9,1%,1/16W,CHIP,CS04992FB07',
 PART_NUMBER='CS04992FB07',
 VALUE='49.9',
 PRIM_FILE='./archive_libs/logical/q_res/chips/chips.prt';

PART_NAME
 R3516 'Q_RES_0402LF-0,5%,1/16W,CHIP,CS00002JB13':;

SECTION_NUMBER 1
 '@T6G_MB_LIB.T6G(SCH_1):PAGE246_I56@PURE_QUANTA.Q_RES(CHIPS)':
 C_PATH='@t6g_mb_lib.t6g(sch_1):page246_i56@pure_quanta.q_res(chips)',
 P_PATH='@t6g_mb_lib.t6g(sch_1):page245_i56@pure_quanta.q_res(chips)',
 PATH='I56',
 DRAWING='@T6G_MB_LIB.T6G(SCH_1):PAGE246',
 WATTAGE='1/16W',
 TOLERANCE='5%',
 MATERIAL='CHIP',
 PHYS_PAGE='245',
 XY='(-3525,2650)',
 ROT='0',
 VER='1',
 PACK_TYPE='0402LF',
 LOCATION='R3516',
 CDS_LIB='pure_quanta',
 CDS_PART_NAME='Q_RES_0402LF-0,5%,1/16W,CHIP,CS00002JB13',
 PART_NUMBER='CS00002JB13',
 VALUE='0',
 PRIM_FILE='./archive_libs/logical/q_res/chips/chips.prt';

PART_NAME
 R3517 'Q_RES_0402LF-0,5%,1/16W,CHIP,CS00002JB13':;

SECTION_NUMBER 1
 '@T6G_MB_LIB.T6G(SCH_1):PAGE246_I55@PURE_QUANTA.Q_RES(CHIPS)':
 C_PATH='@t6g_mb_lib.t6g(sch_1):page246_i55@pure_quanta.q_res(chips)',
 P_PATH='@t6g_mb_lib.t6g(sch_1):page245_i55@pure_quanta.q_res(chips)',
 PATH='I55',
 DRAWING='@T6G_MB_LIB.T6G(SCH_1):PAGE246',
 WATTAGE='1/16W',
 TOLERANCE='5%',
 MATERIAL='CHIP',
 PHYS_PAGE='245',
 XY='(-3525,2450)',
 ROT='0',
 VER='1',
 PACK_TYPE='0402LF',
 LOCATION='R3517',
 CDS_LIB='pure_quanta',
 CDS_PART_NAME='Q_RES_0402LF-0,5%,1/16W,CHIP,CS00002JB13',
 PART_NUMBER='CS00002JB13',
 VALUE='0',
 PRIM_FILE='./archive_libs/logical/q_res/chips/chips.prt';

PART_NAME
 R3518 'Q_RES_0402LF-0,5%,1/16W,CHIP,CS00002JB13':;

SECTION_NUMBER 1
 '@T6G_MB_LIB.T6G(SCH_1):PAGE246_I47@PURE_QUANTA.Q_RES(CHIPS)':
 C_PATH='@t6g_mb_lib.t6g(sch_1):page246_i47@pure_quanta.q_res(chips)',
 P_PATH='@t6g_mb_lib.t6g(sch_1):page245_i47@pure_quanta.q_res(chips)',
 PATH='I47',
 DRAWING='@T6G_MB_LIB.T6G(SCH_1):PAGE246',
 WATTAGE='1/16W',
 TOLERANCE='5%',
 MATERIAL='CHIP',
 PHYS_PAGE='245',
 XY='(-3525,2250)',
 ROT='0',
 VER='1',
 PACK_TYPE='0402LF',
 LOCATION='R3518',
 CDS_LIB='pure_quanta',
 CDS_PART_NAME='Q_RES_0402LF-0,5%,1/16W,CHIP,CS00002JB13',
 PART_NUMBER='CS00002JB13',
 VALUE='0',
 PRIM_FILE='./archive_libs/logical/q_res/chips/chips.prt';

PART_NAME
 R3519 'Q_RES_0402LF-4.7K,5%,1/16W,CHIP,CS24702JB10':;

SECTION_NUMBER 1
 '@T6G_MB_LIB.T6G(SCH_1):PAGE248_I34@PURE_QUANTA.Q_RES(CHIPS)':
 C_PATH='@t6g_mb_lib.t6g(sch_1):page248_i34@pure_quanta.q_res(chips)',
 P_PATH='@t6g_mb_lib.t6g(sch_1):page247_i34@pure_quanta.q_res(chips)',
 PATH='I34',
 DRAWING='@T6G_MB_LIB.T6G(SCH_1):PAGE248',
 WATTAGE='1/16W',
 TOLERANCE='5%',
 MATERIAL='CHIP',
 PHYS_PAGE='247',
 XY='(-3200,3625)',
 ROT='0',
 VER='2',
 PACK_TYPE='0402LF',
 LOCATION='R3519',
 CDS_LIB='pure_quanta',
 CDS_PART_NAME='Q_RES_0402LF-4.7K,5%,1/16W,CHIP,CS24702JB10',
 PART_NUMBER='CS24702JB10',
 VALUE='4.7K',
 PRIM_FILE='./archive_libs/logical/q_res/chips/chips.prt';

PART_NAME
 R3520 'Q_RES_0402LF-4.7K,5%,1/16W,CHIP,CS24702JB10':;

SECTION_NUMBER 1
 '@T6G_MB_LIB.T6G(SCH_1):PAGE248_I23@PURE_QUANTA.Q_RES(CHIPS)':
 C_PATH='@t6g_mb_lib.t6g(sch_1):page248_i23@pure_quanta.q_res(chips)',
 P_PATH='@t6g_mb_lib.t6g(sch_1):page247_i23@pure_quanta.q_res(chips)',
 PATH='I23',
 DRAWING='@T6G_MB_LIB.T6G(SCH_1):PAGE248',
 WATTAGE='1/16W',
 TOLERANCE='5%',
 MATERIAL='CHIP',
 PHYS_PAGE='247',
 XY='(-2950,3625)',
 ROT='0',
 VER='2',
 PACK_TYPE='0402LF',
 LOCATION='R3520',
 CDS_LIB='pure_quanta',
 CDS_PART_NAME='Q_RES_0402LF-4.7K,5%,1/16W,CHIP,CS24702JB10',
 PART_NUMBER='CS24702JB10',
 VALUE='4.7K',
 PRIM_FILE='./archive_libs/logical/q_res/chips/chips.prt';

PART_NAME
 R3521 'Q_RES_0402LF-54.9K,1%,1/16W,CHIP,CS35492FB03':;

SECTION_NUMBER 1
 '@T6G_MB_LIB.T6G(SCH_1):PAGE249_I36@PURE_QUANTA.Q_RES(CHIPS)':
 C_PATH='@t6g_mb_lib.t6g(sch_1):page249_i36@pure_quanta.q_res(chips)',
 P_PATH='@t6g_mb_lib.t6g(sch_1):page248_i36@pure_quanta.q_res(chips)',
 PATH='I36',
 DRAWING='@T6G_MB_LIB.T6G(SCH_1):PAGE249',
 WATTAGE='1/16W',
 TOLERANCE='1%',
 MATERIAL='CHIP',
 PHYS_PAGE='248',
 XY='(-5025,2975)',
 ROT='0',
 VER='2',
 PACK_TYPE='0402LF',
 LOCATION='R3521',
 CDS_LIB='pure_quanta',
 CDS_PART_NAME='Q_RES_0402LF-54.9K,1%,1/16W,CHIP,CS35492FB03',
 PART_NUMBER='CS35492FB03',
 VALUE='54.9K',
 PRIM_FILE='./archive_libs/logical/q_res/chips/chips.prt';

PART_NAME
 R3522 'Q_RES_0402LF-54.9K,1%,1/16W,CHIP,CS35492FB03':;

SECTION_NUMBER 1
 '@T6G_MB_LIB.T6G(SCH_1):PAGE249_I37@PURE_QUANTA.Q_RES(CHIPS)':
 C_PATH='@t6g_mb_lib.t6g(sch_1):page249_i37@pure_quanta.q_res(chips)',
 P_PATH='@t6g_mb_lib.t6g(sch_1):page248_i37@pure_quanta.q_res(chips)',
 PATH='I37',
 DRAWING='@T6G_MB_LIB.T6G(SCH_1):PAGE249',
 WATTAGE='1/16W',
 TOLERANCE='1%',
 MATERIAL='CHIP',
 PHYS_PAGE='248',
 XY='(-4775,2975)',
 ROT='0',
 VER='2',
 PACK_TYPE='0402LF',
 LOCATION='R3522',
 CDS_LIB='pure_quanta',
 CDS_PART_NAME='Q_RES_0402LF-54.9K,1%,1/16W,CHIP,CS35492FB03',
 PART_NUMBER='CS35492FB03',
 VALUE='54.9K',
 PRIM_FILE='./archive_libs/logical/q_res/chips/chips.prt';

PART_NAME
 R3523 'Q_RES_0402LF-54.9K,1%,1/16W,CHIP,CS35492FB03':;

SECTION_NUMBER 1
 '@T6G_MB_LIB.T6G(SCH_1):PAGE249_I80@PURE_QUANTA.Q_RES(CHIPS)':
 C_PATH='@t6g_mb_lib.t6g(sch_1):page249_i80@pure_quanta.q_res(chips)',
 P_PATH='@t6g_mb_lib.t6g(sch_1):page248_i80@pure_quanta.q_res(chips)',
 PATH='I80',
 DRAWING='@T6G_MB_LIB.T6G(SCH_1):PAGE249',
 WATTAGE='1/16W',
 TOLERANCE='1%',
 MATERIAL='CHIP',
 PHYS_PAGE='248',
 XY='(-2425,4325)',
 ROT='0',
 VER='2',
 PACK_TYPE='0402LF',
 LOCATION='R3523',
 CDS_LIB='pure_quanta',
 CDS_PART_NAME='Q_RES_0402LF-54.9K,1%,1/16W,CHIP,CS35492FB03',
 PART_NUMBER='CS35492FB03',
 VALUE='54.9K',
 PRIM_FILE='./archive_libs/logical/q_res/chips/chips.prt';

PART_NAME
 R3524 'Q_RES_0402LF-54.9K,1%,1/16W,CHIP,CS35492FB03':;

SECTION_NUMBER 1
 '@T6G_MB_LIB.T6G(SCH_1):PAGE249_I81@PURE_QUANTA.Q_RES(CHIPS)':
 C_PATH='@t6g_mb_lib.t6g(sch_1):page249_i81@pure_quanta.q_res(chips)',
 P_PATH='@t6g_mb_lib.t6g(sch_1):page248_i81@pure_quanta.q_res(chips)',
 PATH='I81',
 DRAWING='@T6G_MB_LIB.T6G(SCH_1):PAGE249',
 WATTAGE='1/16W',
 TOLERANCE='1%',
 MATERIAL='CHIP',
 PHYS_PAGE='248',
 XY='(-2175,4325)',
 ROT='0',
 VER='2',
 PACK_TYPE='0402LF',
 LOCATION='R3524',
 CDS_LIB='pure_quanta',
 CDS_PART_NAME='Q_RES_0402LF-54.9K,1%,1/16W,CHIP,CS35492FB03',
 PART_NUMBER='CS35492FB03',
 VALUE='54.9K',
 PRIM_FILE='./archive_libs/logical/q_res/chips/chips.prt';

PART_NAME
 R3525 'Q_RES_0402LF-54.9K,1%,1/16W,CHIP,CS35492FB03':;

SECTION_NUMBER 1
 '@T6G_MB_LIB.T6G(SCH_1):PAGE299_I184@PURE_QUANTA.Q_RES(CHIPS)':
 C_PATH='@t6g_mb_lib.t6g(sch_1):page299_i184@pure_quanta.q_res(chips)',
 P_PATH='@t6g_mb_lib.t6g(sch_1):page126_i184@pure_quanta.q_res(chips)',
 PATH='I184',
 DRAWING='@T6G_MB_LIB.T6G(SCH_1):PAGE299',
 WATTAGE='1/16W',
 TOLERANCE='1%',
 MATERIAL='CHIP',
 PHYS_PAGE='126',
 XY='(1725,-100)',
 ROT='0',
 VER='2',
 PACK_TYPE='0402LF',
 LOCATION='R3525',
 CDS_LIB='pure_quanta',
 CDS_PART_NAME='Q_RES_0402LF-54.9K,1%,1/16W,CHIP,CS35492FB03',
 PART_NUMBER='CS35492FB03',
 VALUE='54.9K',
 PRIM_FILE='./archive_libs/logical/q_res/chips/chips.prt';

PART_NAME
 R3526 'Q_RES_0402LF-0,5%,1/16W,CHIP,CS00002JB13':;

SECTION_NUMBER 1
 '@T6G_MB_LIB.T6G(SCH_1):PAGE252_I23@PURE_QUANTA.Q_RES(CHIPS)':
 C_PATH='@t6g_mb_lib.t6g(sch_1):page252_i23@pure_quanta.q_res(chips)',
 P_PATH='@t6g_mb_lib.t6g(sch_1):page250_i23@pure_quanta.q_res(chips)',
 PATH='I23',
 DRAWING='@T6G_MB_LIB.T6G(SCH_1):PAGE252',
 WATTAGE='1/16W',
 TOLERANCE='5%',
 MATERIAL='CHIP',
 PHYS_PAGE='250',
 XY='(-5400,4225)',
 ROT='2',
 VER='1',
 PACK_TYPE='0402LF',
 LOCATION='R3526',
 CDS_LIB='pure_quanta',
 CDS_PART_NAME='Q_RES_0402LF-0,5%,1/16W,CHIP,CS00002JB13',
 PART_NUMBER='CS00002JB13',
 VALUE='0',
 PRIM_FILE='./archive_libs/logical/q_res/chips/chips.prt';

PART_NAME
 R3527 'Q_RES_0402LF-0,5%,1/16W,CHIP,CS00002JB13':;

SECTION_NUMBER 1
 '@T6G_MB_LIB.T6G(SCH_1):PAGE252_I24@PURE_QUANTA.Q_RES(CHIPS)':
 C_PATH='@t6g_mb_lib.t6g(sch_1):page252_i24@pure_quanta.q_res(chips)',
 P_PATH='@t6g_mb_lib.t6g(sch_1):page250_i24@pure_quanta.q_res(chips)',
 PATH='I24',
 DRAWING='@T6G_MB_LIB.T6G(SCH_1):PAGE252',
 WATTAGE='1/16W',
 TOLERANCE='5%',
 MATERIAL='CHIP',
 PHYS_PAGE='250',
 XY='(-5400,4275)',
 ROT='2',
 VER='1',
 PACK_TYPE='0402LF',
 LOCATION='R3527',
 CDS_LIB='pure_quanta',
 CDS_PART_NAME='Q_RES_0402LF-0,5%,1/16W,CHIP,CS00002JB13',
 PART_NUMBER='CS00002JB13',
 VALUE='0',
 PRIM_FILE='./archive_libs/logical/q_res/chips/chips.prt';

PART_NAME
 R3529 'Q_RES_0402LF-10K,1%,1/16W,CHIP,CS31002FB08':;

SECTION_NUMBER 1
 '@T6G_MB_LIB.T6G(SCH_1):PAGE346_I99@PURE_QUANTA.Q_RES(CHIPS)':
 C_PATH='@t6g_mb_lib.t6g(sch_1):page346_i99@pure_quanta.q_res(chips)',
 P_PATH='@t6g_mb_lib.t6g(sch_1):page148_i99@pure_quanta.q_res(chips)',
 PATH='I99',
 DRAWING='@T6G_MB_LIB.T6G(SCH_1):PAGE346',
 WATTAGE='1/16W',
 TOLERANCE='1%',
 MATERIAL='CHIP',
 PHYS_PAGE='148',
 XY='(-25,1600)',
 ROT='0',
 VER='2',
 PACK_TYPE='0402LF',
 LOCATION='R3529',
 CDS_LIB='pure_quanta',
 CDS_PART_NAME='Q_RES_0402LF-10K,1%,1/16W,CHIP,CS31002FB08',
 PART_NUMBER='CS31002FB08',
 VALUE='10K',
 PRIM_FILE='./archive_libs/logical/q_res/chips/chips.prt';

PART_NAME
 R3530 'Q_RES_0402LF-4.7K,5%,1/16W,CHIP,CS24702JB10':;

SECTION_NUMBER 1
 '@T6G_MB_LIB.T6G(SCH_1):PAGE346_I80@PURE_QUANTA.Q_RES(CHIPS)':
 C_PATH='@t6g_mb_lib.t6g(sch_1):page346_i80@pure_quanta.q_res(chips)',
 P_PATH='@t6g_mb_lib.t6g(sch_1):page148_i80@pure_quanta.q_res(chips)',
 PATH='I80',
 DRAWING='@T6G_MB_LIB.T6G(SCH_1):PAGE346',
 WATTAGE='1/16W',
 TOLERANCE='5%',
 MATERIAL='CHIP',
 PHYS_PAGE='148',
 XY='(2125,1575)',
 ROT='0',
 VER='2',
 PACK_TYPE='0402LF',
 LOCATION='R3530',
 CDS_LIB='pure_quanta',
 CDS_PART_NAME='Q_RES_0402LF-4.7K,5%,1/16W,CHIP,CS24702JB10',
 PART_NUMBER='CS24702JB10',
 VALUE='4.7K',
 PRIM_FILE='./archive_libs/logical/q_res/chips/chips.prt';

PART_NAME
 R3531 'Q_RES_0402LF-200K,1%,1/16W,EMPTY,CS42002FB05':;

SECTION_NUMBER 1
 '@T6G_MB_LIB.T6G(SCH_1):PAGE346_I96@PURE_QUANTA.Q_RES(CHIPS)':
 C_PATH='@t6g_mb_lib.t6g(sch_1):page346_i96@pure_quanta.q_res(chips)',
 P_PATH='@t6g_mb_lib.t6g(sch_1):page148_i96@pure_quanta.q_res(chips)',
 PATH='I96',
 DRAWING='@T6G_MB_LIB.T6G(SCH_1):PAGE346',
 WATTAGE='1/16W',
 TOLERANCE='1%',
 MATERIAL='EMPTY',
 PHYS_PAGE='148',
 XY='(-1500,975)',
 ROT='0',
 VER='1',
 PACK_TYPE='0402LF',
 LOCATION='R3531',
 CDS_LIB='pure_quanta',
 CDS_PART_NAME='Q_RES_0402LF-200K,1%,1/16W,EMPTY,CS42002FB05',
 PART_NUMBER='CS42002FB05',
 VALUE='200K',
 PRIM_FILE='./archive_libs/logical/q_res/chips/chips.prt';

PART_NAME
 R3532 'Q_RES_0402LF-4.7K,5%,1/16W,CHIP,CS24702JB10':;

SECTION_NUMBER 1
 '@T6G_MB_LIB.T6G(SCH_1):PAGE346_I78@PURE_QUANTA.Q_RES(CHIPS)':
 C_PATH='@t6g_mb_lib.t6g(sch_1):page346_i78@pure_quanta.q_res(chips)',
 P_PATH='@t6g_mb_lib.t6g(sch_1):page148_i78@pure_quanta.q_res(chips)',
 PATH='I78',
 DRAWING='@T6G_MB_LIB.T6G(SCH_1):PAGE346',
 WATTAGE='1/16W',
 TOLERANCE='5%',
 MATERIAL='CHIP',
 PHYS_PAGE='148',
 XY='(2375,1575)',
 ROT='0',
 VER='2',
 PACK_TYPE='0402LF',
 LOCATION='R3532',
 CDS_LIB='pure_quanta',
 CDS_PART_NAME='Q_RES_0402LF-4.7K,5%,1/16W,CHIP,CS24702JB10',
 PART_NUMBER='CS24702JB10',
 VALUE='4.7K',
 PRIM_FILE='./archive_libs/logical/q_res/chips/chips.prt';

PART_NAME
 R3533 'Q_RES_0402LF-33.2,1%,1/16W,CHIP,CS03322FB03':;

SECTION_NUMBER 1
 '@T6G_MB_LIB.T6G(SCH_1):PAGE346_I76@PURE_QUANTA.Q_RES(CHIPS)':
 C_PATH='@t6g_mb_lib.t6g(sch_1):page346_i76@pure_quanta.q_res(chips)',
 P_PATH='@t6g_mb_lib.t6g(sch_1):page148_i76@pure_quanta.q_res(chips)',
 PATH='I76',
 DRAWING='@T6G_MB_LIB.T6G(SCH_1):PAGE346',
 WATTAGE='1/16W',
 TOLERANCE='1%',
 MATERIAL='CHIP',
 PHYS_PAGE='148',
 XY='(2700,1225)',
 ROT='0',
 VER='1',
 PACK_TYPE='0402LF',
 LOCATION='R3533',
 CDS_LIB='pure_quanta',
 CDS_PART_NAME='Q_RES_0402LF-33.2,1%,1/16W,CHIP,CS03322FB03',
 PART_NUMBER='CS03322FB03',
 VALUE='33.2',
 PRIM_FILE='./archive_libs/logical/q_res/chips/chips.prt';

PART_NAME
 R3534 'Q_RES_0402LF-33.2,1%,1/16W,CHIP,CS03322FB03':;

SECTION_NUMBER 1
 '@T6G_MB_LIB.T6G(SCH_1):PAGE346_I77@PURE_QUANTA.Q_RES(CHIPS)':
 C_PATH='@t6g_mb_lib.t6g(sch_1):page346_i77@pure_quanta.q_res(chips)',
 P_PATH='@t6g_mb_lib.t6g(sch_1):page148_i77@pure_quanta.q_res(chips)',
 PATH='I77',
 DRAWING='@T6G_MB_LIB.T6G(SCH_1):PAGE346',
 WATTAGE='1/16W',
 TOLERANCE='1%',
 MATERIAL='CHIP',
 PHYS_PAGE='148',
 XY='(2700,1125)',
 ROT='0',
 VER='1',
 PACK_TYPE='0402LF',
 LOCATION='R3534',
 CDS_LIB='pure_quanta',
 CDS_PART_NAME='Q_RES_0402LF-33.2,1%,1/16W,CHIP,CS03322FB03',
 PART_NUMBER='CS03322FB03',
 VALUE='33.2',
 PRIM_FILE='./archive_libs/logical/q_res/chips/chips.prt';

PART_NAME
 R3535 'Q_RES_0402LF-2.2K,5%,1/16W,CHIP,CS22202JB07':;

SECTION_NUMBER 1
 '@T6G_MB_LIB.T6G(SCH_1):PAGE252_I44@PURE_QUANTA.Q_RES(CHIPS)':
 C_PATH='@t6g_mb_lib.t6g(sch_1):page252_i44@pure_quanta.q_res(chips)',
 P_PATH='@t6g_mb_lib.t6g(sch_1):page250_i44@pure_quanta.q_res(chips)',
 PATH='I44',
 DRAWING='@T6G_MB_LIB.T6G(SCH_1):PAGE252',
 WATTAGE='1/16W',
 TOLERANCE='5%',
 MATERIAL='CHIP',
 PHYS_PAGE='250',
 XY='(-2125,1875)',
 ROT='0',
 VER='1',
 PACK_TYPE='0402LF',
 LOCATION='R3535',
 CDS_LIB='pure_quanta',
 CDS_PART_NAME='Q_RES_0402LF-2.2K,5%,1/16W,CHIP,CS22202JB07',
 PART_NUMBER='CS22202JB07',
 VALUE='2.2K',
 PRIM_FILE='./archive_libs/logical/q_res/chips/chips.prt';

PART_NAME
 R3536 'Q_RES_0402LF-2.2K,5%,1/16W,CHIP,CS22202JB07':;

SECTION_NUMBER 1
 '@T6G_MB_LIB.T6G(SCH_1):PAGE252_I43@PURE_QUANTA.Q_RES(CHIPS)':
 C_PATH='@t6g_mb_lib.t6g(sch_1):page252_i43@pure_quanta.q_res(chips)',
 P_PATH='@t6g_mb_lib.t6g(sch_1):page250_i43@pure_quanta.q_res(chips)',
 PATH='I43',
 DRAWING='@T6G_MB_LIB.T6G(SCH_1):PAGE252',
 WATTAGE='1/16W',
 TOLERANCE='5%',
 MATERIAL='CHIP',
 PHYS_PAGE='250',
 XY='(-2125,1825)',
 ROT='0',
 VER='1',
 PACK_TYPE='0402LF',
 LOCATION='R3536',
 CDS_LIB='pure_quanta',
 CDS_PART_NAME='Q_RES_0402LF-2.2K,5%,1/16W,CHIP,CS22202JB07',
 PART_NUMBER='CS22202JB07',
 VALUE='2.2K',
 PRIM_FILE='./archive_libs/logical/q_res/chips/chips.prt';

PART_NAME
 R3553 'Q_RES_0402LF-33.2,1%,1/16W,CHIP,CS03322FB03':;

SECTION_NUMBER 1
 '@T6G_MB_LIB.T6G(SCH_1):PAGE359_I134@PURE_QUANTA.Q_RES(CHIPS)':
 C_PATH='@t6g_mb_lib.t6g(sch_1):page359_i134@pure_quanta.q_res(chips)',
 P_PATH='@t6g_mb_lib.t6g(sch_1):page235_i134@pure_quanta.q_res(chips)',
 PATH='I134',
 DRAWING='@T6G_MB_LIB.T6G(SCH_1):PAGE359',
 WATTAGE='1/16W',
 TOLERANCE='1%',
 MATERIAL='CHIP',
 PHYS_PAGE='235',
 XY='(225,-2975)',
 ROT='0',
 VER='1',
 PACK_TYPE='0402LF',
 LOCATION='R3553',
 CDS_LIB='pure_quanta',
 CDS_PART_NAME='Q_RES_0402LF-33.2,1%,1/16W,CHIP,CS03322FB03',
 PART_NUMBER='CS03322FB03',
 VALUE='33.2',
 PRIM_FILE='./archive_libs/logical/q_res/chips/chips.prt';

PART_NAME
 R3554 'Q_RES_0402LF-33.2,1%,1/16W,CHIP,CS03322FB03':;

SECTION_NUMBER 1
 '@T6G_MB_LIB.T6G(SCH_1):PAGE359_I136@PURE_QUANTA.Q_RES(CHIPS)':
 C_PATH='@t6g_mb_lib.t6g(sch_1):page359_i136@pure_quanta.q_res(chips)',
 P_PATH='@t6g_mb_lib.t6g(sch_1):page235_i136@pure_quanta.q_res(chips)',
 PATH='I136',
 DRAWING='@T6G_MB_LIB.T6G(SCH_1):PAGE359',
 WATTAGE='1/16W',
 TOLERANCE='1%',
 MATERIAL='CHIP',
 PHYS_PAGE='235',
 XY='(225,-2825)',
 ROT='0',
 VER='1',
 PACK_TYPE='0402LF',
 LOCATION='R3554',
 CDS_LIB='pure_quanta',
 CDS_PART_NAME='Q_RES_0402LF-33.2,1%,1/16W,CHIP,CS03322FB03',
 PART_NUMBER='CS03322FB03',
 VALUE='33.2',
 PRIM_FILE='./archive_libs/logical/q_res/chips/chips.prt';

PART_NAME
 R3559 'Q_RES_0402LF-0,5%,1/16W,CHIP,CS00002JB13':;

SECTION_NUMBER 1
 '@T6G_MB_LIB.T6G(SCH_1):PAGE360_I96@PURE_QUANTA.Q_RES(CHIPS)':
 C_PATH='@t6g_mb_lib.t6g(sch_1):page360_i96@pure_quanta.q_res(chips)',
 P_PATH='@t6g_mb_lib.t6g(sch_1):page237_i96@pure_quanta.q_res(chips)',
 PATH='I96',
 DRAWING='@T6G_MB_LIB.T6G(SCH_1):PAGE360',
 WATTAGE='1/16W',
 TOLERANCE='5%',
 MATERIAL='CHIP',
 PHYS_PAGE='237',
 XY='(3375,375)',
 ROT='0',
 VER='1',
 PACK_TYPE='0402LF',
 LOCATION='R3559',
 CDS_LIB='pure_quanta',
 CDS_PART_NAME='Q_RES_0402LF-0,5%,1/16W,CHIP,CS00002JB13',
 PART_NUMBER='CS00002JB13',
 VALUE='0',
 PRIM_FILE='./archive_libs/logical/q_res/chips/chips.prt';

PART_NAME
 R3560 'Q_RES_0402LF-0,5%,1/16W,CHIP,CS00002JB13':;

SECTION_NUMBER 1
 '@T6G_MB_LIB.T6G(SCH_1):PAGE360_I41@PURE_QUANTA.Q_RES(CHIPS)':
 C_PATH='@t6g_mb_lib.t6g(sch_1):page360_i41@pure_quanta.q_res(chips)',
 P_PATH='@t6g_mb_lib.t6g(sch_1):page237_i41@pure_quanta.q_res(chips)',
 PATH='I41',
 DRAWING='@T6G_MB_LIB.T6G(SCH_1):PAGE360',
 WATTAGE='1/16W',
 TOLERANCE='5%',
 MATERIAL='CHIP',
 PHYS_PAGE='237',
 XY='(2800,-1725)',
 ROT='0',
 VER='1',
 PACK_TYPE='0402LF',
 LOCATION='R3560',
 CDS_LIB='pure_quanta',
 CDS_PART_NAME='Q_RES_0402LF-0,5%,1/16W,CHIP,CS00002JB13',
 PART_NUMBER='CS00002JB13',
 VALUE='0',
 PRIM_FILE='./archive_libs/logical/q_res/chips/chips.prt';

PART_NAME
 R3561 'Q_RES_0402LF-0,5%,1/16W,CHIP,CS00002JB13':;

SECTION_NUMBER 1
 '@T6G_MB_LIB.T6G(SCH_1):PAGE360_I64@PURE_QUANTA.Q_RES(CHIPS)':
 C_PATH='@t6g_mb_lib.t6g(sch_1):page360_i64@pure_quanta.q_res(chips)',
 P_PATH='@t6g_mb_lib.t6g(sch_1):page237_i64@pure_quanta.q_res(chips)',
 PATH='I64',
 DRAWING='@T6G_MB_LIB.T6G(SCH_1):PAGE360',
 WATTAGE='1/16W',
 TOLERANCE='5%',
 MATERIAL='CHIP',
 PHYS_PAGE='237',
 XY='(2925,-3875)',
 ROT='0',
 VER='1',
 PACK_TYPE='0402LF',
 LOCATION='R3561',
 CDS_LIB='pure_quanta',
 CDS_PART_NAME='Q_RES_0402LF-0,5%,1/16W,CHIP,CS00002JB13',
 PART_NUMBER='CS00002JB13',
 VALUE='0',
 PRIM_FILE='./archive_libs/logical/q_res/chips/chips.prt';

PART_NAME
 R3563 'Q_RES_0402LF-0,5%,1/16W,CHIP,CS00002JB13':;

SECTION_NUMBER 1
 '@T6G_MB_LIB.T6G(SCH_1):PAGE295_I35@PURE_QUANTA.Q_RES(CHIPS)':
 C_PATH='@t6g_mb_lib.t6g(sch_1):page295_i35@pure_quanta.q_res(chips)',
 P_PATH='@t6g_mb_lib.t6g(sch_1):page236_i35@pure_quanta.q_res(chips)',
 PATH='I35',
 DRAWING='@T6G_MB_LIB.T6G(SCH_1):PAGE295',
 WATTAGE='1/16W',
 TOLERANCE='5%',
 MATERIAL='CHIP',
 PHYS_PAGE='236',
 XY='(4450,3325)',
 ROT='0',
 VER='1',
 PACK_TYPE='0402LF',
 LOCATION='R3563',
 CDS_LIB='pure_quanta',
 CDS_PART_NAME='Q_RES_0402LF-0,5%,1/16W,CHIP,CS00002JB13',
 PART_NUMBER='CS00002JB13',
 VALUE='0',
 PRIM_FILE='./archive_libs/logical/q_res/chips/chips.prt';

PART_NAME
 R3568 'Q_RES_0402LF-0,5%,1/16W,CHIP,CS00002JB13':;

SECTION_NUMBER 1
 '@T6G_MB_LIB.T6G(SCH_1):PAGE360_I128@PURE_QUANTA.Q_RES(CHIPS)':
 C_PATH='@t6g_mb_lib.t6g(sch_1):page360_i128@pure_quanta.q_res(chips)',
 P_PATH='@t6g_mb_lib.t6g(sch_1):page237_i128@pure_quanta.q_res(chips)',
 PATH='I128',
 DRAWING='@T6G_MB_LIB.T6G(SCH_1):PAGE360',
 WATTAGE='1/16W',
 TOLERANCE='5%',
 MATERIAL='CHIP',
 PHYS_PAGE='237',
 XY='(100,125)',
 ROT='0',
 VER='1',
 PACK_TYPE='0402LF',
 LOCATION='R3568',
 CDS_LIB='pure_quanta',
 CDS_PART_NAME='Q_RES_0402LF-0,5%,1/16W,CHIP,CS00002JB13',
 PART_NUMBER='CS00002JB13',
 VALUE='0',
 PRIM_FILE='./archive_libs/logical/q_res/chips/chips.prt';

PART_NAME
 R3569 'Q_RES_0402LF-0,5%,1/16W,CHIP,CS00002JB13':;

SECTION_NUMBER 1
 '@T6G_MB_LIB.T6G(SCH_1):PAGE360_I127@PURE_QUANTA.Q_RES(CHIPS)':
 C_PATH='@t6g_mb_lib.t6g(sch_1):page360_i127@pure_quanta.q_res(chips)',
 P_PATH='@t6g_mb_lib.t6g(sch_1):page237_i127@pure_quanta.q_res(chips)',
 PATH='I127',
 DRAWING='@T6G_MB_LIB.T6G(SCH_1):PAGE360',
 WATTAGE='1/16W',
 TOLERANCE='5%',
 MATERIAL='CHIP',
 PHYS_PAGE='237',
 XY='(100,75)',
 ROT='0',
 VER='1',
 PACK_TYPE='0402LF',
 LOCATION='R3569',
 CDS_LIB='pure_quanta',
 CDS_PART_NAME='Q_RES_0402LF-0,5%,1/16W,CHIP,CS00002JB13',
 PART_NUMBER='CS00002JB13',
 VALUE='0',
 PRIM_FILE='./archive_libs/logical/q_res/chips/chips.prt';

PART_NAME
 R3570 'Q_RES_0402LF-10,1%,1/16W,CHIP,CS01002FB07':;

SECTION_NUMBER 1
 '@T6G_MB_LIB.T6G(SCH_1):PAGE360_I109@PURE_QUANTA.Q_RES(CHIPS)':
 C_PATH='@t6g_mb_lib.t6g(sch_1):page360_i109@pure_quanta.q_res(chips)',
 P_PATH='@t6g_mb_lib.t6g(sch_1):page237_i109@pure_quanta.q_res(chips)',
 PATH='I109',
 DRAWING='@T6G_MB_LIB.T6G(SCH_1):PAGE360',
 WATTAGE='1/16W',
 TOLERANCE='1%',
 MATERIAL='CHIP',
 PHYS_PAGE='237',
 XY='(150,-475)',
 ROT='0',
 VER='1',
 PACK_TYPE='0402LF',
 LOCATION='R3570',
 CDS_LIB='pure_quanta',
 CDS_PART_NAME='Q_RES_0402LF-10,1%,1/16W,CHIP,CS01002FB07',
 PART_NUMBER='CS01002FB07',
 VALUE='10',
 PRIM_FILE='./archive_libs/logical/q_res/chips/chips.prt';

PART_NAME
 R3571 'Q_RES_0402LF-10,1%,1/16W,CHIP,CS01002FB07':;

SECTION_NUMBER 1
 '@T6G_MB_LIB.T6G(SCH_1):PAGE360_I110@PURE_QUANTA.Q_RES(CHIPS)':
 C_PATH='@t6g_mb_lib.t6g(sch_1):page360_i110@pure_quanta.q_res(chips)',
 P_PATH='@t6g_mb_lib.t6g(sch_1):page237_i110@pure_quanta.q_res(chips)',
 PATH='I110',
 DRAWING='@T6G_MB_LIB.T6G(SCH_1):PAGE360',
 WATTAGE='1/16W',
 TOLERANCE='1%',
 MATERIAL='CHIP',
 PHYS_PAGE='237',
 XY='(150,-750)',
 ROT='0',
 VER='1',
 PACK_TYPE='0402LF',
 LOCATION='R3571',
 CDS_LIB='pure_quanta',
 CDS_PART_NAME='Q_RES_0402LF-10,1%,1/16W,CHIP,CS01002FB07',
 PART_NUMBER='CS01002FB07',
 VALUE='10',
 PRIM_FILE='./archive_libs/logical/q_res/chips/chips.prt';

PART_NAME
 R3572 'Q_RES_0402LF-0,5%,1/16W,CHIP,CS00002JB13':;

SECTION_NUMBER 1
 '@T6G_MB_LIB.T6G(SCH_1):PAGE360_I130@PURE_QUANTA.Q_RES(CHIPS)':
 C_PATH='@t6g_mb_lib.t6g(sch_1):page360_i130@pure_quanta.q_res(chips)',
 P_PATH='@t6g_mb_lib.t6g(sch_1):page237_i130@pure_quanta.q_res(chips)',
 PATH='I130',
 DRAWING='@T6G_MB_LIB.T6G(SCH_1):PAGE360',
 WATTAGE='1/16W',
 TOLERANCE='5%',
 MATERIAL='CHIP',
 PHYS_PAGE='237',
 XY='(-300,-1975)',
 ROT='0',
 VER='1',
 PACK_TYPE='0402LF',
 LOCATION='R3572',
 CDS_LIB='pure_quanta',
 CDS_PART_NAME='Q_RES_0402LF-0,5%,1/16W,CHIP,CS00002JB13',
 PART_NUMBER='CS00002JB13',
 VALUE='0',
 PRIM_FILE='./archive_libs/logical/q_res/chips/chips.prt';

PART_NAME
 R3573 'Q_RES_0402LF-0,5%,1/16W,CHIP,CS00002JB13':;

SECTION_NUMBER 1
 '@T6G_MB_LIB.T6G(SCH_1):PAGE360_I129@PURE_QUANTA.Q_RES(CHIPS)':
 C_PATH='@t6g_mb_lib.t6g(sch_1):page360_i129@pure_quanta.q_res(chips)',
 P_PATH='@t6g_mb_lib.t6g(sch_1):page237_i129@pure_quanta.q_res(chips)',
 PATH='I129',
 DRAWING='@T6G_MB_LIB.T6G(SCH_1):PAGE360',
 WATTAGE='1/16W',
 TOLERANCE='5%',
 MATERIAL='CHIP',
 PHYS_PAGE='237',
 XY='(-300,-2025)',
 ROT='0',
 VER='1',
 PACK_TYPE='0402LF',
 LOCATION='R3573',
 CDS_LIB='pure_quanta',
 CDS_PART_NAME='Q_RES_0402LF-0,5%,1/16W,CHIP,CS00002JB13',
 PART_NUMBER='CS00002JB13',
 VALUE='0',
 PRIM_FILE='./archive_libs/logical/q_res/chips/chips.prt';

PART_NAME
 R3574 'Q_RES_0402LF-10,1%,1/16W,CHIP,CS01002FB07':;

SECTION_NUMBER 1
 '@T6G_MB_LIB.T6G(SCH_1):PAGE360_I35@PURE_QUANTA.Q_RES(CHIPS)':
 C_PATH='@t6g_mb_lib.t6g(sch_1):page360_i35@pure_quanta.q_res(chips)',
 P_PATH='@t6g_mb_lib.t6g(sch_1):page237_i35@pure_quanta.q_res(chips)',
 PATH='I35',
 DRAWING='@T6G_MB_LIB.T6G(SCH_1):PAGE360',
 WATTAGE='1/16W',
 TOLERANCE='1%',
 MATERIAL='CHIP',
 PHYS_PAGE='237',
 XY='(-275,-2575)',
 ROT='0',
 VER='1',
 PACK_TYPE='0402LF',
 LOCATION='R3574',
 CDS_LIB='pure_quanta',
 CDS_PART_NAME='Q_RES_0402LF-10,1%,1/16W,CHIP,CS01002FB07',
 PART_NUMBER='CS01002FB07',
 VALUE='10',
 PRIM_FILE='./archive_libs/logical/q_res/chips/chips.prt';

PART_NAME
 R3575 'Q_RES_0402LF-10,1%,1/16W,CHIP,CS01002FB07':;

SECTION_NUMBER 1
 '@T6G_MB_LIB.T6G(SCH_1):PAGE360_I33@PURE_QUANTA.Q_RES(CHIPS)':
 C_PATH='@t6g_mb_lib.t6g(sch_1):page360_i33@pure_quanta.q_res(chips)',
 P_PATH='@t6g_mb_lib.t6g(sch_1):page237_i33@pure_quanta.q_res(chips)',
 PATH='I33',
 DRAWING='@T6G_MB_LIB.T6G(SCH_1):PAGE360',
 WATTAGE='1/16W',
 TOLERANCE='1%',
 MATERIAL='CHIP',
 PHYS_PAGE='237',
 XY='(-275,-2850)',
 ROT='0',
 VER='1',
 PACK_TYPE='0402LF',
 LOCATION='R3575',
 CDS_LIB='pure_quanta',
 CDS_PART_NAME='Q_RES_0402LF-10,1%,1/16W,CHIP,CS01002FB07',
 PART_NUMBER='CS01002FB07',
 VALUE='10',
 PRIM_FILE='./archive_libs/logical/q_res/chips/chips.prt';

PART_NAME
 R3576 'Q_RES_0402LF-0,5%,1/16W,CHIP,CS00002JB13':;

SECTION_NUMBER 1
 '@T6G_MB_LIB.T6G(SCH_1):PAGE360_I131@PURE_QUANTA.Q_RES(CHIPS)':
 C_PATH='@t6g_mb_lib.t6g(sch_1):page360_i131@pure_quanta.q_res(chips)',
 P_PATH='@t6g_mb_lib.t6g(sch_1):page237_i131@pure_quanta.q_res(chips)',
 PATH='I131',
 DRAWING='@T6G_MB_LIB.T6G(SCH_1):PAGE360',
 WATTAGE='1/16W',
 TOLERANCE='5%',
 MATERIAL='CHIP',
 PHYS_PAGE='237',
 XY='(-175,-4125)',
 ROT='0',
 VER='1',
 PACK_TYPE='0402LF',
 LOCATION='R3576',
 CDS_LIB='pure_quanta',
 CDS_PART_NAME='Q_RES_0402LF-0,5%,1/16W,CHIP,CS00002JB13',
 PART_NUMBER='CS00002JB13',
 VALUE='0',
 PRIM_FILE='./archive_libs/logical/q_res/chips/chips.prt';

PART_NAME
 R3577 'Q_RES_0402LF-0,5%,1/16W,CHIP,CS00002JB13':;

SECTION_NUMBER 1
 '@T6G_MB_LIB.T6G(SCH_1):PAGE360_I132@PURE_QUANTA.Q_RES(CHIPS)':
 C_PATH='@t6g_mb_lib.t6g(sch_1):page360_i132@pure_quanta.q_res(chips)',
 P_PATH='@t6g_mb_lib.t6g(sch_1):page237_i132@pure_quanta.q_res(chips)',
 PATH='I132',
 DRAWING='@T6G_MB_LIB.T6G(SCH_1):PAGE360',
 WATTAGE='1/16W',
 TOLERANCE='5%',
 MATERIAL='CHIP',
 PHYS_PAGE='237',
 XY='(-175,-4175)',
 ROT='0',
 VER='1',
 PACK_TYPE='0402LF',
 LOCATION='R3577',
 CDS_LIB='pure_quanta',
 CDS_PART_NAME='Q_RES_0402LF-0,5%,1/16W,CHIP,CS00002JB13',
 PART_NUMBER='CS00002JB13',
 VALUE='0',
 PRIM_FILE='./archive_libs/logical/q_res/chips/chips.prt';

PART_NAME
 R3578 'Q_RES_0402LF-10,1%,1/16W,CHIP,CS01002FB07':;

SECTION_NUMBER 1
 '@T6G_MB_LIB.T6G(SCH_1):PAGE360_I58@PURE_QUANTA.Q_RES(CHIPS)':
 C_PATH='@t6g_mb_lib.t6g(sch_1):page360_i58@pure_quanta.q_res(chips)',
 P_PATH='@t6g_mb_lib.t6g(sch_1):page237_i58@pure_quanta.q_res(chips)',
 PATH='I58',
 DRAWING='@T6G_MB_LIB.T6G(SCH_1):PAGE360',
 WATTAGE='1/16W',
 TOLERANCE='1%',
 MATERIAL='CHIP',
 PHYS_PAGE='237',
 XY='(-150,-4725)',
 ROT='0',
 VER='1',
 PACK_TYPE='0402LF',
 LOCATION='R3578',
 CDS_LIB='pure_quanta',
 CDS_PART_NAME='Q_RES_0402LF-10,1%,1/16W,CHIP,CS01002FB07',
 PART_NUMBER='CS01002FB07',
 VALUE='10',
 PRIM_FILE='./archive_libs/logical/q_res/chips/chips.prt';

PART_NAME
 R3579 'Q_RES_0402LF-10,1%,1/16W,CHIP,CS01002FB07':;

SECTION_NUMBER 1
 '@T6G_MB_LIB.T6G(SCH_1):PAGE360_I56@PURE_QUANTA.Q_RES(CHIPS)':
 C_PATH='@t6g_mb_lib.t6g(sch_1):page360_i56@pure_quanta.q_res(chips)',
 P_PATH='@t6g_mb_lib.t6g(sch_1):page237_i56@pure_quanta.q_res(chips)',
 PATH='I56',
 DRAWING='@T6G_MB_LIB.T6G(SCH_1):PAGE360',
 WATTAGE='1/16W',
 TOLERANCE='1%',
 MATERIAL='CHIP',
 PHYS_PAGE='237',
 XY='(-150,-5000)',
 ROT='0',
 VER='1',
 PACK_TYPE='0402LF',
 LOCATION='R3579',
 CDS_LIB='pure_quanta',
 CDS_PART_NAME='Q_RES_0402LF-10,1%,1/16W,CHIP,CS01002FB07',
 PART_NUMBER='CS01002FB07',
 VALUE='10',
 PRIM_FILE='./archive_libs/logical/q_res/chips/chips.prt';

PART_NAME
 R3580 'Q_RES_0402LF-0,5%,1/16W,CHIP,CS00002JB13':;

SECTION_NUMBER 1
 '@T6G_MB_LIB.T6G(SCH_1):PAGE252_I69@PURE_QUANTA.Q_RES(CHIPS)':
 C_PATH='@t6g_mb_lib.t6g(sch_1):page252_i69@pure_quanta.q_res(chips)',
 P_PATH='@t6g_mb_lib.t6g(sch_1):page250_i69@pure_quanta.q_res(chips)',
 PATH='I69',
 DRAWING='@T6G_MB_LIB.T6G(SCH_1):PAGE252',
 WATTAGE='1/16W',
 TOLERANCE='5%',
 MATERIAL='CHIP',
 PHYS_PAGE='250',
 XY='(-2600,4325)',
 ROT='0',
 VER='1',
 PACK_TYPE='0402LF',
 LOCATION='R3580',
 CDS_LIB='pure_quanta',
 CDS_PART_NAME='Q_RES_0402LF-0,5%,1/16W,CHIP,CS00002JB13',
 PART_NUMBER='CS00002JB13',
 VALUE='0',
 PRIM_FILE='./archive_libs/logical/q_res/chips/chips.prt';

PART_NAME
 R3581 'Q_RES_0402LF-0,5%,1/16W,CHIP,CS00002JB13':;

SECTION_NUMBER 1
 '@T6G_MB_LIB.T6G(SCH_1):PAGE252_I68@PURE_QUANTA.Q_RES(CHIPS)':
 C_PATH='@t6g_mb_lib.t6g(sch_1):page252_i68@pure_quanta.q_res(chips)',
 P_PATH='@t6g_mb_lib.t6g(sch_1):page250_i68@pure_quanta.q_res(chips)',
 PATH='I68',
 DRAWING='@T6G_MB_LIB.T6G(SCH_1):PAGE252',
 WATTAGE='1/16W',
 TOLERANCE='5%',
 MATERIAL='CHIP',
 PHYS_PAGE='250',
 XY='(-2600,4375)',
 ROT='0',
 VER='1',
 PACK_TYPE='0402LF',
 LOCATION='R3581',
 CDS_LIB='pure_quanta',
 CDS_PART_NAME='Q_RES_0402LF-0,5%,1/16W,CHIP,CS00002JB13',
 PART_NUMBER='CS00002JB13',
 VALUE='0',
 PRIM_FILE='./archive_libs/logical/q_res/chips/chips.prt';

PART_NAME
 R3582 'Q_RES_0402LF-2.2K,5%,1/16W,CHIP,CS22202JB07':;

SECTION_NUMBER 1
 '@T6G_MB_LIB.T6G(SCH_1):PAGE252_I46@PURE_QUANTA.Q_RES(CHIPS)':
 C_PATH='@t6g_mb_lib.t6g(sch_1):page252_i46@pure_quanta.q_res(chips)',
 P_PATH='@t6g_mb_lib.t6g(sch_1):page250_i46@pure_quanta.q_res(chips)',
 PATH='I46',
 DRAWING='@T6G_MB_LIB.T6G(SCH_1):PAGE252',
 WATTAGE='1/16W',
 TOLERANCE='5%',
 MATERIAL='CHIP',
 PHYS_PAGE='250',
 XY='(-2150,2175)',
 ROT='0',
 VER='1',
 PACK_TYPE='0402LF',
 LOCATION='R3582',
 CDS_LIB='pure_quanta',
 CDS_PART_NAME='Q_RES_0402LF-2.2K,5%,1/16W,CHIP,CS22202JB07',
 PART_NUMBER='CS22202JB07',
 VALUE='2.2K',
 PRIM_FILE='./archive_libs/logical/q_res/chips/chips.prt';

PART_NAME
 R3583 'Q_RES_0402LF-2.2K,5%,1/16W,CHIP,CS22202JB07':;

SECTION_NUMBER 1
 '@T6G_MB_LIB.T6G(SCH_1):PAGE252_I45@PURE_QUANTA.Q_RES(CHIPS)':
 C_PATH='@t6g_mb_lib.t6g(sch_1):page252_i45@pure_quanta.q_res(chips)',
 P_PATH='@t6g_mb_lib.t6g(sch_1):page250_i45@pure_quanta.q_res(chips)',
 PATH='I45',
 DRAWING='@T6G_MB_LIB.T6G(SCH_1):PAGE252',
 WATTAGE='1/16W',
 TOLERANCE='5%',
 MATERIAL='CHIP',
 PHYS_PAGE='250',
 XY='(-2150,2125)',
 ROT='0',
 VER='1',
 PACK_TYPE='0402LF',
 LOCATION='R3583',
 CDS_LIB='pure_quanta',
 CDS_PART_NAME='Q_RES_0402LF-2.2K,5%,1/16W,CHIP,CS22202JB07',
 PART_NUMBER='CS22202JB07',
 VALUE='2.2K',
 PRIM_FILE='./archive_libs/logical/q_res/chips/chips.prt';

PART_NAME
 R3586 'Q_RES_0402LF-33.2,1%,1/16W,CHIP,CS03322FB03':;

SECTION_NUMBER 1
 '@T6G_MB_LIB.T6G(SCH_1):PAGE253_I12@PURE_QUANTA.Q_RES(CHIPS)':
 C_PATH='@t6g_mb_lib.t6g(sch_1):page253_i12@pure_quanta.q_res(chips)',
 P_PATH='@t6g_mb_lib.t6g(sch_1):page251_i12@pure_quanta.q_res(chips)',
 PATH='I12',
 DRAWING='@T6G_MB_LIB.T6G(SCH_1):PAGE253',
 WATTAGE='1/16W',
 TOLERANCE='1%',
 MATERIAL='CHIP',
 PHYS_PAGE='251',
 XY='(-4950,4025)',
 ROT='0',
 VER='1',
 PACK_TYPE='0402LF',
 LOCATION='R3586',
 CDS_LIB='pure_quanta',
 CDS_PART_NAME='Q_RES_0402LF-33.2,1%,1/16W,CHIP,CS03322FB03',
 PART_NUMBER='CS03322FB03',
 VALUE='33.2',
 PRIM_FILE='./archive_libs/logical/q_res/chips/chips.prt';

PART_NAME
 R3587 'Q_RES_0402LF-33.2,1%,1/16W,CHIP,CS03322FB03':;

SECTION_NUMBER 1
 '@T6G_MB_LIB.T6G(SCH_1):PAGE253_I11@PURE_QUANTA.Q_RES(CHIPS)':
 C_PATH='@t6g_mb_lib.t6g(sch_1):page253_i11@pure_quanta.q_res(chips)',
 P_PATH='@t6g_mb_lib.t6g(sch_1):page251_i11@pure_quanta.q_res(chips)',
 PATH='I11',
 DRAWING='@T6G_MB_LIB.T6G(SCH_1):PAGE253',
 WATTAGE='1/16W',
 TOLERANCE='1%',
 MATERIAL='CHIP',
 PHYS_PAGE='251',
 XY='(-4950,3975)',
 ROT='0',
 VER='1',
 PACK_TYPE='0402LF',
 LOCATION='R3587',
 CDS_LIB='pure_quanta',
 CDS_PART_NAME='Q_RES_0402LF-33.2,1%,1/16W,CHIP,CS03322FB03',
 PART_NUMBER='CS03322FB03',
 VALUE='33.2',
 PRIM_FILE='./archive_libs/logical/q_res/chips/chips.prt';

PART_NAME
 R3588 'Q_RES_0402LF-33.2,1%,1/16W,CHIP,CS03322FB03':;

SECTION_NUMBER 1
 '@T6G_MB_LIB.T6G(SCH_1):PAGE253_I10@PURE_QUANTA.Q_RES(CHIPS)':
 C_PATH='@t6g_mb_lib.t6g(sch_1):page253_i10@pure_quanta.q_res(chips)',
 P_PATH='@t6g_mb_lib.t6g(sch_1):page251_i10@pure_quanta.q_res(chips)',
 PATH='I10',
 DRAWING='@T6G_MB_LIB.T6G(SCH_1):PAGE253',
 WATTAGE='1/16W',
 TOLERANCE='1%',
 MATERIAL='CHIP',
 PHYS_PAGE='251',
 XY='(-4950,3675)',
 ROT='0',
 VER='1',
 PACK_TYPE='0402LF',
 LOCATION='R3588',
 CDS_LIB='pure_quanta',
 CDS_PART_NAME='Q_RES_0402LF-33.2,1%,1/16W,CHIP,CS03322FB03',
 PART_NUMBER='CS03322FB03',
 VALUE='33.2',
 PRIM_FILE='./archive_libs/logical/q_res/chips/chips.prt';

PART_NAME
 R3589 'Q_RES_0402LF-33.2,1%,1/16W,CHIP,CS03322FB03':;

SECTION_NUMBER 1
 '@T6G_MB_LIB.T6G(SCH_1):PAGE253_I9@PURE_QUANTA.Q_RES(CHIPS)':
 C_PATH='@t6g_mb_lib.t6g(sch_1):page253_i9@pure_quanta.q_res(chips)',
 P_PATH='@t6g_mb_lib.t6g(sch_1):page251_i9@pure_quanta.q_res(chips)',
 PATH='I9',
 DRAWING='@T6G_MB_LIB.T6G(SCH_1):PAGE253',
 WATTAGE='1/16W',
 TOLERANCE='1%',
 MATERIAL='CHIP',
 PHYS_PAGE='251',
 XY='(-4950,3625)',
 ROT='0',
 VER='1',
 PACK_TYPE='0402LF',
 LOCATION='R3589',
 CDS_LIB='pure_quanta',
 CDS_PART_NAME='Q_RES_0402LF-33.2,1%,1/16W,CHIP,CS03322FB03',
 PART_NUMBER='CS03322FB03',
 VALUE='33.2',
 PRIM_FILE='./archive_libs/logical/q_res/chips/chips.prt';

PART_NAME
 R3590 'Q_RES_0402LF-33.2,1%,1/16W,CHIP,CS03322FB03':;

SECTION_NUMBER 1
 '@T6G_MB_LIB.T6G(SCH_1):PAGE253_I8@PURE_QUANTA.Q_RES(CHIPS)':
 C_PATH='@t6g_mb_lib.t6g(sch_1):page253_i8@pure_quanta.q_res(chips)',
 P_PATH='@t6g_mb_lib.t6g(sch_1):page251_i8@pure_quanta.q_res(chips)',
 PATH='I8',
 DRAWING='@T6G_MB_LIB.T6G(SCH_1):PAGE253',
 WATTAGE='1/16W',
 TOLERANCE='1%',
 MATERIAL='CHIP',
 PHYS_PAGE='251',
 XY='(-4950,3400)',
 ROT='0',
 VER='1',
 PACK_TYPE='0402LF',
 LOCATION='R3590',
 CDS_LIB='pure_quanta',
 CDS_PART_NAME='Q_RES_0402LF-33.2,1%,1/16W,CHIP,CS03322FB03',
 PART_NUMBER='CS03322FB03',
 VALUE='33.2',
 PRIM_FILE='./archive_libs/logical/q_res/chips/chips.prt';

PART_NAME
 R3591 'Q_RES_0402LF-33.2,1%,1/16W,CHIP,CS03322FB03':;

SECTION_NUMBER 1
 '@T6G_MB_LIB.T6G(SCH_1):PAGE253_I7@PURE_QUANTA.Q_RES(CHIPS)':
 C_PATH='@t6g_mb_lib.t6g(sch_1):page253_i7@pure_quanta.q_res(chips)',
 P_PATH='@t6g_mb_lib.t6g(sch_1):page251_i7@pure_quanta.q_res(chips)',
 PATH='I7',
 DRAWING='@T6G_MB_LIB.T6G(SCH_1):PAGE253',
 WATTAGE='1/16W',
 TOLERANCE='1%',
 MATERIAL='CHIP',
 PHYS_PAGE='251',
 XY='(-4950,3350)',
 ROT='0',
 VER='1',
 PACK_TYPE='0402LF',
 LOCATION='R3591',
 CDS_LIB='pure_quanta',
 CDS_PART_NAME='Q_RES_0402LF-33.2,1%,1/16W,CHIP,CS03322FB03',
 PART_NUMBER='CS03322FB03',
 VALUE='33.2',
 PRIM_FILE='./archive_libs/logical/q_res/chips/chips.prt';

PART_NAME
 R3592 'Q_RES_0402LF-33.2,1%,1/16W,CHIP,CS03322FB03':;

SECTION_NUMBER 1
 '@T6G_MB_LIB.T6G(SCH_1):PAGE253_I4@PURE_QUANTA.Q_RES(CHIPS)':
 C_PATH='@t6g_mb_lib.t6g(sch_1):page253_i4@pure_quanta.q_res(chips)',
 P_PATH='@t6g_mb_lib.t6g(sch_1):page251_i4@pure_quanta.q_res(chips)',
 PATH='I4',
 DRAWING='@T6G_MB_LIB.T6G(SCH_1):PAGE253',
 WATTAGE='1/16W',
 TOLERANCE='1%',
 MATERIAL='CHIP',
 PHYS_PAGE='251',
 XY='(-4950,2825)',
 ROT='0',
 VER='1',
 PACK_TYPE='0402LF',
 LOCATION='R3592',
 CDS_LIB='pure_quanta',
 CDS_PART_NAME='Q_RES_0402LF-33.2,1%,1/16W,CHIP,CS03322FB03',
 PART_NUMBER='CS03322FB03',
 VALUE='33.2',
 PRIM_FILE='./archive_libs/logical/q_res/chips/chips.prt';

PART_NAME
 R3593 'Q_RES_0402LF-33.2,1%,1/16W,CHIP,CS03322FB03':;

SECTION_NUMBER 1
 '@T6G_MB_LIB.T6G(SCH_1):PAGE253_I3@PURE_QUANTA.Q_RES(CHIPS)':
 C_PATH='@t6g_mb_lib.t6g(sch_1):page253_i3@pure_quanta.q_res(chips)',
 P_PATH='@t6g_mb_lib.t6g(sch_1):page251_i3@pure_quanta.q_res(chips)',
 PATH='I3',
 DRAWING='@T6G_MB_LIB.T6G(SCH_1):PAGE253',
 WATTAGE='1/16W',
 TOLERANCE='1%',
 MATERIAL='CHIP',
 PHYS_PAGE='251',
 XY='(-4950,2775)',
 ROT='0',
 VER='1',
 PACK_TYPE='0402LF',
 LOCATION='R3593',
 CDS_LIB='pure_quanta',
 CDS_PART_NAME='Q_RES_0402LF-33.2,1%,1/16W,CHIP,CS03322FB03',
 PART_NUMBER='CS03322FB03',
 VALUE='33.2',
 PRIM_FILE='./archive_libs/logical/q_res/chips/chips.prt';

PART_NAME
 R3594 'Q_RES_0402LF-33.2,1%,1/16W,CHIP,CS03322FB03':;

SECTION_NUMBER 1
 '@T6G_MB_LIB.T6G(SCH_1):PAGE253_I6@PURE_QUANTA.Q_RES(CHIPS)':
 C_PATH='@t6g_mb_lib.t6g(sch_1):page253_i6@pure_quanta.q_res(chips)',
 P_PATH='@t6g_mb_lib.t6g(sch_1):page251_i6@pure_quanta.q_res(chips)',
 PATH='I6',
 DRAWING='@T6G_MB_LIB.T6G(SCH_1):PAGE253',
 WATTAGE='1/16W',
 TOLERANCE='1%',
 MATERIAL='CHIP',
 PHYS_PAGE='251',
 XY='(-4925,3100)',
 ROT='0',
 VER='1',
 PACK_TYPE='0402LF',
 LOCATION='R3594',
 CDS_LIB='pure_quanta',
 CDS_PART_NAME='Q_RES_0402LF-33.2,1%,1/16W,CHIP,CS03322FB03',
 PART_NUMBER='CS03322FB03',
 VALUE='33.2',
 PRIM_FILE='./archive_libs/logical/q_res/chips/chips.prt';

PART_NAME
 R3595 'Q_RES_0402LF-33.2,1%,1/16W,CHIP,CS03322FB03':;

SECTION_NUMBER 1
 '@T6G_MB_LIB.T6G(SCH_1):PAGE253_I5@PURE_QUANTA.Q_RES(CHIPS)':
 C_PATH='@t6g_mb_lib.t6g(sch_1):page253_i5@pure_quanta.q_res(chips)',
 P_PATH='@t6g_mb_lib.t6g(sch_1):page251_i5@pure_quanta.q_res(chips)',
 PATH='I5',
 DRAWING='@T6G_MB_LIB.T6G(SCH_1):PAGE253',
 WATTAGE='1/16W',
 TOLERANCE='1%',
 MATERIAL='CHIP',
 PHYS_PAGE='251',
 XY='(-4925,3050)',
 ROT='0',
 VER='1',
 PACK_TYPE='0402LF',
 LOCATION='R3595',
 CDS_LIB='pure_quanta',
 CDS_PART_NAME='Q_RES_0402LF-33.2,1%,1/16W,CHIP,CS03322FB03',
 PART_NUMBER='CS03322FB03',
 VALUE='33.2',
 PRIM_FILE='./archive_libs/logical/q_res/chips/chips.prt';

PART_NAME
 R3600 'Q_RES_0402LF-0,5%,1/16W,CHIP,CS00002JB13':;

SECTION_NUMBER 1
 '@T6G_MB_LIB.T6G(SCH_1):PAGE295_I152@PURE_QUANTA.Q_RES(CHIPS)':
 C_PATH='@t6g_mb_lib.t6g(sch_1):page295_i152@pure_quanta.q_res(chips)',
 P_PATH='@t6g_mb_lib.t6g(sch_1):page236_i152@pure_quanta.q_res(chips)',
 PATH='I152',
 DRAWING='@T6G_MB_LIB.T6G(SCH_1):PAGE295',
 WATTAGE='1/16W',
 TOLERANCE='5%',
 MATERIAL='CHIP',
 PHYS_PAGE='236',
 XY='(1275,3075)',
 ROT='0',
 VER='1',
 PACK_TYPE='0402LF',
 LOCATION='R3600',
 CDS_LIB='pure_quanta',
 CDS_PART_NAME='Q_RES_0402LF-0,5%,1/16W,CHIP,CS00002JB13',
 PART_NUMBER='CS00002JB13',
 VALUE='0',
 PRIM_FILE='./archive_libs/logical/q_res/chips/chips.prt';

PART_NAME
 R3601 'Q_RES_0402LF-0,5%,1/16W,CHIP,CS00002JB13':;

SECTION_NUMBER 1
 '@T6G_MB_LIB.T6G(SCH_1):PAGE295_I153@PURE_QUANTA.Q_RES(CHIPS)':
 C_PATH='@t6g_mb_lib.t6g(sch_1):page295_i153@pure_quanta.q_res(chips)',
 P_PATH='@t6g_mb_lib.t6g(sch_1):page236_i153@pure_quanta.q_res(chips)',
 PATH='I153',
 DRAWING='@T6G_MB_LIB.T6G(SCH_1):PAGE295',
 WATTAGE='1/16W',
 TOLERANCE='5%',
 MATERIAL='CHIP',
 PHYS_PAGE='236',
 XY='(1275,3025)',
 ROT='0',
 VER='1',
 PACK_TYPE='0402LF',
 LOCATION='R3601',
 CDS_LIB='pure_quanta',
 CDS_PART_NAME='Q_RES_0402LF-0,5%,1/16W,CHIP,CS00002JB13',
 PART_NUMBER='CS00002JB13',
 VALUE='0',
 PRIM_FILE='./archive_libs/logical/q_res/chips/chips.prt';

PART_NAME
 R3602 'Q_RES_0402LF-10,1%,1/16W,CHIP,CS01002FB07':;

SECTION_NUMBER 1
 '@T6G_MB_LIB.T6G(SCH_1):PAGE295_I41@PURE_QUANTA.Q_RES(CHIPS)':
 C_PATH='@t6g_mb_lib.t6g(sch_1):page295_i41@pure_quanta.q_res(chips)',
 P_PATH='@t6g_mb_lib.t6g(sch_1):page236_i41@pure_quanta.q_res(chips)',
 PATH='I41',
 DRAWING='@T6G_MB_LIB.T6G(SCH_1):PAGE295',
 WATTAGE='1/16W',
 TOLERANCE='1%',
 MATERIAL='CHIP',
 PHYS_PAGE='236',
 XY='(1300,2475)',
 ROT='0',
 VER='1',
 PACK_TYPE='0402LF',
 LOCATION='R3602',
 CDS_LIB='pure_quanta',
 CDS_PART_NAME='Q_RES_0402LF-10,1%,1/16W,CHIP,CS01002FB07',
 PART_NUMBER='CS01002FB07',
 VALUE='10',
 PRIM_FILE='./archive_libs/logical/q_res/chips/chips.prt';

PART_NAME
 R3603 'Q_RES_0402LF-10,1%,1/16W,CHIP,CS01002FB07':;

SECTION_NUMBER 1
 '@T6G_MB_LIB.T6G(SCH_1):PAGE295_I43@PURE_QUANTA.Q_RES(CHIPS)':
 C_PATH='@t6g_mb_lib.t6g(sch_1):page295_i43@pure_quanta.q_res(chips)',
 P_PATH='@t6g_mb_lib.t6g(sch_1):page236_i43@pure_quanta.q_res(chips)',
 PATH='I43',
 DRAWING='@T6G_MB_LIB.T6G(SCH_1):PAGE295',
 WATTAGE='1/16W',
 TOLERANCE='1%',
 MATERIAL='CHIP',
 PHYS_PAGE='236',
 XY='(1300,2200)',
 ROT='0',
 VER='1',
 PACK_TYPE='0402LF',
 LOCATION='R3603',
 CDS_LIB='pure_quanta',
 CDS_PART_NAME='Q_RES_0402LF-10,1%,1/16W,CHIP,CS01002FB07',
 PART_NUMBER='CS01002FB07',
 VALUE='10',
 PRIM_FILE='./archive_libs/logical/q_res/chips/chips.prt';

PART_NAME
 R3608 'Q_RES_0402LF-4.7K,1%,1/16W,CHIP,CS24702FB06':;

SECTION_NUMBER 1
 '@T6G_MB_LIB.T6G(SCH_1):PAGE360_I103@PURE_QUANTA.Q_RES(CHIPS)':
 C_PATH='@t6g_mb_lib.t6g(sch_1):page360_i103@pure_quanta.q_res(chips)',
 P_PATH='@t6g_mb_lib.t6g(sch_1):page237_i103@pure_quanta.q_res(chips)',
 PATH='I103',
 DRAWING='@T6G_MB_LIB.T6G(SCH_1):PAGE360',
 WATTAGE='1/16W',
 TOLERANCE='1%',
 MATERIAL='CHIP',
 PHYS_PAGE='237',
 XY='(-525,600)',
 ROT='0',
 VER='1',
 PACK_TYPE='0402LF',
 LOCATION='R3608',
 CDS_LIB='pure_quanta',
 CDS_PART_NAME='Q_RES_0402LF-4.7K,1%,1/16W,CHIP,CS24702FB06',
 PART_NUMBER='CS24702FB06',
 VALUE='4.7K',
 PRIM_FILE='./archive_libs/logical/q_res/chips/chips.prt';

PART_NAME
 R3609 'Q_RES_0402LF-4.7K,1%,1/16W,EMPTY,CS24702FB06':;

SECTION_NUMBER 1
 '@T6G_MB_LIB.T6G(SCH_1):PAGE360_I104@PURE_QUANTA.Q_RES(CHIPS)':
 C_PATH='@t6g_mb_lib.t6g(sch_1):page360_i104@pure_quanta.q_res(chips)',
 P_PATH='@t6g_mb_lib.t6g(sch_1):page237_i104@pure_quanta.q_res(chips)',
 PATH='I104',
 DRAWING='@T6G_MB_LIB.T6G(SCH_1):PAGE360',
 WATTAGE='1/16W',
 TOLERANCE='1%',
 MATERIAL='EMPTY',
 PHYS_PAGE='237',
 XY='(-525,525)',
 ROT='0',
 VER='1',
 PACK_TYPE='0402LF',
 LOCATION='R3609',
 CDS_LIB='pure_quanta',
 CDS_PART_NAME='Q_RES_0402LF-4.7K,1%,1/16W,EMPTY,CS24702FB06',
 PART_NUMBER='CS24702FB06',
 VALUE='4.7K',
 PRIM_FILE='./archive_libs/logical/q_res/chips/chips.prt';

PART_NAME
 R3610 'Q_RES_0402LF-4.7K,1%,1/16W,EMPTY,CS24702FB06':;

SECTION_NUMBER 1
 '@T6G_MB_LIB.T6G(SCH_1):PAGE360_I45@PURE_QUANTA.Q_RES(CHIPS)':
 C_PATH='@t6g_mb_lib.t6g(sch_1):page360_i45@pure_quanta.q_res(chips)',
 P_PATH='@t6g_mb_lib.t6g(sch_1):page237_i45@pure_quanta.q_res(chips)',
 PATH='I45',
 DRAWING='@T6G_MB_LIB.T6G(SCH_1):PAGE360',
 WATTAGE='1/16W',
 TOLERANCE='1%',
 MATERIAL='EMPTY',
 PHYS_PAGE='237',
 XY='(-1050,-1675)',
 ROT='0',
 VER='1',
 PACK_TYPE='0402LF',
 LOCATION='R3610',
 CDS_LIB='pure_quanta',
 CDS_PART_NAME='Q_RES_0402LF-4.7K,1%,1/16W,EMPTY,CS24702FB06',
 PART_NUMBER='CS24702FB06',
 VALUE='4.7K',
 PRIM_FILE='./archive_libs/logical/q_res/chips/chips.prt';

PART_NAME
 R3611 'Q_RES_0402LF-4.7K,1%,1/16W,CHIP,CS24702FB06':;

SECTION_NUMBER 1
 '@T6G_MB_LIB.T6G(SCH_1):PAGE360_I36@PURE_QUANTA.Q_RES(CHIPS)':
 C_PATH='@t6g_mb_lib.t6g(sch_1):page360_i36@pure_quanta.q_res(chips)',
 P_PATH='@t6g_mb_lib.t6g(sch_1):page237_i36@pure_quanta.q_res(chips)',
 PATH='I36',
 DRAWING='@T6G_MB_LIB.T6G(SCH_1):PAGE360',
 WATTAGE='1/16W',
 TOLERANCE='1%',
 MATERIAL='CHIP',
 PHYS_PAGE='237',
 XY='(-1050,-1750)',
 ROT='0',
 VER='1',
 PACK_TYPE='0402LF',
 LOCATION='R3611',
 CDS_LIB='pure_quanta',
 CDS_PART_NAME='Q_RES_0402LF-4.7K,1%,1/16W,CHIP,CS24702FB06',
 PART_NUMBER='CS24702FB06',
 VALUE='4.7K',
 PRIM_FILE='./archive_libs/logical/q_res/chips/chips.prt';

PART_NAME
 R3612 'Q_RES_0402LF-4.7K,1%,1/16W,EMPTY,CS24702FB06':;

SECTION_NUMBER 1
 '@T6G_MB_LIB.T6G(SCH_1):PAGE360_I68@PURE_QUANTA.Q_RES(CHIPS)':
 C_PATH='@t6g_mb_lib.t6g(sch_1):page360_i68@pure_quanta.q_res(chips)',
 P_PATH='@t6g_mb_lib.t6g(sch_1):page237_i68@pure_quanta.q_res(chips)',
 PATH='I68',
 DRAWING='@T6G_MB_LIB.T6G(SCH_1):PAGE360',
 WATTAGE='1/16W',
 TOLERANCE='1%',
 MATERIAL='EMPTY',
 PHYS_PAGE='237',
 XY='(-975,-3850)',
 ROT='0',
 VER='1',
 PACK_TYPE='0402LF',
 LOCATION='R3612',
 CDS_LIB='pure_quanta',
 CDS_PART_NAME='Q_RES_0402LF-4.7K,1%,1/16W,EMPTY,CS24702FB06',
 PART_NUMBER='CS24702FB06',
 VALUE='4.7K',
 PRIM_FILE='./archive_libs/logical/q_res/chips/chips.prt';

PART_NAME
 R3613 'Q_RES_0402LF-4.7K,1%,1/16W,EMPTY,CS24702FB06':;

SECTION_NUMBER 1
 '@T6G_MB_LIB.T6G(SCH_1):PAGE360_I59@PURE_QUANTA.Q_RES(CHIPS)':
 C_PATH='@t6g_mb_lib.t6g(sch_1):page360_i59@pure_quanta.q_res(chips)',
 P_PATH='@t6g_mb_lib.t6g(sch_1):page237_i59@pure_quanta.q_res(chips)',
 PATH='I59',
 DRAWING='@T6G_MB_LIB.T6G(SCH_1):PAGE360',
 WATTAGE='1/16W',
 TOLERANCE='1%',
 MATERIAL='EMPTY',
 PHYS_PAGE='237',
 XY='(-975,-3925)',
 ROT='0',
 VER='1',
 PACK_TYPE='0402LF',
 LOCATION='R3613',
 CDS_LIB='pure_quanta',
 CDS_PART_NAME='Q_RES_0402LF-4.7K,1%,1/16W,EMPTY,CS24702FB06',
 PART_NUMBER='CS24702FB06',
 VALUE='4.7K',
 PRIM_FILE='./archive_libs/logical/q_res/chips/chips.prt';

PART_NAME
 R3616 'Q_RES_0402LF-4.7K,1%,1/16W,CHIP,CS24702FB06':;

SECTION_NUMBER 1
 '@T6G_MB_LIB.T6G(SCH_1):PAGE295_I31@PURE_QUANTA.Q_RES(CHIPS)':
 C_PATH='@t6g_mb_lib.t6g(sch_1):page295_i31@pure_quanta.q_res(chips)',
 P_PATH='@t6g_mb_lib.t6g(sch_1):page236_i31@pure_quanta.q_res(chips)',
 PATH='I31',
 DRAWING='@T6G_MB_LIB.T6G(SCH_1):PAGE295',
 WATTAGE='1/16W',
 TOLERANCE='1%',
 MATERIAL='CHIP',
 PHYS_PAGE='236',
 XY='(625,3350)',
 ROT='0',
 VER='1',
 PACK_TYPE='0402LF',
 LOCATION='R3616',
 CDS_LIB='pure_quanta',
 CDS_PART_NAME='Q_RES_0402LF-4.7K,1%,1/16W,CHIP,CS24702FB06',
 PART_NUMBER='CS24702FB06',
 VALUE='4.7K',
 PRIM_FILE='./archive_libs/logical/q_res/chips/chips.prt';

PART_NAME
 R3617 'Q_RES_0402LF-4.7K,1%,1/16W,EMPTY,CS24702FB06':;

SECTION_NUMBER 1
 '@T6G_MB_LIB.T6G(SCH_1):PAGE295_I40@PURE_QUANTA.Q_RES(CHIPS)':
 C_PATH='@t6g_mb_lib.t6g(sch_1):page295_i40@pure_quanta.q_res(chips)',
 P_PATH='@t6g_mb_lib.t6g(sch_1):page236_i40@pure_quanta.q_res(chips)',
 PATH='I40',
 DRAWING='@T6G_MB_LIB.T6G(SCH_1):PAGE295',
 WATTAGE='1/16W',
 TOLERANCE='1%',
 MATERIAL='EMPTY',
 PHYS_PAGE='236',
 XY='(625,3275)',
 ROT='0',
 VER='1',
 PACK_TYPE='0402LF',
 LOCATION='R3617',
 CDS_LIB='pure_quanta',
 CDS_PART_NAME='Q_RES_0402LF-4.7K,1%,1/16W,EMPTY,CS24702FB06',
 PART_NUMBER='CS24702FB06',
 VALUE='4.7K',
 PRIM_FILE='./archive_libs/logical/q_res/chips/chips.prt';

PART_NAME
 R3620 'Q_RES_0402LF-0,5%,1/16W,CHIP,CS00002JB13':;

SECTION_NUMBER 1
 '@T6G_MB_LIB.T6G(SCH_1):PAGE360_I100@PURE_QUANTA.Q_RES(CHIPS)':
 C_PATH='@t6g_mb_lib.t6g(sch_1):page360_i100@pure_quanta.q_res(chips)',
 P_PATH='@t6g_mb_lib.t6g(sch_1):page237_i100@pure_quanta.q_res(chips)',
 PATH='I100',
 DRAWING='@T6G_MB_LIB.T6G(SCH_1):PAGE360',
 WATTAGE='1/16W',
 TOLERANCE='5%',
 MATERIAL='CHIP',
 PHYS_PAGE='237',
 XY='(525,350)',
 ROT='0',
 VER='2',
 PACK_TYPE='0402LF',
 LOCATION='R3620',
 CDS_LIB='pure_quanta',
 CDS_PART_NAME='Q_RES_0402LF-0,5%,1/16W,CHIP,CS00002JB13',
 PART_NUMBER='CS00002JB13',
 VALUE='0',
 PRIM_FILE='./archive_libs/logical/q_res/chips/chips.prt';

PART_NAME
 R3621 'Q_RES_0402LF-4.7K,1%,1/16W,EMPTY,CS24702FB06':;

SECTION_NUMBER 1
 '@T6G_MB_LIB.T6G(SCH_1):PAGE360_I87@PURE_QUANTA.Q_RES(CHIPS)':
 C_PATH='@t6g_mb_lib.t6g(sch_1):page360_i87@pure_quanta.q_res(chips)',
 P_PATH='@t6g_mb_lib.t6g(sch_1):page237_i87@pure_quanta.q_res(chips)',
 PATH='I87',
 DRAWING='@T6G_MB_LIB.T6G(SCH_1):PAGE360',
 WATTAGE='1/16W',
 TOLERANCE='1%',
 MATERIAL='EMPTY',
 PHYS_PAGE='237',
 XY='(-225,-1325)',
 ROT='0',
 VER='2',
 PACK_TYPE='0402LF',
 LOCATION='R3621',
 CDS_LIB='pure_quanta',
 CDS_PART_NAME='Q_RES_0402LF-4.7K,1%,1/16W,EMPTY,CS24702FB06',
 PART_NUMBER='CS24702FB06',
 VALUE='4.7K',
 PRIM_FILE='./archive_libs/logical/q_res/chips/chips.prt';

PART_NAME
 R3622 'Q_RES_0402LF-4.7K,1%,1/16W,CHIP,CS24702FB06':;

SECTION_NUMBER 1
 '@T6G_MB_LIB.T6G(SCH_1):PAGE360_I90@PURE_QUANTA.Q_RES(CHIPS)':
 C_PATH='@t6g_mb_lib.t6g(sch_1):page360_i90@pure_quanta.q_res(chips)',
 P_PATH='@t6g_mb_lib.t6g(sch_1):page237_i90@pure_quanta.q_res(chips)',
 PATH='I90',
 DRAWING='@T6G_MB_LIB.T6G(SCH_1):PAGE360',
 WATTAGE='1/16W',
 TOLERANCE='1%',
 MATERIAL='CHIP',
 PHYS_PAGE='237',
 XY='(-175,-3525)',
 ROT='0',
 VER='2',
 PACK_TYPE='0402LF',
 LOCATION='R3622',
 CDS_LIB='pure_quanta',
 CDS_PART_NAME='Q_RES_0402LF-4.7K,1%,1/16W,CHIP,CS24702FB06',
 PART_NUMBER='CS24702FB06',
 VALUE='4.7K',
 PRIM_FILE='./archive_libs/logical/q_res/chips/chips.prt';

PART_NAME
 R3623 'Q_RES_0402LF-4.7K,1%,1/16W,CHIP,CS24702FB06':;

SECTION_NUMBER 1
 '@T6G_MB_LIB.T6G(SCH_1):PAGE360_I86@PURE_QUANTA.Q_RES(CHIPS)':
 C_PATH='@t6g_mb_lib.t6g(sch_1):page360_i86@pure_quanta.q_res(chips)',
 P_PATH='@t6g_mb_lib.t6g(sch_1):page237_i86@pure_quanta.q_res(chips)',
 PATH='I86',
 DRAWING='@T6G_MB_LIB.T6G(SCH_1):PAGE360',
 WATTAGE='1/16W',
 TOLERANCE='1%',
 MATERIAL='CHIP',
 PHYS_PAGE='237',
 XY='(75,-1325)',
 ROT='0',
 VER='2',
 PACK_TYPE='0402LF',
 LOCATION='R3623',
 CDS_LIB='pure_quanta',
 CDS_PART_NAME='Q_RES_0402LF-4.7K,1%,1/16W,CHIP,CS24702FB06',
 PART_NUMBER='CS24702FB06',
 VALUE='4.7K',
 PRIM_FILE='./archive_libs/logical/q_res/chips/chips.prt';

PART_NAME
 R3624 'Q_RES_0402LF-4.7K,1%,1/16W,CHIP,CS24702FB06':;

SECTION_NUMBER 1
 '@T6G_MB_LIB.T6G(SCH_1):PAGE360_I89@PURE_QUANTA.Q_RES(CHIPS)':
 C_PATH='@t6g_mb_lib.t6g(sch_1):page360_i89@pure_quanta.q_res(chips)',
 P_PATH='@t6g_mb_lib.t6g(sch_1):page237_i89@pure_quanta.q_res(chips)',
 PATH='I89',
 DRAWING='@T6G_MB_LIB.T6G(SCH_1):PAGE360',
 WATTAGE='1/16W',
 TOLERANCE='1%',
 MATERIAL='CHIP',
 PHYS_PAGE='237',
 XY='(125,-3525)',
 ROT='0',
 VER='2',
 PACK_TYPE='0402LF',
 LOCATION='R3624',
 CDS_LIB='pure_quanta',
 CDS_PART_NAME='Q_RES_0402LF-4.7K,1%,1/16W,CHIP,CS24702FB06',
 PART_NUMBER='CS24702FB06',
 VALUE='4.7K',
 PRIM_FILE='./archive_libs/logical/q_res/chips/chips.prt';

PART_NAME
 R3627 'Q_RES_0402LF-4.7K,1%,1/16W,CHIP,CS24702FB06':;

SECTION_NUMBER 1
 '@T6G_MB_LIB.T6G(SCH_1):PAGE295_I89@PURE_QUANTA.Q_RES(CHIPS)':
 C_PATH='@t6g_mb_lib.t6g(sch_1):page295_i89@pure_quanta.q_res(chips)',
 P_PATH='@t6g_mb_lib.t6g(sch_1):page236_i89@pure_quanta.q_res(chips)',
 PATH='I89',
 DRAWING='@T6G_MB_LIB.T6G(SCH_1):PAGE295',
 WATTAGE='1/16W',
 TOLERANCE='1%',
 MATERIAL='CHIP',
 PHYS_PAGE='236',
 XY='(1525,3700)',
 ROT='0',
 VER='2',
 PACK_TYPE='0402LF',
 LOCATION='R3627',
 CDS_LIB='pure_quanta',
 CDS_PART_NAME='Q_RES_0402LF-4.7K,1%,1/16W,CHIP,CS24702FB06',
 PART_NUMBER='CS24702FB06',
 VALUE='4.7K',
 PRIM_FILE='./archive_libs/logical/q_res/chips/chips.prt';

PART_NAME
 R3628 'Q_RES_0402LF-4.7K,1%,1/16W,EMPTY,CS24702FB06':;

SECTION_NUMBER 1
 '@T6G_MB_LIB.T6G(SCH_1):PAGE295_I88@PURE_QUANTA.Q_RES(CHIPS)':
 C_PATH='@t6g_mb_lib.t6g(sch_1):page295_i88@pure_quanta.q_res(chips)',
 P_PATH='@t6g_mb_lib.t6g(sch_1):page236_i88@pure_quanta.q_res(chips)',
 PATH='I88',
 DRAWING='@T6G_MB_LIB.T6G(SCH_1):PAGE295',
 WATTAGE='1/16W',
 TOLERANCE='1%',
 MATERIAL='EMPTY',
 PHYS_PAGE='236',
 XY='(1825,3700)',
 ROT='0',
 VER='2',
 PACK_TYPE='0402LF',
 LOCATION='R3628',
 CDS_LIB='pure_quanta',
 CDS_PART_NAME='Q_RES_0402LF-4.7K,1%,1/16W,EMPTY,CS24702FB06',
 PART_NUMBER='CS24702FB06',
 VALUE='4.7K',
 PRIM_FILE='./archive_libs/logical/q_res/chips/chips.prt';

PART_NAME
 R3630 'Q_RES_0402LF-0,5%,1/16W,EMPTY,CS00002JB13':
 ROOM='NIC_P12V_MPS_MAM_BOM2';

SECTION_NUMBER 1
 '@T6G_MB_LIB.T6G(SCH_1):PAGE344_I73@PURE_QUANTA.Q_RES(CHIPS)':
 C_PATH='@t6g_mb_lib.t6g(sch_1):page344_i73@pure_quanta.q_res(chips)',
 P_PATH='@t6g_mb_lib.t6g(sch_1):page141_i73@pure_quanta.q_res(chips)',
 PATH='I73',
 DRAWING='@T6G_MB_LIB.T6G(SCH_1):PAGE344',
 WATTAGE='1/16W',
 TOLERANCE='5%',
 MATERIAL='EMPTY',
 PHYS_PAGE='141',
 XY='(-3500,3050)',
 ROT='0',
 VER='1',
 PACK_TYPE='0402LF',
 LOCATION='R3630',
 CDS_LIB='pure_quanta',
 CDS_PART_NAME='Q_RES_0402LF-0,5%,1/16W,EMPTY,CS00002JB13',
 ROOM='NIC_P12V_MPS_MAM_BOM2',
 PART_NUMBER='CS00002JB13',
 VALUE='0',
 PRIM_FILE='./archive_libs/logical/q_res/chips/chips.prt';

PART_NAME
 R3631 'Q_RES_0402LF-0,5%,1/16W,EMPTY,CS00002JB13':
 ROOM='NIC_P3V3_BOM2';

SECTION_NUMBER 1
 '@T6G_MB_LIB.T6G(SCH_1):PAGE344_I74@PURE_QUANTA.Q_RES(CHIPS)':
 C_PATH='@t6g_mb_lib.t6g(sch_1):page344_i74@pure_quanta.q_res(chips)',
 P_PATH='@t6g_mb_lib.t6g(sch_1):page141_i74@pure_quanta.q_res(chips)',
 PATH='I74',
 DRAWING='@T6G_MB_LIB.T6G(SCH_1):PAGE344',
 WATTAGE='1/16W',
 TOLERANCE='5%',
 MATERIAL='EMPTY',
 PHYS_PAGE='141',
 XY='(225,6475)',
 ROT='0',
 VER='1',
 PACK_TYPE='0402LF',
 LOCATION='R3631',
 CDS_LIB='pure_quanta',
 CDS_PART_NAME='Q_RES_0402LF-0,5%,1/16W,EMPTY,CS00002JB13',
 ROOM='NIC_P3V3_BOM2',
 PART_NUMBER='CS00002JB13',
 VALUE='0',
 PRIM_FILE='./archive_libs/logical/q_res/chips/chips.prt';

PART_NAME
 R3633 'Q_RES_2512LF-0.002,1%,2W,CHIP,CS+002AFR06':;

SECTION_NUMBER 1
 '@T6G_MB_LIB.T6G(SCH_1):PAGE360_I116@PURE_QUANTA.Q_RES(CHIPS)':
 C_PATH='@t6g_mb_lib.t6g(sch_1):page360_i116@pure_quanta.q_res(chips)',
 P_PATH='@t6g_mb_lib.t6g(sch_1):page237_i116@pure_quanta.q_res(chips)',
 PATH='I116',
 DRAWING='@T6G_MB_LIB.T6G(SCH_1):PAGE360',
 WATTAGE='2W',
 TOLERANCE='1%',
 MATERIAL='CHIP',
 PHYS_PAGE='237',
 XY='(-1750,-275)',
 ROT='0',
 VER='1',
 PACK_TYPE='2512LF',
 LOCATION='R3633',
 CDS_LIB='pure_quanta',
 CDS_PART_NAME='Q_RES_2512LF-0.002,1%,2W,CHIP,CS+002AFR06',
 PART_NUMBER='CS+002AFR06',
 VALUE='0.002',
 PRIM_FILE='./archive_libs/logical/q_res/chips/chips.prt';

PART_NAME
 R3634 'Q_RES_2512LF-0.002,1%,2W,CHIP,CS+002AFR06':;

SECTION_NUMBER 1
 '@T6G_MB_LIB.T6G(SCH_1):PAGE360_I92@PURE_QUANTA.Q_RES(CHIPS)':
 C_PATH='@t6g_mb_lib.t6g(sch_1):page360_i92@pure_quanta.q_res(chips)',
 P_PATH='@t6g_mb_lib.t6g(sch_1):page237_i92@pure_quanta.q_res(chips)',
 PATH='I92',
 DRAWING='@T6G_MB_LIB.T6G(SCH_1):PAGE360',
 WATTAGE='2W',
 TOLERANCE='1%',
 MATERIAL='CHIP',
 PHYS_PAGE='237',
 XY='(-2150,-2375)',
 ROT='0',
 VER='1',
 PACK_TYPE='2512LF',
 LOCATION='R3634',
 CDS_LIB='pure_quanta',
 CDS_PART_NAME='Q_RES_2512LF-0.002,1%,2W,CHIP,CS+002AFR06',
 PART_NUMBER='CS+002AFR06',
 VALUE='0.002',
 PRIM_FILE='./archive_libs/logical/q_res/chips/chips.prt';

PART_NAME
 R3635 'Q_RES_2512LF-0.002,1%,2W,CHIP,CS+002AFR06':;

SECTION_NUMBER 1
 '@T6G_MB_LIB.T6G(SCH_1):PAGE360_I93@PURE_QUANTA.Q_RES(CHIPS)':
 C_PATH='@t6g_mb_lib.t6g(sch_1):page360_i93@pure_quanta.q_res(chips)',
 P_PATH='@t6g_mb_lib.t6g(sch_1):page237_i93@pure_quanta.q_res(chips)',
 PATH='I93',
 DRAWING='@T6G_MB_LIB.T6G(SCH_1):PAGE360',
 WATTAGE='2W',
 TOLERANCE='1%',
 MATERIAL='CHIP',
 PHYS_PAGE='237',
 XY='(-2050,-4525)',
 ROT='0',
 VER='1',
 PACK_TYPE='2512LF',
 LOCATION='R3635',
 CDS_LIB='pure_quanta',
 CDS_PART_NAME='Q_RES_2512LF-0.002,1%,2W,CHIP,CS+002AFR06',
 PART_NUMBER='CS+002AFR06',
 VALUE='0.002',
 PRIM_FILE='./archive_libs/logical/q_res/chips/chips.prt';

PART_NAME
 R3645 'Q_RES_2512LF-0.002,1%,2W,CHIP,CS+002AFR06':;

SECTION_NUMBER 1
 '@T6G_MB_LIB.T6G(SCH_1):PAGE295_I93@PURE_QUANTA.Q_RES(CHIPS)':
 C_PATH='@t6g_mb_lib.t6g(sch_1):page295_i93@pure_quanta.q_res(chips)',
 P_PATH='@t6g_mb_lib.t6g(sch_1):page236_i93@pure_quanta.q_res(chips)',
 PATH='I93',
 DRAWING='@T6G_MB_LIB.T6G(SCH_1):PAGE295',
 WATTAGE='2W',
 TOLERANCE='1%',
 MATERIAL='CHIP',
 PHYS_PAGE='236',
 XY='(-600,2675)',
 ROT='0',
 VER='1',
 PACK_TYPE='2512LF',
 LOCATION='R3645',
 CDS_LIB='pure_quanta',
 CDS_PART_NAME='Q_RES_2512LF-0.002,1%,2W,CHIP,CS+002AFR06',
 PART_NUMBER='CS+002AFR06',
 VALUE='0.002',
 PRIM_FILE='./archive_libs/logical/q_res/chips/chips.prt';

PART_NAME
 R3651 'Q_RES_0402LF-0,5%,1/16W,CHIP,CS00002JB13':
 ROOM='USB2 BOM1';

SECTION_NUMBER 1
 '@T6G_MB_LIB.T6G(SCH_1):PAGE358_I138@PURE_QUANTA.Q_RES(CHIPS)':
 C_PATH='@t6g_mb_lib.t6g(sch_1):page358_i138@pure_quanta.q_res(chips)',
 P_PATH='@t6g_mb_lib.t6g(sch_1):page234_i138@pure_quanta.q_res(chips)',
 PATH='I138',
 DRAWING='@T6G_MB_LIB.T6G(SCH_1):PAGE358',
 WATTAGE='1/16W',
 TOLERANCE='5%',
 MATERIAL='CHIP',
 PHYS_PAGE='234',
 XY='(2550,3925)',
 ROT='0',
 VER='1',
 PACK_TYPE='0402LF',
 LOCATION='R3651',
 CDS_LIB='pure_quanta',
 CDS_PART_NAME='Q_RES_0402LF-0,5%,1/16W,CHIP,CS00002JB13',
 ROOM='USB2 BOM1',
 PART_NUMBER='CS00002JB13',
 VALUE='0',
 PRIM_FILE='./archive_libs/logical/q_res/chips/chips.prt';

PART_NAME
 R3652 'Q_RES_0402LF-0,5%,1/16W,CHIP,CS00002JB13':
 ROOM='USB2 BOM1';

SECTION_NUMBER 1
 '@T6G_MB_LIB.T6G(SCH_1):PAGE358_I137@PURE_QUANTA.Q_RES(CHIPS)':
 C_PATH='@t6g_mb_lib.t6g(sch_1):page358_i137@pure_quanta.q_res(chips)',
 P_PATH='@t6g_mb_lib.t6g(sch_1):page234_i137@pure_quanta.q_res(chips)',
 PATH='I137',
 DRAWING='@T6G_MB_LIB.T6G(SCH_1):PAGE358',
 WATTAGE='1/16W',
 TOLERANCE='5%',
 MATERIAL='CHIP',
 PHYS_PAGE='234',
 XY='(2550,3875)',
 ROT='0',
 VER='1',
 PACK_TYPE='0402LF',
 LOCATION='R3652',
 CDS_LIB='pure_quanta',
 CDS_PART_NAME='Q_RES_0402LF-0,5%,1/16W,CHIP,CS00002JB13',
 ROOM='USB2 BOM1',
 PART_NUMBER='CS00002JB13',
 VALUE='0',
 PRIM_FILE='./archive_libs/logical/q_res/chips/chips.prt';

PART_NAME
 R3653 'Q_RES_0402LF-680,1%,1/16W,CHIP,CS16802FB03':
 ROOM='USB2 BOM1';

SECTION_NUMBER 1
 '@T6G_MB_LIB.T6G(SCH_1):PAGE358_I139@PURE_QUANTA.Q_RES(CHIPS)':
 C_PATH='@t6g_mb_lib.t6g(sch_1):page358_i139@pure_quanta.q_res(chips)',
 P_PATH='@t6g_mb_lib.t6g(sch_1):page234_i139@pure_quanta.q_res(chips)',
 PATH='I139',
 DRAWING='@T6G_MB_LIB.T6G(SCH_1):PAGE358',
 WATTAGE='1/16W',
 TOLERANCE='1%',
 MATERIAL='CHIP',
 PHYS_PAGE='234',
 XY='(-1075,3100)',
 ROT='0',
 VER='2',
 PACK_TYPE='0402LF',
 LOCATION='R3653',
 CDS_LIB='pure_quanta',
 CDS_PART_NAME='Q_RES_0402LF-680,1%,1/16W,CHIP,CS16802FB03',
 ROOM='USB2 BOM1',
 PART_NUMBER='CS16802FB03',
 VALUE='680',
 PRIM_FILE='./archive_libs/logical/q_res/chips/chips.prt';

PART_NAME
 R3654 'Q_RES_0402LF-33.2,1%,1/16W,CHIP,CS03322FB03':;

SECTION_NUMBER 1
 '@T6G_MB_LIB.T6G(SCH_1):PAGE358_I155@PURE_QUANTA.Q_RES(CHIPS)':
 C_PATH='@t6g_mb_lib.t6g(sch_1):page358_i155@pure_quanta.q_res(chips)',
 P_PATH='@t6g_mb_lib.t6g(sch_1):page234_i155@pure_quanta.q_res(chips)',
 PATH='I155',
 DRAWING='@T6G_MB_LIB.T6G(SCH_1):PAGE358',
 WATTAGE='1/16W',
 TOLERANCE='1%',
 MATERIAL='CHIP',
 PHYS_PAGE='234',
 XY='(-2725,3425)',
 ROT='0',
 VER='1',
 PACK_TYPE='0402LF',
 LOCATION='R3654',
 CDS_LIB='pure_quanta',
 CDS_PART_NAME='Q_RES_0402LF-33.2,1%,1/16W,CHIP,CS03322FB03',
 PART_NUMBER='CS03322FB03',
 VALUE='33.2',
 PRIM_FILE='./archive_libs/logical/q_res/chips/chips.prt';

PART_NAME
 R3655 'Q_RES_0402LF-0,5%,1/16W,CHIP,CS00002JB13':
 ROOM='USB2 BOM1';

SECTION_NUMBER 1
 '@T6G_MB_LIB.T6G(SCH_1):PAGE358_I161@PURE_QUANTA.Q_RES(CHIPS)':
 C_PATH='@t6g_mb_lib.t6g(sch_1):page358_i161@pure_quanta.q_res(chips)',
 P_PATH='@t6g_mb_lib.t6g(sch_1):page234_i161@pure_quanta.q_res(chips)',
 PATH='I161',
 DRAWING='@T6G_MB_LIB.T6G(SCH_1):PAGE358',
 WATTAGE='1/16W',
 TOLERANCE='5%',
 MATERIAL='CHIP',
 PHYS_PAGE='234',
 XY='(-3750,4800)',
 ROT='0',
 VER='1',
 PACK_TYPE='0402LF',
 LOCATION='R3655',
 CDS_LIB='pure_quanta',
 CDS_PART_NAME='Q_RES_0402LF-0,5%,1/16W,CHIP,CS00002JB13',
 ROOM='USB2 BOM1',
 PART_NUMBER='CS00002JB13',
 VALUE='0',
 PRIM_FILE='./archive_libs/logical/q_res/chips/chips.prt';

PART_NAME
 R3656 'Q_RES_0402LF-10K,1%,1/16W,EMPTY,CS31002FB08':
 ROOM='USB2 BOM1';

SECTION_NUMBER 1
 '@T6G_MB_LIB.T6G(SCH_1):PAGE358_I194@PURE_QUANTA.Q_RES(CHIPS)':
 C_PATH='@t6g_mb_lib.t6g(sch_1):page358_i194@pure_quanta.q_res(chips)',
 P_PATH='@t6g_mb_lib.t6g(sch_1):page234_i194@pure_quanta.q_res(chips)',
 PATH='I194',
 DRAWING='@T6G_MB_LIB.T6G(SCH_1):PAGE358',
 WATTAGE='1/16W',
 TOLERANCE='1%',
 MATERIAL='EMPTY',
 PHYS_PAGE='234',
 XY='(-1550,2275)',
 ROT='0',
 VER='1',
 PACK_TYPE='0402LF',
 LOCATION='R3656',
 CDS_LIB='pure_quanta',
 CDS_PART_NAME='Q_RES_0402LF-10K,1%,1/16W,EMPTY,CS31002FB08',
 ROOM='USB2 BOM1',
 PART_NUMBER='CS31002FB08',
 VALUE='10K',
 PRIM_FILE='./archive_libs/logical/q_res/chips/chips.prt';

PART_NAME
 R3657 'Q_RES_0402LF-10K,1%,1/16W,EMPTY,CS31002FB08':
 ROOM='USB2 BOM1';

SECTION_NUMBER 1
 '@T6G_MB_LIB.T6G(SCH_1):PAGE358_I195@PURE_QUANTA.Q_RES(CHIPS)':
 C_PATH='@t6g_mb_lib.t6g(sch_1):page358_i195@pure_quanta.q_res(chips)',
 P_PATH='@t6g_mb_lib.t6g(sch_1):page234_i195@pure_quanta.q_res(chips)',
 PATH='I195',
 DRAWING='@T6G_MB_LIB.T6G(SCH_1):PAGE358',
 WATTAGE='1/16W',
 TOLERANCE='1%',
 MATERIAL='EMPTY',
 PHYS_PAGE='234',
 XY='(-1550,2125)',
 ROT='0',
 VER='1',
 PACK_TYPE='0402LF',
 LOCATION='R3657',
 CDS_LIB='pure_quanta',
 CDS_PART_NAME='Q_RES_0402LF-10K,1%,1/16W,EMPTY,CS31002FB08',
 ROOM='USB2 BOM1',
 PART_NUMBER='CS31002FB08',
 VALUE='10K',
 PRIM_FILE='./archive_libs/logical/q_res/chips/chips.prt';

PART_NAME
 R3658 'Q_RES_0402LF-10K,1%,1/16W,EMPTY,CS31002FB08':
 ROOM='USB2 BOM1';

SECTION_NUMBER 1
 '@T6G_MB_LIB.T6G(SCH_1):PAGE358_I196@PURE_QUANTA.Q_RES(CHIPS)':
 C_PATH='@t6g_mb_lib.t6g(sch_1):page358_i196@pure_quanta.q_res(chips)',
 P_PATH='@t6g_mb_lib.t6g(sch_1):page234_i196@pure_quanta.q_res(chips)',
 PATH='I196',
 DRAWING='@T6G_MB_LIB.T6G(SCH_1):PAGE358',
 WATTAGE='1/16W',
 TOLERANCE='1%',
 MATERIAL='EMPTY',
 PHYS_PAGE='234',
 XY='(-1550,2000)',
 ROT='0',
 VER='1',
 PACK_TYPE='0402LF',
 LOCATION='R3658',
 CDS_LIB='pure_quanta',
 CDS_PART_NAME='Q_RES_0402LF-10K,1%,1/16W,EMPTY,CS31002FB08',
 ROOM='USB2 BOM1',
 PART_NUMBER='CS31002FB08',
 VALUE='10K',
 PRIM_FILE='./archive_libs/logical/q_res/chips/chips.prt';

PART_NAME
 R3659 'Q_RES_0402LF-10K,1%,1/16W,EMPTY,CS31002FB08':
 ROOM='USB2 BOM1';

SECTION_NUMBER 1
 '@T6G_MB_LIB.T6G(SCH_1):PAGE358_I198@PURE_QUANTA.Q_RES(CHIPS)':
 C_PATH='@t6g_mb_lib.t6g(sch_1):page358_i198@pure_quanta.q_res(chips)',
 P_PATH='@t6g_mb_lib.t6g(sch_1):page234_i198@pure_quanta.q_res(chips)',
 PATH='I198',
 DRAWING='@T6G_MB_LIB.T6G(SCH_1):PAGE358',
 WATTAGE='1/16W',
 TOLERANCE='1%',
 MATERIAL='EMPTY',
 PHYS_PAGE='234',
 XY='(-1550,1875)',
 ROT='0',
 VER='1',
 PACK_TYPE='0402LF',
 LOCATION='R3659',
 CDS_LIB='pure_quanta',
 CDS_PART_NAME='Q_RES_0402LF-10K,1%,1/16W,EMPTY,CS31002FB08',
 ROOM='USB2 BOM1',
 PART_NUMBER='CS31002FB08',
 VALUE='10K',
 PRIM_FILE='./archive_libs/logical/q_res/chips/chips.prt';

PART_NAME
 R3660 'Q_RES_0402LF-10K,1%,1/16W,CHIP,CS31002FB08':;

SECTION_NUMBER 1
 '@T6G_MB_LIB.T6G(SCH_1):PAGE358_I159@PURE_QUANTA.Q_RES(CHIPS)':
 C_PATH='@t6g_mb_lib.t6g(sch_1):page358_i159@pure_quanta.q_res(chips)',
 P_PATH='@t6g_mb_lib.t6g(sch_1):page234_i159@pure_quanta.q_res(chips)',
 PATH='I159',
 DRAWING='@T6G_MB_LIB.T6G(SCH_1):PAGE358',
 WATTAGE='1/16W',
 TOLERANCE='1%',
 MATERIAL='CHIP',
 PHYS_PAGE='234',
 XY='(-1900,3775)',
 ROT='0',
 VER='2',
 PACK_TYPE='0402LF',
 LOCATION='R3660',
 CDS_LIB='pure_quanta',
 CDS_PART_NAME='Q_RES_0402LF-10K,1%,1/16W,CHIP,CS31002FB08',
 PART_NUMBER='CS31002FB08',
 VALUE='10K',
 PRIM_FILE='./archive_libs/logical/q_res/chips/chips.prt';

PART_NAME
 R3661 'Q_RES_0402LF-47K,0.1%,1/16W,EMPTY,CS34702BB05':;

SECTION_NUMBER 1
 '@T6G_MB_LIB.T6G(SCH_1):PAGE358_I201@PURE_QUANTA.Q_RES(CHIPS)':
 C_PATH='@t6g_mb_lib.t6g(sch_1):page358_i201@pure_quanta.q_res(chips)',
 P_PATH='@t6g_mb_lib.t6g(sch_1):page234_i201@pure_quanta.q_res(chips)',
 PATH='I201',
 DRAWING='@T6G_MB_LIB.T6G(SCH_1):PAGE358',
 WATTAGE='1/16W',
 TOLERANCE='0.1%',
 MATERIAL='EMPTY',
 PHYS_PAGE='234',
 XY='(-1900,3100)',
 ROT='1',
 VER='1',
 PACK_TYPE='0402LF',
 LOCATION='R3661',
 CDS_LIB='pure_quanta',
 CDS_PART_NAME='Q_RES_0402LF-47K,0.1%,1/16W,EMPTY,CS34702BB05',
 PART_NUMBER='CS34702BB05',
 VALUE='47K',
 PRIM_FILE='./archive_libs/logical/q_res/chips/chips.prt';

PART_NAME
 R3662 'Q_RES_0402LF-0,5%,1/16W,CHIP,CS00002JB13':
 ROOM='USB2 BOM1';

SECTION_NUMBER 1
 '@T6G_MB_LIB.T6G(SCH_1):PAGE358_I167@PURE_QUANTA.Q_RES(CHIPS)':
 C_PATH='@t6g_mb_lib.t6g(sch_1):page358_i167@pure_quanta.q_res(chips)',
 P_PATH='@t6g_mb_lib.t6g(sch_1):page234_i167@pure_quanta.q_res(chips)',
 PATH='I167',
 DRAWING='@T6G_MB_LIB.T6G(SCH_1):PAGE358',
 WATTAGE='1/16W',
 TOLERANCE='5%',
 MATERIAL='CHIP',
 PHYS_PAGE='234',
 XY='(-1025,3925)',
 ROT='0',
 VER='1',
 PACK_TYPE='0402LF',
 LOCATION='R3662',
 CDS_LIB='pure_quanta',
 CDS_PART_NAME='Q_RES_0402LF-0,5%,1/16W,CHIP,CS00002JB13',
 ROOM='USB2 BOM1',
 PART_NUMBER='CS00002JB13',
 VALUE='0',
 PRIM_FILE='./archive_libs/logical/q_res/chips/chips.prt';

PART_NAME
 R3663 'Q_RES_0402LF-10K,1%,1/16W,CHIP,CS31002FB08':
 ROOM='USB2 BOM1';

SECTION_NUMBER 1
 '@T6G_MB_LIB.T6G(SCH_1):PAGE358_I186@PURE_QUANTA.Q_RES(CHIPS)':
 C_PATH='@t6g_mb_lib.t6g(sch_1):page358_i186@pure_quanta.q_res(chips)',
 P_PATH='@t6g_mb_lib.t6g(sch_1):page234_i186@pure_quanta.q_res(chips)',
 PATH='I186',
 DRAWING='@T6G_MB_LIB.T6G(SCH_1):PAGE358',
 WATTAGE='1/16W',
 TOLERANCE='1%',
 MATERIAL='CHIP',
 PHYS_PAGE='234',
 XY='(-4150,2950)',
 ROT='0',
 VER='2',
 PACK_TYPE='0402LF',
 LOCATION='R3663',
 CDS_LIB='pure_quanta',
 CDS_PART_NAME='Q_RES_0402LF-10K,1%,1/16W,CHIP,CS31002FB08',
 ROOM='USB2 BOM1',
 PART_NUMBER='CS31002FB08',
 VALUE='10K',
 PRIM_FILE='./archive_libs/logical/q_res/chips/chips.prt';

PART_NAME
 R3664 'Q_RES_0402LF-10K,1%,1/16W,EMPTY,CS31002FB08':
 ROOM='USB2 BOM1';

SECTION_NUMBER 1
 '@T6G_MB_LIB.T6G(SCH_1):PAGE358_I187@PURE_QUANTA.Q_RES(CHIPS)':
 C_PATH='@t6g_mb_lib.t6g(sch_1):page358_i187@pure_quanta.q_res(chips)',
 P_PATH='@t6g_mb_lib.t6g(sch_1):page234_i187@pure_quanta.q_res(chips)',
 PATH='I187',
 DRAWING='@T6G_MB_LIB.T6G(SCH_1):PAGE358',
 WATTAGE='1/16W',
 TOLERANCE='1%',
 MATERIAL='EMPTY',
 PHYS_PAGE='234',
 XY='(-4150,2350)',
 ROT='0',
 VER='2',
 PACK_TYPE='0402LF',
 LOCATION='R3664',
 CDS_LIB='pure_quanta',
 CDS_PART_NAME='Q_RES_0402LF-10K,1%,1/16W,EMPTY,CS31002FB08',
 ROOM='USB2 BOM1',
 PART_NUMBER='CS31002FB08',
 VALUE='10K',
 PRIM_FILE='./archive_libs/logical/q_res/chips/chips.prt';

PART_NAME
 R3665 'Q_RES_0402LF-100K,1%,1/16W,CHIP,CS41002FB09':
 ROOM='USB2 BOM1';

SECTION_NUMBER 1
 '@T6G_MB_LIB.T6G(SCH_1):PAGE358_I182@PURE_QUANTA.Q_RES(CHIPS)':
 C_PATH='@t6g_mb_lib.t6g(sch_1):page358_i182@pure_quanta.q_res(chips)',
 P_PATH='@t6g_mb_lib.t6g(sch_1):page234_i182@pure_quanta.q_res(chips)',
 PATH='I182',
 DRAWING='@T6G_MB_LIB.T6G(SCH_1):PAGE358',
 WATTAGE='1/16W',
 TOLERANCE='1%',
 MATERIAL='CHIP',
 PHYS_PAGE='234',
 XY='(-750,3075)',
 ROT='0',
 VER='2',
 PACK_TYPE='0402LF',
 LOCATION='R3665',
 CDS_LIB='pure_quanta',
 CDS_PART_NAME='Q_RES_0402LF-100K,1%,1/16W,CHIP,CS41002FB09',
 ROOM='USB2 BOM1',
 PART_NUMBER='CS41002FB09',
 VALUE='100K',
 PRIM_FILE='./archive_libs/logical/q_res/chips/chips.prt';

PART_NAME
 R3666 'Q_RES_0402LF-0,5%,1/16W,CHIP,CS00002JB13':
 ROOM='USB2 BOM1';

SECTION_NUMBER 1
 '@T6G_MB_LIB.T6G(SCH_1):PAGE358_I199@PURE_QUANTA.Q_RES(CHIPS)':
 C_PATH='@t6g_mb_lib.t6g(sch_1):page358_i199@pure_quanta.q_res(chips)',
 P_PATH='@t6g_mb_lib.t6g(sch_1):page234_i199@pure_quanta.q_res(chips)',
 PATH='I199',
 DRAWING='@T6G_MB_LIB.T6G(SCH_1):PAGE358',
 WATTAGE='1/16W',
 TOLERANCE='5%',
 MATERIAL='CHIP',
 PHYS_PAGE='234',
 XY='(1375,4275)',
 ROT='0',
 VER='1',
 PACK_TYPE='0402LF',
 LOCATION='R3666',
 CDS_LIB='pure_quanta',
 CDS_PART_NAME='Q_RES_0402LF-0,5%,1/16W,CHIP,CS00002JB13',
 ROOM='USB2 BOM1',
 PART_NUMBER='CS00002JB13',
 VALUE='0',
 PRIM_FILE='./archive_libs/logical/q_res/chips/chips.prt';

PART_NAME
 R3667 'Q_RES_0402LF-1K,1%,1/16W,EMPTY,CS21002FB06':
 ROOM='ADC_TI_BOM1';

SECTION_NUMBER 1
 '@T6G_MB_LIB.T6G(SCH_1):PAGE369_I66@PURE_QUANTA.Q_RES(CHIPS)':
 C_PATH='@t6g_mb_lib.t6g(sch_1):page369_i66@pure_quanta.q_res(chips)',
 P_PATH='@t6g_mb_lib.t6g(sch_1):page257_i66@pure_quanta.q_res(chips)',
 PATH='I66',
 DRAWING='@T6G_MB_LIB.T6G(SCH_1):PAGE369',
 WATTAGE='1/16W',
 TOLERANCE='1%',
 MATERIAL='EMPTY',
 PHYS_PAGE='257',
 XY='(-4550,1325)',
 ROT='0',
 VER='2',
 PACK_TYPE='0402LF',
 LOCATION='R3667',
 CDS_LIB='pure_quanta',
 CDS_PART_NAME='Q_RES_0402LF-1K,1%,1/16W,EMPTY,CS21002FB06',
 ROOM='ADC_TI_BOM1',
 PART_NUMBER='CS21002FB06',
 VALUE='1K',
 PRIM_FILE='./archive_libs/logical/q_res/chips/chips.prt';

PART_NAME
 R3668 'Q_RES_0402LF-1K,1%,1/16W,CHIP,CS21002FB06':
 ROOM='ADC_TI_BOM1';

SECTION_NUMBER 1
 '@T6G_MB_LIB.T6G(SCH_1):PAGE369_I38@PURE_QUANTA.Q_RES(CHIPS)':
 C_PATH='@t6g_mb_lib.t6g(sch_1):page369_i38@pure_quanta.q_res(chips)',
 P_PATH='@t6g_mb_lib.t6g(sch_1):page257_i38@pure_quanta.q_res(chips)',
 PATH='I38',
 DRAWING='@T6G_MB_LIB.T6G(SCH_1):PAGE369',
 WATTAGE='1/16W',
 TOLERANCE='1%',
 MATERIAL='CHIP',
 PHYS_PAGE='257',
 XY='(-4550,725)',
 ROT='0',
 VER='2',
 PACK_TYPE='0402LF',
 LOCATION='R3668',
 CDS_LIB='pure_quanta',
 CDS_PART_NAME='Q_RES_0402LF-1K,1%,1/16W,CHIP,CS21002FB06',
 ROOM='ADC_TI_BOM1',
 PART_NUMBER='CS21002FB06',
 VALUE='1K',
 PRIM_FILE='./archive_libs/logical/q_res/chips/chips.prt';

PART_NAME
 R3669 'Q_RES_0402LF-1K,1%,1/16W,EMPTY,CS21002FB06':
 ROOM='ADC_TI_BOM1';

SECTION_NUMBER 1
 '@T6G_MB_LIB.T6G(SCH_1):PAGE369_I68@PURE_QUANTA.Q_RES(CHIPS)':
 C_PATH='@t6g_mb_lib.t6g(sch_1):page369_i68@pure_quanta.q_res(chips)',
 P_PATH='@t6g_mb_lib.t6g(sch_1):page257_i68@pure_quanta.q_res(chips)',
 PATH='I68',
 DRAWING='@T6G_MB_LIB.T6G(SCH_1):PAGE369',
 WATTAGE='1/16W',
 TOLERANCE='1%',
 MATERIAL='EMPTY',
 PHYS_PAGE='257',
 XY='(-4300,1325)',
 ROT='0',
 VER='2',
 PACK_TYPE='0402LF',
 LOCATION='R3669',
 CDS_LIB='pure_quanta',
 CDS_PART_NAME='Q_RES_0402LF-1K,1%,1/16W,EMPTY,CS21002FB06',
 ROOM='ADC_TI_BOM1',
 PART_NUMBER='CS21002FB06',
 VALUE='1K',
 PRIM_FILE='./archive_libs/logical/q_res/chips/chips.prt';

PART_NAME
 R3670 'Q_RES_0402LF-1K,1%,1/16W,CHIP,CS21002FB06':
 ROOM='ADC_TI_BOM1';

SECTION_NUMBER 1
 '@T6G_MB_LIB.T6G(SCH_1):PAGE369_I40@PURE_QUANTA.Q_RES(CHIPS)':
 C_PATH='@t6g_mb_lib.t6g(sch_1):page369_i40@pure_quanta.q_res(chips)',
 P_PATH='@t6g_mb_lib.t6g(sch_1):page257_i40@pure_quanta.q_res(chips)',
 PATH='I40',
 DRAWING='@T6G_MB_LIB.T6G(SCH_1):PAGE369',
 WATTAGE='1/16W',
 TOLERANCE='1%',
 MATERIAL='CHIP',
 PHYS_PAGE='257',
 XY='(-4300,725)',
 ROT='0',
 VER='2',
 PACK_TYPE='0402LF',
 LOCATION='R3670',
 CDS_LIB='pure_quanta',
 CDS_PART_NAME='Q_RES_0402LF-1K,1%,1/16W,CHIP,CS21002FB06',
 ROOM='ADC_TI_BOM1',
 PART_NUMBER='CS21002FB06',
 VALUE='1K',
 PRIM_FILE='./archive_libs/logical/q_res/chips/chips.prt';

PART_NAME
 R3671 'Q_RES_0402LF-0,5%,1/16W,CHIP,CS00002JB13':
 ROOM='ADC_TI_BOM1';

SECTION_NUMBER 1
 '@T6G_MB_LIB.T6G(SCH_1):PAGE369_I149@PURE_QUANTA.Q_RES(CHIPS)':
 C_PATH='@t6g_mb_lib.t6g(sch_1):page369_i149@pure_quanta.q_res(chips)',
 P_PATH='@t6g_mb_lib.t6g(sch_1):page257_i149@pure_quanta.q_res(chips)',
 PATH='I149',
 DRAWING='@T6G_MB_LIB.T6G(SCH_1):PAGE369',
 WATTAGE='1/16W',
 TOLERANCE='5%',
 MATERIAL='CHIP',
 PHYS_PAGE='257',
 XY='(-1550,1050)',
 ROT='0',
 VER='1',
 PACK_TYPE='0402LF',
 LOCATION='R3671',
 CDS_LIB='pure_quanta',
 CDS_PART_NAME='Q_RES_0402LF-0,5%,1/16W,CHIP,CS00002JB13',
 ROOM='ADC_TI_BOM1',
 PART_NUMBER='CS00002JB13',
 VALUE='0',
 PRIM_FILE='./archive_libs/logical/q_res/chips/chips.prt';

PART_NAME
 R3672 'Q_RES_0402LF-0,5%,1/16W,CHIP,CS00002JB13':
 ROOM='ADC_TI_BOM1';

SECTION_NUMBER 1
 '@T6G_MB_LIB.T6G(SCH_1):PAGE369_I150@PURE_QUANTA.Q_RES(CHIPS)':
 C_PATH='@t6g_mb_lib.t6g(sch_1):page369_i150@pure_quanta.q_res(chips)',
 P_PATH='@t6g_mb_lib.t6g(sch_1):page257_i150@pure_quanta.q_res(chips)',
 PATH='I150',
 DRAWING='@T6G_MB_LIB.T6G(SCH_1):PAGE369',
 WATTAGE='1/16W',
 TOLERANCE='5%',
 MATERIAL='CHIP',
 PHYS_PAGE='257',
 XY='(-1550,1000)',
 ROT='0',
 VER='1',
 PACK_TYPE='0402LF',
 LOCATION='R3672',
 CDS_LIB='pure_quanta',
 CDS_PART_NAME='Q_RES_0402LF-0,5%,1/16W,CHIP,CS00002JB13',
 ROOM='ADC_TI_BOM1',
 PART_NUMBER='CS00002JB13',
 VALUE='0',
 PRIM_FILE='./archive_libs/logical/q_res/chips/chips.prt';

PART_NAME
 R3679 'Q_RES_0402LF-0,5%,1/16W,EMPTY,CS00002JB13':
 ROOM='ADC_MAM_BOM2';

SECTION_NUMBER 1
 '@T6G_MB_LIB.T6G(SCH_1):PAGE369_I10@PURE_QUANTA.Q_RES(CHIPS)':
 C_PATH='@t6g_mb_lib.t6g(sch_1):page369_i10@pure_quanta.q_res(chips)',
 P_PATH='@t6g_mb_lib.t6g(sch_1):page257_i10@pure_quanta.q_res(chips)',
 PATH='I10',
 DRAWING='@T6G_MB_LIB.T6G(SCH_1):PAGE369',
 WATTAGE='1/16W',
 TOLERANCE='5%',
 MATERIAL='EMPTY',
 PHYS_PAGE='257',
 XY='(-8100,2200)',
 ROT='0',
 VER='1',
 PACK_TYPE='0402LF',
 LOCATION='R3679',
 CDS_LIB='pure_quanta',
 CDS_PART_NAME='Q_RES_0402LF-0,5%,1/16W,EMPTY,CS00002JB13',
 ROOM='ADC_MAM_BOM2',
 PART_NUMBER='CS00002JB13',
 VALUE='0',
 PRIM_FILE='./archive_libs/logical/q_res/chips/chips.prt';

PART_NAME
 R3680 'Q_RES_0402LF-0,5%,1/16W,CHIP,CS00002JB13':
 ROOM='ADC_TI_BOM1';

SECTION_NUMBER 1
 '@T6G_MB_LIB.T6G(SCH_1):PAGE369_I9@PURE_QUANTA.Q_RES(CHIPS)':
 C_PATH='@t6g_mb_lib.t6g(sch_1):page369_i9@pure_quanta.q_res(chips)',
 P_PATH='@t6g_mb_lib.t6g(sch_1):page257_i9@pure_quanta.q_res(chips)',
 PATH='I9',
 DRAWING='@T6G_MB_LIB.T6G(SCH_1):PAGE369',
 WATTAGE='1/16W',
 TOLERANCE='5%',
 MATERIAL='CHIP',
 PHYS_PAGE='257',
 XY='(-8100,2050)',
 ROT='0',
 VER='1',
 PACK_TYPE='0402LF',
 LOCATION='R3680',
 CDS_LIB='pure_quanta',
 CDS_PART_NAME='Q_RES_0402LF-0,5%,1/16W,CHIP,CS00002JB13',
 ROOM='ADC_TI_BOM1',
 PART_NUMBER='CS00002JB13',
 VALUE='0',
 PRIM_FILE='./archive_libs/logical/q_res/chips/chips.prt';

PART_NAME
 R3681 'Q_RES_0402LF-0,5%,1/16W,EMPTY,CS00002JB13':
 ROOM='ADC_MAM_BOM2';

SECTION_NUMBER 1
 '@T6G_MB_LIB.T6G(SCH_1):PAGE369_I30@PURE_QUANTA.Q_RES(CHIPS)':
 C_PATH='@t6g_mb_lib.t6g(sch_1):page369_i30@pure_quanta.q_res(chips)',
 P_PATH='@t6g_mb_lib.t6g(sch_1):page257_i30@pure_quanta.q_res(chips)',
 PATH='I30',
 DRAWING='@T6G_MB_LIB.T6G(SCH_1):PAGE369',
 WATTAGE='1/16W',
 TOLERANCE='5%',
 MATERIAL='EMPTY',
 PHYS_PAGE='257',
 XY='(-8200,5975)',
 ROT='0',
 VER='1',
 PACK_TYPE='0402LF',
 LOCATION='R3681',
 CDS_LIB='pure_quanta',
 CDS_PART_NAME='Q_RES_0402LF-0,5%,1/16W,EMPTY,CS00002JB13',
 ROOM='ADC_MAM_BOM2',
 PART_NUMBER='CS00002JB13',
 VALUE='0',
 PRIM_FILE='./archive_libs/logical/q_res/chips/chips.prt';

PART_NAME
 R3682 'Q_RES_0402LF-0,5%,1/16W,CHIP,CS00002JB13':
 ROOM='ADC_TI_BOM1';

SECTION_NUMBER 1
 '@T6G_MB_LIB.T6G(SCH_1):PAGE369_I27@PURE_QUANTA.Q_RES(CHIPS)':
 C_PATH='@t6g_mb_lib.t6g(sch_1):page369_i27@pure_quanta.q_res(chips)',
 P_PATH='@t6g_mb_lib.t6g(sch_1):page257_i27@pure_quanta.q_res(chips)',
 PATH='I27',
 DRAWING='@T6G_MB_LIB.T6G(SCH_1):PAGE369',
 WATTAGE='1/16W',
 TOLERANCE='5%',
 MATERIAL='CHIP',
 PHYS_PAGE='257',
 XY='(-8200,5825)',
 ROT='0',
 VER='1',
 PACK_TYPE='0402LF',
 LOCATION='R3682',
 CDS_LIB='pure_quanta',
 CDS_PART_NAME='Q_RES_0402LF-0,5%,1/16W,CHIP,CS00002JB13',
 ROOM='ADC_TI_BOM1',
 PART_NUMBER='CS00002JB13',
 VALUE='0',
 PRIM_FILE='./archive_libs/logical/q_res/chips/chips.prt';

PART_NAME
 R3683 'Q_RES_0402LF-0,5%,1/16W,EMPTY,CS00002JB13':
 ROOM='ADC_MAM_BOM2';

SECTION_NUMBER 1
 '@T6G_MB_LIB.T6G(SCH_1):PAGE369_I23@PURE_QUANTA.Q_RES(CHIPS)':
 C_PATH='@t6g_mb_lib.t6g(sch_1):page369_i23@pure_quanta.q_res(chips)',
 P_PATH='@t6g_mb_lib.t6g(sch_1):page257_i23@pure_quanta.q_res(chips)',
 PATH='I23',
 DRAWING='@T6G_MB_LIB.T6G(SCH_1):PAGE369',
 WATTAGE='1/16W',
 TOLERANCE='5%',
 MATERIAL='EMPTY',
 PHYS_PAGE='257',
 XY='(-8275,4650)',
 ROT='0',
 VER='1',
 PACK_TYPE='0402LF',
 LOCATION='R3683',
 CDS_LIB='pure_quanta',
 CDS_PART_NAME='Q_RES_0402LF-0,5%,1/16W,EMPTY,CS00002JB13',
 ROOM='ADC_MAM_BOM2',
 PART_NUMBER='CS00002JB13',
 VALUE='0',
 PRIM_FILE='./archive_libs/logical/q_res/chips/chips.prt';

PART_NAME
 R3684 'Q_RES_0402LF-0,5%,1/16W,CHIP,CS00002JB13':
 ROOM='ADC_TI_BOM1';

SECTION_NUMBER 1
 '@T6G_MB_LIB.T6G(SCH_1):PAGE369_I22@PURE_QUANTA.Q_RES(CHIPS)':
 C_PATH='@t6g_mb_lib.t6g(sch_1):page369_i22@pure_quanta.q_res(chips)',
 P_PATH='@t6g_mb_lib.t6g(sch_1):page257_i22@pure_quanta.q_res(chips)',
 PATH='I22',
 DRAWING='@T6G_MB_LIB.T6G(SCH_1):PAGE369',
 WATTAGE='1/16W',
 TOLERANCE='5%',
 MATERIAL='CHIP',
 PHYS_PAGE='257',
 XY='(-8275,4500)',
 ROT='0',
 VER='1',
 PACK_TYPE='0402LF',
 LOCATION='R3684',
 CDS_LIB='pure_quanta',
 CDS_PART_NAME='Q_RES_0402LF-0,5%,1/16W,CHIP,CS00002JB13',
 ROOM='ADC_TI_BOM1',
 PART_NUMBER='CS00002JB13',
 VALUE='0',
 PRIM_FILE='./archive_libs/logical/q_res/chips/chips.prt';

PART_NAME
 R3685 'Q_RES_0402LF-0,5%,1/16W,EMPTY,CS00002JB13':
 ROOM='ADC_MAM_BOM2';

SECTION_NUMBER 1
 '@T6G_MB_LIB.T6G(SCH_1):PAGE369_I18@PURE_QUANTA.Q_RES(CHIPS)':
 C_PATH='@t6g_mb_lib.t6g(sch_1):page369_i18@pure_quanta.q_res(chips)',
 P_PATH='@t6g_mb_lib.t6g(sch_1):page257_i18@pure_quanta.q_res(chips)',
 PATH='I18',
 DRAWING='@T6G_MB_LIB.T6G(SCH_1):PAGE369',
 WATTAGE='1/16W',
 TOLERANCE='5%',
 MATERIAL='EMPTY',
 PHYS_PAGE='257',
 XY='(-8275,3500)',
 ROT='0',
 VER='1',
 PACK_TYPE='0402LF',
 LOCATION='R3685',
 CDS_LIB='pure_quanta',
 CDS_PART_NAME='Q_RES_0402LF-0,5%,1/16W,EMPTY,CS00002JB13',
 ROOM='ADC_MAM_BOM2',
 PART_NUMBER='CS00002JB13',
 VALUE='0',
 PRIM_FILE='./archive_libs/logical/q_res/chips/chips.prt';

PART_NAME
 R3686 'Q_RES_0402LF-0,5%,1/16W,CHIP,CS00002JB13':
 ROOM='ADC_TI_BOM1';

SECTION_NUMBER 1
 '@T6G_MB_LIB.T6G(SCH_1):PAGE369_I16@PURE_QUANTA.Q_RES(CHIPS)':
 C_PATH='@t6g_mb_lib.t6g(sch_1):page369_i16@pure_quanta.q_res(chips)',
 P_PATH='@t6g_mb_lib.t6g(sch_1):page257_i16@pure_quanta.q_res(chips)',
 PATH='I16',
 DRAWING='@T6G_MB_LIB.T6G(SCH_1):PAGE369',
 WATTAGE='1/16W',
 TOLERANCE='5%',
 MATERIAL='CHIP',
 PHYS_PAGE='257',
 XY='(-8275,3350)',
 ROT='0',
 VER='1',
 PACK_TYPE='0402LF',
 LOCATION='R3686',
 CDS_LIB='pure_quanta',
 CDS_PART_NAME='Q_RES_0402LF-0,5%,1/16W,CHIP,CS00002JB13',
 ROOM='ADC_TI_BOM1',
 PART_NUMBER='CS00002JB13',
 VALUE='0',
 PRIM_FILE='./archive_libs/logical/q_res/chips/chips.prt';

PART_NAME
 R3687 'Q_RES_0402LF-0,5%,1/16W,EMPTY,CS00002JB13':
 ROOM='ADC_MAM_BOM2';

SECTION_NUMBER 1
 '@T6G_MB_LIB.T6G(SCH_1):PAGE369_I42@PURE_QUANTA.Q_RES(CHIPS)':
 C_PATH='@t6g_mb_lib.t6g(sch_1):page369_i42@pure_quanta.q_res(chips)',
 P_PATH='@t6g_mb_lib.t6g(sch_1):page257_i42@pure_quanta.q_res(chips)',
 PATH='I42',
 DRAWING='@T6G_MB_LIB.T6G(SCH_1):PAGE369',
 WATTAGE='1/16W',
 TOLERANCE='5%',
 MATERIAL='EMPTY',
 PHYS_PAGE='257',
 XY='(-7425,1300)',
 ROT='0',
 VER='1',
 PACK_TYPE='0402LF',
 LOCATION='R3687',
 CDS_LIB='pure_quanta',
 CDS_PART_NAME='Q_RES_0402LF-0,5%,1/16W,EMPTY,CS00002JB13',
 ROOM='ADC_MAM_BOM2',
 PART_NUMBER='CS00002JB13',
 VALUE='0',
 PRIM_FILE='./archive_libs/logical/q_res/chips/chips.prt';

PART_NAME
 R3688 'Q_RES_0402LF-0,5%,1/16W,CHIP,CS00002JB13':
 ROOM='ADC_TI_BOM1';

SECTION_NUMBER 1
 '@T6G_MB_LIB.T6G(SCH_1):PAGE369_I41@PURE_QUANTA.Q_RES(CHIPS)':
 C_PATH='@t6g_mb_lib.t6g(sch_1):page369_i41@pure_quanta.q_res(chips)',
 P_PATH='@t6g_mb_lib.t6g(sch_1):page257_i41@pure_quanta.q_res(chips)',
 PATH='I41',
 DRAWING='@T6G_MB_LIB.T6G(SCH_1):PAGE369',
 WATTAGE='1/16W',
 TOLERANCE='5%',
 MATERIAL='CHIP',
 PHYS_PAGE='257',
 XY='(-7425,1150)',
 ROT='0',
 VER='1',
 PACK_TYPE='0402LF',
 LOCATION='R3688',
 CDS_LIB='pure_quanta',
 CDS_PART_NAME='Q_RES_0402LF-0,5%,1/16W,CHIP,CS00002JB13',
 ROOM='ADC_TI_BOM1',
 PART_NUMBER='CS00002JB13',
 VALUE='0',
 PRIM_FILE='./archive_libs/logical/q_res/chips/chips.prt';

PART_NAME
 R3689 'Q_RES_0402LF-4.7K,1%,1/16W,EMPTY,CS24702FB06':
 ROOM='ADC_TI_BOM1';

SECTION_NUMBER 1
 '@T6G_MB_LIB.T6G(SCH_1):PAGE369_I131@PURE_QUANTA.Q_RES(CHIPS)':
 C_PATH='@t6g_mb_lib.t6g(sch_1):page369_i131@pure_quanta.q_res(chips)',
 P_PATH='@t6g_mb_lib.t6g(sch_1):page257_i131@pure_quanta.q_res(chips)',
 PATH='I131',
 DRAWING='@T6G_MB_LIB.T6G(SCH_1):PAGE369',
 WATTAGE='1/16W',
 TOLERANCE='1%',
 MATERIAL='EMPTY',
 PHYS_PAGE='257',
 XY='(-3475,2500)',
 ROT='0',
 VER='2',
 PACK_TYPE='0402LF',
 LOCATION='R3689',
 CDS_LIB='pure_quanta',
 CDS_PART_NAME='Q_RES_0402LF-4.7K,1%,1/16W,EMPTY,CS24702FB06',
 ROOM='ADC_TI_BOM1',
 PART_NUMBER='CS24702FB06',
 VALUE='4.7K',
 PRIM_FILE='./archive_libs/logical/q_res/chips/chips.prt';

PART_NAME
 R3690 'Q_RES_0402LF-4.7K,1%,1/16W,EMPTY,CS24702FB06':
 ROOM='ADC_TI_BOM1';

SECTION_NUMBER 1
 '@T6G_MB_LIB.T6G(SCH_1):PAGE369_I130@PURE_QUANTA.Q_RES(CHIPS)':
 C_PATH='@t6g_mb_lib.t6g(sch_1):page369_i130@pure_quanta.q_res(chips)',
 P_PATH='@t6g_mb_lib.t6g(sch_1):page257_i130@pure_quanta.q_res(chips)',
 PATH='I130',
 DRAWING='@T6G_MB_LIB.T6G(SCH_1):PAGE369',
 WATTAGE='1/16W',
 TOLERANCE='1%',
 MATERIAL='EMPTY',
 PHYS_PAGE='257',
 XY='(-3475,2000)',
 ROT='0',
 VER='2',
 PACK_TYPE='0402LF',
 LOCATION='R3690',
 CDS_LIB='pure_quanta',
 CDS_PART_NAME='Q_RES_0402LF-4.7K,1%,1/16W,EMPTY,CS24702FB06',
 ROOM='ADC_TI_BOM1',
 PART_NUMBER='CS24702FB06',
 VALUE='4.7K',
 PRIM_FILE='./archive_libs/logical/q_res/chips/chips.prt';

PART_NAME
 R3703 'Q_RES_0402LF-10K,1%,1/16W,EMPTY,CS31002FB08':;

SECTION_NUMBER 1
 '@T6G_MB_LIB.T6G(SCH_1):PAGE251_I7@PURE_QUANTA.Q_RES(CHIPS)':
 C_PATH='@t6g_mb_lib.t6g(sch_1):page251_i7@pure_quanta.q_res(chips)',
 P_PATH='@t6g_mb_lib.t6g(sch_1):page252_i7@pure_quanta.q_res(chips)',
 PATH='I7',
 DRAWING='@T6G_MB_LIB.T6G(SCH_1):PAGE251',
 WATTAGE='1/16W',
 TOLERANCE='1%',
 MATERIAL='EMPTY',
 PHYS_PAGE='252',
 XY='(-6575,2850)',
 ROT='0',
 VER='2',
 PACK_TYPE='0402LF',
 LOCATION='R3703',
 CDS_LIB='pure_quanta',
 CDS_PART_NAME='Q_RES_0402LF-10K,1%,1/16W,EMPTY,CS31002FB08',
 PART_NUMBER='CS31002FB08',
 VALUE='10K',
 PRIM_FILE='./archive_libs/logical/q_res/chips/chips.prt';

PART_NAME
 R3704 'Q_RES_0402LF-1K,1%,1/16W,CHIP,CS21002FB06':;

SECTION_NUMBER 1
 '@T6G_MB_LIB.T6G(SCH_1):PAGE251_I1@PURE_QUANTA.Q_RES(CHIPS)':
 C_PATH='@t6g_mb_lib.t6g(sch_1):page251_i1@pure_quanta.q_res(chips)',
 P_PATH='@t6g_mb_lib.t6g(sch_1):page252_i1@pure_quanta.q_res(chips)',
 PATH='I1',
 DRAWING='@T6G_MB_LIB.T6G(SCH_1):PAGE251',
 WATTAGE='1/16W',
 TOLERANCE='1%',
 MATERIAL='CHIP',
 PHYS_PAGE='252',
 XY='(-6575,2200)',
 ROT='0',
 VER='2',
 PACK_TYPE='0402LF',
 LOCATION='R3704',
 CDS_LIB='pure_quanta',
 CDS_PART_NAME='Q_RES_0402LF-1K,1%,1/16W,CHIP,CS21002FB06',
 PART_NUMBER='CS21002FB06',
 VALUE='1K',
 PRIM_FILE='./archive_libs/logical/q_res/chips/chips.prt';

PART_NAME
 R3705 'Q_RES_0402LF-10K,1%,1/16W,EMPTY,CS31002FB08':;

SECTION_NUMBER 1
 '@T6G_MB_LIB.T6G(SCH_1):PAGE251_I27@PURE_QUANTA.Q_RES(CHIPS)':
 C_PATH='@t6g_mb_lib.t6g(sch_1):page251_i27@pure_quanta.q_res(chips)',
 P_PATH='@t6g_mb_lib.t6g(sch_1):page252_i27@pure_quanta.q_res(chips)',
 PATH='I27',
 DRAWING='@T6G_MB_LIB.T6G(SCH_1):PAGE251',
 WATTAGE='1/16W',
 TOLERANCE='1%',
 MATERIAL='EMPTY',
 PHYS_PAGE='252',
 XY='(-6950,4750)',
 ROT='2',
 VER='2',
 PACK_TYPE='0402LF',
 LOCATION='R3705',
 CDS_LIB='pure_quanta',
 CDS_PART_NAME='Q_RES_0402LF-10K,1%,1/16W,EMPTY,CS31002FB08',
 PART_NUMBER='CS31002FB08',
 VALUE='10K',
 PRIM_FILE='./archive_libs/logical/q_res/chips/chips.prt';

PART_NAME
 R3706 'Q_RES_0402LF-10K,1%,1/16W,EMPTY,CS31002FB08':;

SECTION_NUMBER 1
 '@T6G_MB_LIB.T6G(SCH_1):PAGE251_I8@PURE_QUANTA.Q_RES(CHIPS)':
 C_PATH='@t6g_mb_lib.t6g(sch_1):page251_i8@pure_quanta.q_res(chips)',
 P_PATH='@t6g_mb_lib.t6g(sch_1):page252_i8@pure_quanta.q_res(chips)',
 PATH='I8',
 DRAWING='@T6G_MB_LIB.T6G(SCH_1):PAGE251',
 WATTAGE='1/16W',
 TOLERANCE='1%',
 MATERIAL='EMPTY',
 PHYS_PAGE='252',
 XY='(-6300,2850)',
 ROT='0',
 VER='2',
 PACK_TYPE='0402LF',
 LOCATION='R3706',
 CDS_LIB='pure_quanta',
 CDS_PART_NAME='Q_RES_0402LF-10K,1%,1/16W,EMPTY,CS31002FB08',
 PART_NUMBER='CS31002FB08',
 VALUE='10K',
 PRIM_FILE='./archive_libs/logical/q_res/chips/chips.prt';

PART_NAME
 R3707 'Q_RES_0402LF-1K,1%,1/16W,CHIP,CS21002FB06':;

SECTION_NUMBER 1
 '@T6G_MB_LIB.T6G(SCH_1):PAGE251_I4@PURE_QUANTA.Q_RES(CHIPS)':
 C_PATH='@t6g_mb_lib.t6g(sch_1):page251_i4@pure_quanta.q_res(chips)',
 P_PATH='@t6g_mb_lib.t6g(sch_1):page252_i4@pure_quanta.q_res(chips)',
 PATH='I4',
 DRAWING='@T6G_MB_LIB.T6G(SCH_1):PAGE251',
 WATTAGE='1/16W',
 TOLERANCE='1%',
 MATERIAL='CHIP',
 PHYS_PAGE='252',
 XY='(-6300,2200)',
 ROT='0',
 VER='2',
 PACK_TYPE='0402LF',
 LOCATION='R3707',
 CDS_LIB='pure_quanta',
 CDS_PART_NAME='Q_RES_0402LF-1K,1%,1/16W,CHIP,CS21002FB06',
 PART_NUMBER='CS21002FB06',
 VALUE='1K',
 PRIM_FILE='./archive_libs/logical/q_res/chips/chips.prt';

PART_NAME
 R3708 'Q_RES_0402LF-10K,1%,1/16W,EMPTY,CS31002FB08':;

SECTION_NUMBER 1
 '@T6G_MB_LIB.T6G(SCH_1):PAGE251_I10@PURE_QUANTA.Q_RES(CHIPS)':
 C_PATH='@t6g_mb_lib.t6g(sch_1):page251_i10@pure_quanta.q_res(chips)',
 P_PATH='@t6g_mb_lib.t6g(sch_1):page252_i10@pure_quanta.q_res(chips)',
 PATH='I10',
 DRAWING='@T6G_MB_LIB.T6G(SCH_1):PAGE251',
 WATTAGE='1/16W',
 TOLERANCE='1%',
 MATERIAL='EMPTY',
 PHYS_PAGE='252',
 XY='(-6025,2850)',
 ROT='0',
 VER='2',
 PACK_TYPE='0402LF',
 LOCATION='R3708',
 CDS_LIB='pure_quanta',
 CDS_PART_NAME='Q_RES_0402LF-10K,1%,1/16W,EMPTY,CS31002FB08',
 PART_NUMBER='CS31002FB08',
 VALUE='10K',
 PRIM_FILE='./archive_libs/logical/q_res/chips/chips.prt';

PART_NAME
 R3709 'Q_RES_0402LF-1K,1%,1/16W,CHIP,CS21002FB06':;

SECTION_NUMBER 1
 '@T6G_MB_LIB.T6G(SCH_1):PAGE251_I6@PURE_QUANTA.Q_RES(CHIPS)':
 C_PATH='@t6g_mb_lib.t6g(sch_1):page251_i6@pure_quanta.q_res(chips)',
 P_PATH='@t6g_mb_lib.t6g(sch_1):page252_i6@pure_quanta.q_res(chips)',
 PATH='I6',
 DRAWING='@T6G_MB_LIB.T6G(SCH_1):PAGE251',
 WATTAGE='1/16W',
 TOLERANCE='1%',
 MATERIAL='CHIP',
 PHYS_PAGE='252',
 XY='(-6025,2200)',
 ROT='0',
 VER='2',
 PACK_TYPE='0402LF',
 LOCATION='R3709',
 CDS_LIB='pure_quanta',
 CDS_PART_NAME='Q_RES_0402LF-1K,1%,1/16W,CHIP,CS21002FB06',
 PART_NUMBER='CS21002FB06',
 VALUE='1K',
 PRIM_FILE='./archive_libs/logical/q_res/chips/chips.prt';

PART_NAME
 R3710 'Q_RES_0402LF-0,5%,1/16W,CHIP,CS00002JB13':;

SECTION_NUMBER 1
 '@T6G_MB_LIB.T6G(SCH_1):PAGE251_I29@PURE_QUANTA.Q_RES(CHIPS)':
 C_PATH='@t6g_mb_lib.t6g(sch_1):page251_i29@pure_quanta.q_res(chips)',
 P_PATH='@t6g_mb_lib.t6g(sch_1):page252_i29@pure_quanta.q_res(chips)',
 PATH='I29',
 DRAWING='@T6G_MB_LIB.T6G(SCH_1):PAGE251',
 WATTAGE='1/16W',
 TOLERANCE='5%',
 MATERIAL='CHIP',
 PHYS_PAGE='252',
 XY='(-5850,4400)',
 ROT='0',
 VER='1',
 PACK_TYPE='0402LF',
 LOCATION='R3710',
 CDS_LIB='pure_quanta',
 CDS_PART_NAME='Q_RES_0402LF-0,5%,1/16W,CHIP,CS00002JB13',
 PART_NUMBER='CS00002JB13',
 VALUE='0',
 PRIM_FILE='./archive_libs/logical/q_res/chips/chips.prt';

PART_NAME
 R3711 'Q_RES_0402LF-33.2,1%,1/16W,CHIP,CS03322FB03':;

SECTION_NUMBER 1
 '@T6G_MB_LIB.T6G(SCH_1):PAGE251_I69@PURE_QUANTA.Q_RES(CHIPS)':
 C_PATH='@t6g_mb_lib.t6g(sch_1):page251_i69@pure_quanta.q_res(chips)',
 P_PATH='@t6g_mb_lib.t6g(sch_1):page252_i69@pure_quanta.q_res(chips)',
 PATH='I69',
 DRAWING='@T6G_MB_LIB.T6G(SCH_1):PAGE251',
 WATTAGE='1/16W',
 TOLERANCE='1%',
 MATERIAL='CHIP',
 PHYS_PAGE='252',
 XY='(-2825,4500)',
 ROT='2',
 VER='1',
 PACK_TYPE='0402LF',
 LOCATION='R3711',
 CDS_LIB='pure_quanta',
 CDS_PART_NAME='Q_RES_0402LF-33.2,1%,1/16W,CHIP,CS03322FB03',
 PART_NUMBER='CS03322FB03',
 VALUE='33.2',
 PRIM_FILE='./archive_libs/logical/q_res/chips/chips.prt';

PART_NAME
 R3712 'Q_RES_0402LF-33.2,1%,1/16W,CHIP,CS03322FB03':;

SECTION_NUMBER 1
 '@T6G_MB_LIB.T6G(SCH_1):PAGE251_I68@PURE_QUANTA.Q_RES(CHIPS)':
 C_PATH='@t6g_mb_lib.t6g(sch_1):page251_i68@pure_quanta.q_res(chips)',
 P_PATH='@t6g_mb_lib.t6g(sch_1):page252_i68@pure_quanta.q_res(chips)',
 PATH='I68',
 DRAWING='@T6G_MB_LIB.T6G(SCH_1):PAGE251',
 WATTAGE='1/16W',
 TOLERANCE='1%',
 MATERIAL='CHIP',
 PHYS_PAGE='252',
 XY='(-2825,4550)',
 ROT='2',
 VER='1',
 PACK_TYPE='0402LF',
 LOCATION='R3712',
 CDS_LIB='pure_quanta',
 CDS_PART_NAME='Q_RES_0402LF-33.2,1%,1/16W,CHIP,CS03322FB03',
 PART_NUMBER='CS03322FB03',
 VALUE='33.2',
 PRIM_FILE='./archive_libs/logical/q_res/chips/chips.prt';

PART_NAME
 R3713 'Q_RES_0402LF-0,5%,1/16W,CHIP,CS00002JB13':;

SECTION_NUMBER 1
 '@T6G_MB_LIB.T6G(SCH_1):PAGE251_I33@PURE_QUANTA.Q_RES(CHIPS)':
 C_PATH='@t6g_mb_lib.t6g(sch_1):page251_i33@pure_quanta.q_res(chips)',
 P_PATH='@t6g_mb_lib.t6g(sch_1):page252_i33@pure_quanta.q_res(chips)',
 PATH='I33',
 DRAWING='@T6G_MB_LIB.T6G(SCH_1):PAGE251',
 WATTAGE='1/16W',
 TOLERANCE='5%',
 MATERIAL='CHIP',
 PHYS_PAGE='252',
 XY='(-5600,4250)',
 ROT='2',
 VER='1',
 PACK_TYPE='0402LF',
 LOCATION='R3713',
 CDS_LIB='pure_quanta',
 CDS_PART_NAME='Q_RES_0402LF-0,5%,1/16W,CHIP,CS00002JB13',
 PART_NUMBER='CS00002JB13',
 VALUE='0',
 PRIM_FILE='./archive_libs/logical/q_res/chips/chips.prt';

PART_NAME
 R3714 'Q_RES_0402LF-0,5%,1/16W,CHIP,CS00002JB13':;

SECTION_NUMBER 1
 '@T6G_MB_LIB.T6G(SCH_1):PAGE251_I32@PURE_QUANTA.Q_RES(CHIPS)':
 C_PATH='@t6g_mb_lib.t6g(sch_1):page251_i32@pure_quanta.q_res(chips)',
 P_PATH='@t6g_mb_lib.t6g(sch_1):page252_i32@pure_quanta.q_res(chips)',
 PATH='I32',
 DRAWING='@T6G_MB_LIB.T6G(SCH_1):PAGE251',
 WATTAGE='1/16W',
 TOLERANCE='5%',
 MATERIAL='CHIP',
 PHYS_PAGE='252',
 XY='(-5600,4300)',
 ROT='2',
 VER='1',
 PACK_TYPE='0402LF',
 LOCATION='R3714',
 CDS_LIB='pure_quanta',
 CDS_PART_NAME='Q_RES_0402LF-0,5%,1/16W,CHIP,CS00002JB13',
 PART_NUMBER='CS00002JB13',
 VALUE='0',
 PRIM_FILE='./archive_libs/logical/q_res/chips/chips.prt';

PART_NAME
 R3715 'Q_RES_0402LF-0,5%,1/16W,CHIP,CS00002JB13':;

SECTION_NUMBER 1
 '@T6G_MB_LIB.T6G(SCH_1):PAGE251_I31@PURE_QUANTA.Q_RES(CHIPS)':
 C_PATH='@t6g_mb_lib.t6g(sch_1):page251_i31@pure_quanta.q_res(chips)',
 P_PATH='@t6g_mb_lib.t6g(sch_1):page252_i31@pure_quanta.q_res(chips)',
 PATH='I31',
 DRAWING='@T6G_MB_LIB.T6G(SCH_1):PAGE251',
 WATTAGE='1/16W',
 TOLERANCE='5%',
 MATERIAL='CHIP',
 PHYS_PAGE='252',
 XY='(-5600,4150)',
 ROT='2',
 VER='1',
 PACK_TYPE='0402LF',
 LOCATION='R3715',
 CDS_LIB='pure_quanta',
 CDS_PART_NAME='Q_RES_0402LF-0,5%,1/16W,CHIP,CS00002JB13',
 PART_NUMBER='CS00002JB13',
 VALUE='0',
 PRIM_FILE='./archive_libs/logical/q_res/chips/chips.prt';

PART_NAME
 R3716 'Q_RES_0402LF-0,5%,1/16W,CHIP,CS00002JB13':;

SECTION_NUMBER 1
 '@T6G_MB_LIB.T6G(SCH_1):PAGE251_I30@PURE_QUANTA.Q_RES(CHIPS)':
 C_PATH='@t6g_mb_lib.t6g(sch_1):page251_i30@pure_quanta.q_res(chips)',
 P_PATH='@t6g_mb_lib.t6g(sch_1):page252_i30@pure_quanta.q_res(chips)',
 PATH='I30',
 DRAWING='@T6G_MB_LIB.T6G(SCH_1):PAGE251',
 WATTAGE='1/16W',
 TOLERANCE='5%',
 MATERIAL='CHIP',
 PHYS_PAGE='252',
 XY='(-5600,4200)',
 ROT='2',
 VER='1',
 PACK_TYPE='0402LF',
 LOCATION='R3716',
 CDS_LIB='pure_quanta',
 CDS_PART_NAME='Q_RES_0402LF-0,5%,1/16W,CHIP,CS00002JB13',
 PART_NUMBER='CS00002JB13',
 VALUE='0',
 PRIM_FILE='./archive_libs/logical/q_res/chips/chips.prt';

PART_NAME
 R3717 'Q_RES_0402LF-0,5%,1/16W,CHIP,CS00002JB13':;

SECTION_NUMBER 1
 '@T6G_MB_LIB.T6G(SCH_1):PAGE251_I20@PURE_QUANTA.Q_RES(CHIPS)':
 C_PATH='@t6g_mb_lib.t6g(sch_1):page251_i20@pure_quanta.q_res(chips)',
 P_PATH='@t6g_mb_lib.t6g(sch_1):page252_i20@pure_quanta.q_res(chips)',
 PATH='I20',
 DRAWING='@T6G_MB_LIB.T6G(SCH_1):PAGE251',
 WATTAGE='1/16W',
 TOLERANCE='5%',
 MATERIAL='CHIP',
 PHYS_PAGE='252',
 XY='(-5600,4050)',
 ROT='2',
 VER='1',
 PACK_TYPE='0402LF',
 LOCATION='R3717',
 CDS_LIB='pure_quanta',
 CDS_PART_NAME='Q_RES_0402LF-0,5%,1/16W,CHIP,CS00002JB13',
 PART_NUMBER='CS00002JB13',
 VALUE='0',
 PRIM_FILE='./archive_libs/logical/q_res/chips/chips.prt';

PART_NAME
 R3718 'Q_RES_0402LF-0,5%,1/16W,CHIP,CS00002JB13':;

SECTION_NUMBER 1
 '@T6G_MB_LIB.T6G(SCH_1):PAGE251_I21@PURE_QUANTA.Q_RES(CHIPS)':
 C_PATH='@t6g_mb_lib.t6g(sch_1):page251_i21@pure_quanta.q_res(chips)',
 P_PATH='@t6g_mb_lib.t6g(sch_1):page252_i21@pure_quanta.q_res(chips)',
 PATH='I21',
 DRAWING='@T6G_MB_LIB.T6G(SCH_1):PAGE251',
 WATTAGE='1/16W',
 TOLERANCE='5%',
 MATERIAL='CHIP',
 PHYS_PAGE='252',
 XY='(-5600,4100)',
 ROT='2',
 VER='1',
 PACK_TYPE='0402LF',
 LOCATION='R3718',
 CDS_LIB='pure_quanta',
 CDS_PART_NAME='Q_RES_0402LF-0,5%,1/16W,CHIP,CS00002JB13',
 PART_NUMBER='CS00002JB13',
 VALUE='0',
 PRIM_FILE='./archive_libs/logical/q_res/chips/chips.prt';

PART_NAME
 R3719 'Q_RES_0402LF-0,5%,1/16W,CHIP,CS00002JB13':;

SECTION_NUMBER 1
 '@T6G_MB_LIB.T6G(SCH_1):PAGE251_I18@PURE_QUANTA.Q_RES(CHIPS)':
 C_PATH='@t6g_mb_lib.t6g(sch_1):page251_i18@pure_quanta.q_res(chips)',
 P_PATH='@t6g_mb_lib.t6g(sch_1):page252_i18@pure_quanta.q_res(chips)',
 PATH='I18',
 DRAWING='@T6G_MB_LIB.T6G(SCH_1):PAGE251',
 WATTAGE='1/16W',
 TOLERANCE='5%',
 MATERIAL='CHIP',
 PHYS_PAGE='252',
 XY='(-5600,3950)',
 ROT='2',
 VER='1',
 PACK_TYPE='0402LF',
 LOCATION='R3719',
 CDS_LIB='pure_quanta',
 CDS_PART_NAME='Q_RES_0402LF-0,5%,1/16W,CHIP,CS00002JB13',
 PART_NUMBER='CS00002JB13',
 VALUE='0',
 PRIM_FILE='./archive_libs/logical/q_res/chips/chips.prt';

PART_NAME
 R3720 'Q_RES_0402LF-0,5%,1/16W,CHIP,CS00002JB13':;

SECTION_NUMBER 1
 '@T6G_MB_LIB.T6G(SCH_1):PAGE251_I19@PURE_QUANTA.Q_RES(CHIPS)':
 C_PATH='@t6g_mb_lib.t6g(sch_1):page251_i19@pure_quanta.q_res(chips)',
 P_PATH='@t6g_mb_lib.t6g(sch_1):page252_i19@pure_quanta.q_res(chips)',
 PATH='I19',
 DRAWING='@T6G_MB_LIB.T6G(SCH_1):PAGE251',
 WATTAGE='1/16W',
 TOLERANCE='5%',
 MATERIAL='CHIP',
 PHYS_PAGE='252',
 XY='(-5600,4000)',
 ROT='2',
 VER='1',
 PACK_TYPE='0402LF',
 LOCATION='R3720',
 CDS_LIB='pure_quanta',
 CDS_PART_NAME='Q_RES_0402LF-0,5%,1/16W,CHIP,CS00002JB13',
 PART_NUMBER='CS00002JB13',
 VALUE='0',
 PRIM_FILE='./archive_libs/logical/q_res/chips/chips.prt';

PART_NAME
 R3721 'Q_RES_0402LF-0,5%,1/16W,CHIP,CS00002JB13':;

SECTION_NUMBER 1
 '@T6G_MB_LIB.T6G(SCH_1):PAGE251_I67@PURE_QUANTA.Q_RES(CHIPS)':
 C_PATH='@t6g_mb_lib.t6g(sch_1):page251_i67@pure_quanta.q_res(chips)',
 P_PATH='@t6g_mb_lib.t6g(sch_1):page252_i67@pure_quanta.q_res(chips)',
 PATH='I67',
 DRAWING='@T6G_MB_LIB.T6G(SCH_1):PAGE251',
 WATTAGE='1/16W',
 TOLERANCE='5%',
 MATERIAL='CHIP',
 PHYS_PAGE='252',
 XY='(-2950,4250)',
 ROT='0',
 VER='1',
 PACK_TYPE='0402LF',
 LOCATION='R3721',
 CDS_LIB='pure_quanta',
 CDS_PART_NAME='Q_RES_0402LF-0,5%,1/16W,CHIP,CS00002JB13',
 PART_NUMBER='CS00002JB13',
 VALUE='0',
 PRIM_FILE='./archive_libs/logical/q_res/chips/chips.prt';

PART_NAME
 R3722 'Q_RES_0402LF-0,5%,1/16W,CHIP,CS00002JB13':;

SECTION_NUMBER 1
 '@T6G_MB_LIB.T6G(SCH_1):PAGE251_I66@PURE_QUANTA.Q_RES(CHIPS)':
 C_PATH='@t6g_mb_lib.t6g(sch_1):page251_i66@pure_quanta.q_res(chips)',
 P_PATH='@t6g_mb_lib.t6g(sch_1):page252_i66@pure_quanta.q_res(chips)',
 PATH='I66',
 DRAWING='@T6G_MB_LIB.T6G(SCH_1):PAGE251',
 WATTAGE='1/16W',
 TOLERANCE='5%',
 MATERIAL='CHIP',
 PHYS_PAGE='252',
 XY='(-2950,4300)',
 ROT='0',
 VER='1',
 PACK_TYPE='0402LF',
 LOCATION='R3722',
 CDS_LIB='pure_quanta',
 CDS_PART_NAME='Q_RES_0402LF-0,5%,1/16W,CHIP,CS00002JB13',
 PART_NUMBER='CS00002JB13',
 VALUE='0',
 PRIM_FILE='./archive_libs/logical/q_res/chips/chips.prt';

PART_NAME
 R3723 'Q_RES_0402LF-2.2K,5%,1/16W,CHIP,CS22202JB07':;

SECTION_NUMBER 1
 '@T6G_MB_LIB.T6G(SCH_1):PAGE251_I53@PURE_QUANTA.Q_RES(CHIPS)':
 C_PATH='@t6g_mb_lib.t6g(sch_1):page251_i53@pure_quanta.q_res(chips)',
 P_PATH='@t6g_mb_lib.t6g(sch_1):page252_i53@pure_quanta.q_res(chips)',
 PATH='I53',
 DRAWING='@T6G_MB_LIB.T6G(SCH_1):PAGE251',
 WATTAGE='1/16W',
 TOLERANCE='5%',
 MATERIAL='CHIP',
 PHYS_PAGE='252',
 XY='(-2575,2825)',
 ROT='0',
 VER='1',
 PACK_TYPE='0402LF',
 LOCATION='R3723',
 CDS_LIB='pure_quanta',
 CDS_PART_NAME='Q_RES_0402LF-2.2K,5%,1/16W,CHIP,CS22202JB07',
 PART_NUMBER='CS22202JB07',
 VALUE='2.2K',
 PRIM_FILE='./archive_libs/logical/q_res/chips/chips.prt';

PART_NAME
 R3724 'Q_RES_0402LF-2.2K,5%,1/16W,CHIP,CS22202JB07':;

SECTION_NUMBER 1
 '@T6G_MB_LIB.T6G(SCH_1):PAGE251_I52@PURE_QUANTA.Q_RES(CHIPS)':
 C_PATH='@t6g_mb_lib.t6g(sch_1):page251_i52@pure_quanta.q_res(chips)',
 P_PATH='@t6g_mb_lib.t6g(sch_1):page252_i52@pure_quanta.q_res(chips)',
 PATH='I52',
 DRAWING='@T6G_MB_LIB.T6G(SCH_1):PAGE251',
 WATTAGE='1/16W',
 TOLERANCE='5%',
 MATERIAL='CHIP',
 PHYS_PAGE='252',
 XY='(-2575,2775)',
 ROT='0',
 VER='1',
 PACK_TYPE='0402LF',
 LOCATION='R3724',
 CDS_LIB='pure_quanta',
 CDS_PART_NAME='Q_RES_0402LF-2.2K,5%,1/16W,CHIP,CS22202JB07',
 PART_NUMBER='CS22202JB07',
 VALUE='2.2K',
 PRIM_FILE='./archive_libs/logical/q_res/chips/chips.prt';

PART_NAME
 R3725 'Q_RES_0402LF-2.2K,5%,1/16W,CHIP,CS22202JB07':;

SECTION_NUMBER 1
 '@T6G_MB_LIB.T6G(SCH_1):PAGE251_I50@PURE_QUANTA.Q_RES(CHIPS)':
 C_PATH='@t6g_mb_lib.t6g(sch_1):page251_i50@pure_quanta.q_res(chips)',
 P_PATH='@t6g_mb_lib.t6g(sch_1):page252_i50@pure_quanta.q_res(chips)',
 PATH='I50',
 DRAWING='@T6G_MB_LIB.T6G(SCH_1):PAGE251',
 WATTAGE='1/16W',
 TOLERANCE='5%',
 MATERIAL='CHIP',
 PHYS_PAGE='252',
 XY='(-2575,2450)',
 ROT='0',
 VER='1',
 PACK_TYPE='0402LF',
 LOCATION='R3725',
 CDS_LIB='pure_quanta',
 CDS_PART_NAME='Q_RES_0402LF-2.2K,5%,1/16W,CHIP,CS22202JB07',
 PART_NUMBER='CS22202JB07',
 VALUE='2.2K',
 PRIM_FILE='./archive_libs/logical/q_res/chips/chips.prt';

PART_NAME
 R3726 'Q_RES_0402LF-2.2K,5%,1/16W,CHIP,CS22202JB07':;

SECTION_NUMBER 1
 '@T6G_MB_LIB.T6G(SCH_1):PAGE251_I49@PURE_QUANTA.Q_RES(CHIPS)':
 C_PATH='@t6g_mb_lib.t6g(sch_1):page251_i49@pure_quanta.q_res(chips)',
 P_PATH='@t6g_mb_lib.t6g(sch_1):page252_i49@pure_quanta.q_res(chips)',
 PATH='I49',
 DRAWING='@T6G_MB_LIB.T6G(SCH_1):PAGE251',
 WATTAGE='1/16W',
 TOLERANCE='5%',
 MATERIAL='CHIP',
 PHYS_PAGE='252',
 XY='(-2575,2400)',
 ROT='0',
 VER='1',
 PACK_TYPE='0402LF',
 LOCATION='R3726',
 CDS_LIB='pure_quanta',
 CDS_PART_NAME='Q_RES_0402LF-2.2K,5%,1/16W,CHIP,CS22202JB07',
 PART_NUMBER='CS22202JB07',
 VALUE='2.2K',
 PRIM_FILE='./archive_libs/logical/q_res/chips/chips.prt';

PART_NAME
 R3727 'Q_RES_0402LF-2.2K,5%,1/16W,CHIP,CS22202JB07':;

SECTION_NUMBER 1
 '@T6G_MB_LIB.T6G(SCH_1):PAGE251_I48@PURE_QUANTA.Q_RES(CHIPS)':
 C_PATH='@t6g_mb_lib.t6g(sch_1):page251_i48@pure_quanta.q_res(chips)',
 P_PATH='@t6g_mb_lib.t6g(sch_1):page252_i48@pure_quanta.q_res(chips)',
 PATH='I48',
 DRAWING='@T6G_MB_LIB.T6G(SCH_1):PAGE251',
 WATTAGE='1/16W',
 TOLERANCE='5%',
 MATERIAL='CHIP',
 PHYS_PAGE='252',
 XY='(-2575,2175)',
 ROT='0',
 VER='1',
 PACK_TYPE='0402LF',
 LOCATION='R3727',
 CDS_LIB='pure_quanta',
 CDS_PART_NAME='Q_RES_0402LF-2.2K,5%,1/16W,CHIP,CS22202JB07',
 PART_NUMBER='CS22202JB07',
 VALUE='2.2K',
 PRIM_FILE='./archive_libs/logical/q_res/chips/chips.prt';

PART_NAME
 R3728 'Q_RES_0402LF-2.2K,5%,1/16W,CHIP,CS22202JB07':;

SECTION_NUMBER 1
 '@T6G_MB_LIB.T6G(SCH_1):PAGE251_I47@PURE_QUANTA.Q_RES(CHIPS)':
 C_PATH='@t6g_mb_lib.t6g(sch_1):page251_i47@pure_quanta.q_res(chips)',
 P_PATH='@t6g_mb_lib.t6g(sch_1):page252_i47@pure_quanta.q_res(chips)',
 PATH='I47',
 DRAWING='@T6G_MB_LIB.T6G(SCH_1):PAGE251',
 WATTAGE='1/16W',
 TOLERANCE='5%',
 MATERIAL='CHIP',
 PHYS_PAGE='252',
 XY='(-2575,2125)',
 ROT='0',
 VER='1',
 PACK_TYPE='0402LF',
 LOCATION='R3728',
 CDS_LIB='pure_quanta',
 CDS_PART_NAME='Q_RES_0402LF-2.2K,5%,1/16W,CHIP,CS22202JB07',
 PART_NUMBER='CS22202JB07',
 VALUE='2.2K',
 PRIM_FILE='./archive_libs/logical/q_res/chips/chips.prt';

PART_NAME
 R3729 'Q_RES_0402LF-2.2K,5%,1/16W,CHIP,CS22202JB07':;

SECTION_NUMBER 1
 '@T6G_MB_LIB.T6G(SCH_1):PAGE251_I44@PURE_QUANTA.Q_RES(CHIPS)':
 C_PATH='@t6g_mb_lib.t6g(sch_1):page251_i44@pure_quanta.q_res(chips)',
 P_PATH='@t6g_mb_lib.t6g(sch_1):page252_i44@pure_quanta.q_res(chips)',
 PATH='I44',
 DRAWING='@T6G_MB_LIB.T6G(SCH_1):PAGE251',
 WATTAGE='1/16W',
 TOLERANCE='5%',
 MATERIAL='CHIP',
 PHYS_PAGE='252',
 XY='(-2550,1875)',
 ROT='0',
 VER='1',
 PACK_TYPE='0402LF',
 LOCATION='R3729',
 CDS_LIB='pure_quanta',
 CDS_PART_NAME='Q_RES_0402LF-2.2K,5%,1/16W,CHIP,CS22202JB07',
 PART_NUMBER='CS22202JB07',
 VALUE='2.2K',
 PRIM_FILE='./archive_libs/logical/q_res/chips/chips.prt';

PART_NAME
 R3730 'Q_RES_0402LF-2.2K,5%,1/16W,CHIP,CS22202JB07':;

SECTION_NUMBER 1
 '@T6G_MB_LIB.T6G(SCH_1):PAGE251_I45@PURE_QUANTA.Q_RES(CHIPS)':
 C_PATH='@t6g_mb_lib.t6g(sch_1):page251_i45@pure_quanta.q_res(chips)',
 P_PATH='@t6g_mb_lib.t6g(sch_1):page252_i45@pure_quanta.q_res(chips)',
 PATH='I45',
 DRAWING='@T6G_MB_LIB.T6G(SCH_1):PAGE251',
 WATTAGE='1/16W',
 TOLERANCE='5%',
 MATERIAL='CHIP',
 PHYS_PAGE='252',
 XY='(-2550,1825)',
 ROT='0',
 VER='1',
 PACK_TYPE='0402LF',
 LOCATION='R3730',
 CDS_LIB='pure_quanta',
 CDS_PART_NAME='Q_RES_0402LF-2.2K,5%,1/16W,CHIP,CS22202JB07',
 PART_NUMBER='CS22202JB07',
 VALUE='2.2K',
 PRIM_FILE='./archive_libs/logical/q_res/chips/chips.prt';

PART_NAME
 R3731 'Q_RES_0402LF-2.2K,5%,1/16W,CHIP,CS22202JB07':;

SECTION_NUMBER 1
 '@T6G_MB_LIB.T6G(SCH_1):PAGE251_I43@PURE_QUANTA.Q_RES(CHIPS)':
 C_PATH='@t6g_mb_lib.t6g(sch_1):page251_i43@pure_quanta.q_res(chips)',
 P_PATH='@t6g_mb_lib.t6g(sch_1):page252_i43@pure_quanta.q_res(chips)',
 PATH='I43',
 DRAWING='@T6G_MB_LIB.T6G(SCH_1):PAGE251',
 WATTAGE='1/16W',
 TOLERANCE='5%',
 MATERIAL='CHIP',
 PHYS_PAGE='252',
 XY='(-2550,1575)',
 ROT='0',
 VER='1',
 PACK_TYPE='0402LF',
 LOCATION='R3731',
 CDS_LIB='pure_quanta',
 CDS_PART_NAME='Q_RES_0402LF-2.2K,5%,1/16W,CHIP,CS22202JB07',
 PART_NUMBER='CS22202JB07',
 VALUE='2.2K',
 PRIM_FILE='./archive_libs/logical/q_res/chips/chips.prt';

PART_NAME
 R3732 'Q_RES_0402LF-2.2K,5%,1/16W,CHIP,CS22202JB07':;

SECTION_NUMBER 1
 '@T6G_MB_LIB.T6G(SCH_1):PAGE251_I42@PURE_QUANTA.Q_RES(CHIPS)':
 C_PATH='@t6g_mb_lib.t6g(sch_1):page251_i42@pure_quanta.q_res(chips)',
 P_PATH='@t6g_mb_lib.t6g(sch_1):page252_i42@pure_quanta.q_res(chips)',
 PATH='I42',
 DRAWING='@T6G_MB_LIB.T6G(SCH_1):PAGE251',
 WATTAGE='1/16W',
 TOLERANCE='5%',
 MATERIAL='CHIP',
 PHYS_PAGE='252',
 XY='(-2550,1525)',
 ROT='0',
 VER='1',
 PACK_TYPE='0402LF',
 LOCATION='R3732',
 CDS_LIB='pure_quanta',
 CDS_PART_NAME='Q_RES_0402LF-2.2K,5%,1/16W,CHIP,CS22202JB07',
 PART_NUMBER='CS22202JB07',
 VALUE='2.2K',
 PRIM_FILE='./archive_libs/logical/q_res/chips/chips.prt';

PART_NAME
 R3751 'Q_RES_0402LF-0,5%,1/16W,CHIP,CS00002JB13':;

SECTION_NUMBER 1
 '@T6G_MB_LIB.T6G(SCH_1):PAGE295_I146@PURE_QUANTA.Q_RES(CHIPS)':
 C_PATH='@t6g_mb_lib.t6g(sch_1):page295_i146@pure_quanta.q_res(chips)',
 P_PATH='@t6g_mb_lib.t6g(sch_1):page236_i146@pure_quanta.q_res(chips)',
 PATH='I146',
 DRAWING='@T6G_MB_LIB.T6G(SCH_1):PAGE295',
 WATTAGE='1/16W',
 TOLERANCE='5%',
 MATERIAL='CHIP',
 PHYS_PAGE='236',
 XY='(1550,825)',
 ROT='0',
 VER='2',
 PACK_TYPE='0402LF',
 LOCATION='R3751',
 CDS_LIB='pure_quanta',
 CDS_PART_NAME='Q_RES_0402LF-0,5%,1/16W,CHIP,CS00002JB13',
 PART_NUMBER='CS00002JB13',
 VALUE='0',
 PRIM_FILE='./archive_libs/logical/q_res/chips/chips.prt';

PART_NAME
 R3752 'Q_RES_0402LF-0,5%,1/16W,CHIP,CS00002JB13':;

SECTION_NUMBER 1
 '@T6G_MB_LIB.T6G(SCH_1):PAGE295_I122@PURE_QUANTA.Q_RES(CHIPS)':
 C_PATH='@t6g_mb_lib.t6g(sch_1):page295_i122@pure_quanta.q_res(chips)',
 P_PATH='@t6g_mb_lib.t6g(sch_1):page236_i122@pure_quanta.q_res(chips)',
 PATH='I122',
 DRAWING='@T6G_MB_LIB.T6G(SCH_1):PAGE295',
 WATTAGE='1/16W',
 TOLERANCE='5%',
 MATERIAL='CHIP',
 PHYS_PAGE='236',
 XY='(4450,725)',
 ROT='0',
 VER='1',
 PACK_TYPE='0402LF',
 LOCATION='R3752',
 CDS_LIB='pure_quanta',
 CDS_PART_NAME='Q_RES_0402LF-0,5%,1/16W,CHIP,CS00002JB13',
 PART_NUMBER='CS00002JB13',
 VALUE='0',
 PRIM_FILE='./archive_libs/logical/q_res/chips/chips.prt';

PART_NAME
 R3754 'Q_RES_0402LF-0,5%,1/16W,CHIP,CS00002JB13':;

SECTION_NUMBER 1
 '@T6G_MB_LIB.T6G(SCH_1):PAGE295_I155@PURE_QUANTA.Q_RES(CHIPS)':
 C_PATH='@t6g_mb_lib.t6g(sch_1):page295_i155@pure_quanta.q_res(chips)',
 P_PATH='@t6g_mb_lib.t6g(sch_1):page236_i155@pure_quanta.q_res(chips)',
 PATH='I155',
 DRAWING='@T6G_MB_LIB.T6G(SCH_1):PAGE295',
 WATTAGE='1/16W',
 TOLERANCE='5%',
 MATERIAL='CHIP',
 PHYS_PAGE='236',
 XY='(1275,475)',
 ROT='0',
 VER='1',
 PACK_TYPE='0402LF',
 LOCATION='R3754',
 CDS_LIB='pure_quanta',
 CDS_PART_NAME='Q_RES_0402LF-0,5%,1/16W,CHIP,CS00002JB13',
 PART_NUMBER='CS00002JB13',
 VALUE='0',
 PRIM_FILE='./archive_libs/logical/q_res/chips/chips.prt';

PART_NAME
 R3756 'Q_RES_0402LF-0,5%,1/16W,CHIP,CS00002JB13':;

SECTION_NUMBER 1
 '@T6G_MB_LIB.T6G(SCH_1):PAGE295_I154@PURE_QUANTA.Q_RES(CHIPS)':
 C_PATH='@t6g_mb_lib.t6g(sch_1):page295_i154@pure_quanta.q_res(chips)',
 P_PATH='@t6g_mb_lib.t6g(sch_1):page236_i154@pure_quanta.q_res(chips)',
 PATH='I154',
 DRAWING='@T6G_MB_LIB.T6G(SCH_1):PAGE295',
 WATTAGE='1/16W',
 TOLERANCE='5%',
 MATERIAL='CHIP',
 PHYS_PAGE='236',
 XY='(1275,425)',
 ROT='0',
 VER='1',
 PACK_TYPE='0402LF',
 LOCATION='R3756',
 CDS_LIB='pure_quanta',
 CDS_PART_NAME='Q_RES_0402LF-0,5%,1/16W,CHIP,CS00002JB13',
 PART_NUMBER='CS00002JB13',
 VALUE='0',
 PRIM_FILE='./archive_libs/logical/q_res/chips/chips.prt';

PART_NAME
 R3758 'Q_RES_0402LF-10,1%,1/16W,CHIP,CS01002FB07':;

SECTION_NUMBER 1
 '@T6G_MB_LIB.T6G(SCH_1):PAGE295_I132@PURE_QUANTA.Q_RES(CHIPS)':
 C_PATH='@t6g_mb_lib.t6g(sch_1):page295_i132@pure_quanta.q_res(chips)',
 P_PATH='@t6g_mb_lib.t6g(sch_1):page236_i132@pure_quanta.q_res(chips)',
 PATH='I132',
 DRAWING='@T6G_MB_LIB.T6G(SCH_1):PAGE295',
 WATTAGE='1/16W',
 TOLERANCE='1%',
 MATERIAL='CHIP',
 PHYS_PAGE='236',
 XY='(1300,-125)',
 ROT='0',
 VER='1',
 PACK_TYPE='0402LF',
 LOCATION='R3758',
 CDS_LIB='pure_quanta',
 CDS_PART_NAME='Q_RES_0402LF-10,1%,1/16W,CHIP,CS01002FB07',
 PART_NUMBER='CS01002FB07',
 VALUE='10',
 PRIM_FILE='./archive_libs/logical/q_res/chips/chips.prt';

PART_NAME
 R3760 'Q_RES_0402LF-10,1%,1/16W,CHIP,CS01002FB07':;

SECTION_NUMBER 1
 '@T6G_MB_LIB.T6G(SCH_1):PAGE295_I134@PURE_QUANTA.Q_RES(CHIPS)':
 C_PATH='@t6g_mb_lib.t6g(sch_1):page295_i134@pure_quanta.q_res(chips)',
 P_PATH='@t6g_mb_lib.t6g(sch_1):page236_i134@pure_quanta.q_res(chips)',
 PATH='I134',
 DRAWING='@T6G_MB_LIB.T6G(SCH_1):PAGE295',
 WATTAGE='1/16W',
 TOLERANCE='1%',
 MATERIAL='CHIP',
 PHYS_PAGE='236',
 XY='(1300,-400)',
 ROT='0',
 VER='1',
 PACK_TYPE='0402LF',
 LOCATION='R3760',
 CDS_LIB='pure_quanta',
 CDS_PART_NAME='Q_RES_0402LF-10,1%,1/16W,CHIP,CS01002FB07',
 PART_NUMBER='CS01002FB07',
 VALUE='10',
 PRIM_FILE='./archive_libs/logical/q_res/chips/chips.prt';

PART_NAME
 R3763 'Q_RES_0402LF-4.7K,1%,1/16W,CHIP,CS24702FB06':;

SECTION_NUMBER 1
 '@T6G_MB_LIB.T6G(SCH_1):PAGE295_I136@PURE_QUANTA.Q_RES(CHIPS)':
 C_PATH='@t6g_mb_lib.t6g(sch_1):page295_i136@pure_quanta.q_res(chips)',
 P_PATH='@t6g_mb_lib.t6g(sch_1):page236_i136@pure_quanta.q_res(chips)',
 PATH='I136',
 DRAWING='@T6G_MB_LIB.T6G(SCH_1):PAGE295',
 WATTAGE='1/16W',
 TOLERANCE='1%',
 MATERIAL='CHIP',
 PHYS_PAGE='236',
 XY='(750,1075)',
 ROT='0',
 VER='1',
 PACK_TYPE='0402LF',
 LOCATION='R3763',
 CDS_LIB='pure_quanta',
 CDS_PART_NAME='Q_RES_0402LF-4.7K,1%,1/16W,CHIP,CS24702FB06',
 PART_NUMBER='CS24702FB06',
 VALUE='4.7K',
 PRIM_FILE='./archive_libs/logical/q_res/chips/chips.prt';

PART_NAME
 R3764 'Q_RES_0402LF-4.7K,1%,1/16W,EMPTY,CS24702FB06':;

SECTION_NUMBER 1
 '@T6G_MB_LIB.T6G(SCH_1):PAGE295_I135@PURE_QUANTA.Q_RES(CHIPS)':
 C_PATH='@t6g_mb_lib.t6g(sch_1):page295_i135@pure_quanta.q_res(chips)',
 P_PATH='@t6g_mb_lib.t6g(sch_1):page236_i135@pure_quanta.q_res(chips)',
 PATH='I135',
 DRAWING='@T6G_MB_LIB.T6G(SCH_1):PAGE295',
 WATTAGE='1/16W',
 TOLERANCE='1%',
 MATERIAL='EMPTY',
 PHYS_PAGE='236',
 XY='(750,1000)',
 ROT='0',
 VER='1',
 PACK_TYPE='0402LF',
 LOCATION='R3764',
 CDS_LIB='pure_quanta',
 CDS_PART_NAME='Q_RES_0402LF-4.7K,1%,1/16W,EMPTY,CS24702FB06',
 PART_NUMBER='CS24702FB06',
 VALUE='4.7K',
 PRIM_FILE='./archive_libs/logical/q_res/chips/chips.prt';

PART_NAME
 R3767 'Q_RES_2512LF-0.002,1%,2W,CHIP,CS+002AFR06':;

SECTION_NUMBER 1
 '@T6G_MB_LIB.T6G(SCH_1):PAGE295_I144@PURE_QUANTA.Q_RES(CHIPS)':
 C_PATH='@t6g_mb_lib.t6g(sch_1):page295_i144@pure_quanta.q_res(chips)',
 P_PATH='@t6g_mb_lib.t6g(sch_1):page236_i144@pure_quanta.q_res(chips)',
 PATH='I144',
 DRAWING='@T6G_MB_LIB.T6G(SCH_1):PAGE295',
 WATTAGE='2W',
 TOLERANCE='1%',
 MATERIAL='CHIP',
 PHYS_PAGE='236',
 XY='(-600,75)',
 ROT='0',
 VER='1',
 PACK_TYPE='2512LF',
 LOCATION='R3767',
 CDS_LIB='pure_quanta',
 CDS_PART_NAME='Q_RES_2512LF-0.002,1%,2W,CHIP,CS+002AFR06',
 PART_NUMBER='CS+002AFR06',
 VALUE='0.002',
 PRIM_FILE='./archive_libs/logical/q_res/chips/chips.prt';

PART_NAME
 R3770 'Q_RES_0402LF-0,5%,1/16W,CHIP,CS00002JB13':;

SECTION_NUMBER 1
 '@T6G_MB_LIB.T6G(SCH_1):PAGE364_I34@PURE_QUANTA.Q_RES(CHIPS)':
 C_PATH='@t6g_mb_lib.t6g(sch_1):page364_i34@pure_quanta.q_res(chips)',
 P_PATH='@t6g_mb_lib.t6g(sch_1):page241_i34@pure_quanta.q_res(chips)',
 PATH='I34',
 DRAWING='@T6G_MB_LIB.T6G(SCH_1):PAGE364',
 WATTAGE='1/16W',
 TOLERANCE='5%',
 MATERIAL='CHIP',
 PHYS_PAGE='241',
 XY='(-1325,2125)',
 ROT='0',
 VER='1',
 PACK_TYPE='0402LF',
 LOCATION='R3770',
 CDS_LIB='pure_quanta',
 CDS_PART_NAME='Q_RES_0402LF-0,5%,1/16W,CHIP,CS00002JB13',
 PART_NUMBER='CS00002JB13',
 VALUE='0',
 PRIM_FILE='./archive_libs/logical/q_res/chips/chips.prt';

PART_NAME
 R3771 'Q_RES_0402LF-10K,1%,1/16W,CHIP,CS31002FB08':;

SECTION_NUMBER 1
 '@T6G_MB_LIB.T6G(SCH_1):PAGE297_I7@PURE_QUANTA.Q_RES(CHIPS)':
 C_PATH='@t6g_mb_lib.t6g(sch_1):page297_i7@pure_quanta.q_res(chips)',
 P_PATH='@t6g_mb_lib.t6g(sch_1):page145_i7@pure_quanta.q_res(chips)',
 PATH='I7',
 DRAWING='@T6G_MB_LIB.T6G(SCH_1):PAGE297',
 WATTAGE='1/16W',
 TOLERANCE='1%',
 MATERIAL='CHIP',
 PHYS_PAGE='145',
 XY='(-2900,2650)',
 ROT='0',
 VER='2',
 PACK_TYPE='0402LF',
 LOCATION='R3771',
 CDS_LIB='pure_quanta',
 CDS_PART_NAME='Q_RES_0402LF-10K,1%,1/16W,CHIP,CS31002FB08',
 PART_NUMBER='CS31002FB08',
 VALUE='10K',
 PRIM_FILE='./archive_libs/logical/q_res/chips/chips.prt';

PART_NAME
 R3772 'Q_RES_0402LF-0,5%,1/16W,CHIP,CS00002JB13':;

SECTION_NUMBER 1
 '@T6G_MB_LIB.T6G(SCH_1):PAGE297_I38@PURE_QUANTA.Q_RES(CHIPS)':
 C_PATH='@t6g_mb_lib.t6g(sch_1):page297_i38@pure_quanta.q_res(chips)',
 P_PATH='@t6g_mb_lib.t6g(sch_1):page145_i38@pure_quanta.q_res(chips)',
 PATH='I38',
 DRAWING='@T6G_MB_LIB.T6G(SCH_1):PAGE297',
 WATTAGE='1/16W',
 TOLERANCE='5%',
 MATERIAL='CHIP',
 PHYS_PAGE='145',
 XY='(1900,-700)',
 ROT='0',
 VER='1',
 PACK_TYPE='0402LF',
 LOCATION='R3772',
 CDS_LIB='pure_quanta',
 CDS_PART_NAME='Q_RES_0402LF-0,5%,1/16W,CHIP,CS00002JB13',
 PART_NUMBER='CS00002JB13',
 VALUE='0',
 PRIM_FILE='./archive_libs/logical/q_res/chips/chips.prt';

PART_NAME
 R3773 'Q_RES_0402LF-4.7K,5%,1/16W,EMPTY,CS24702JB10':;

SECTION_NUMBER 1
 '@T6G_MB_LIB.T6G(SCH_1):PAGE297_I106@PURE_QUANTA.Q_RES(CHIPS)':
 C_PATH='@t6g_mb_lib.t6g(sch_1):page297_i106@pure_quanta.q_res(chips)',
 P_PATH='@t6g_mb_lib.t6g(sch_1):page145_i106@pure_quanta.q_res(chips)',
 PATH='I106',
 DRAWING='@T6G_MB_LIB.T6G(SCH_1):PAGE297',
 WATTAGE='1/16W',
 TOLERANCE='5%',
 MATERIAL='EMPTY',
 PHYS_PAGE='145',
 XY='(2925,-350)',
 ROT='0',
 VER='2',
 PACK_TYPE='0402LF',
 LOCATION='R3773',
 CDS_LIB='pure_quanta',
 CDS_PART_NAME='Q_RES_0402LF-4.7K,5%,1/16W,EMPTY,CS24702JB10',
 PART_NUMBER='CS24702JB10',
 VALUE='4.7K',
 PRIM_FILE='./archive_libs/logical/q_res/chips/chips.prt';

PART_NAME
 R3775 'Q_RES_0402LF-0,5%,1/16W,CHIP,CS00002JB13':;

SECTION_NUMBER 1
 '@T6G_MB_LIB.T6G(SCH_1):PAGE297_I2@PURE_QUANTA.Q_RES(CHIPS)':
 C_PATH='@t6g_mb_lib.t6g(sch_1):page297_i2@pure_quanta.q_res(chips)',
 P_PATH='@t6g_mb_lib.t6g(sch_1):page145_i2@pure_quanta.q_res(chips)',
 PATH='I2',
 DRAWING='@T6G_MB_LIB.T6G(SCH_1):PAGE297',
 WATTAGE='1/16W',
 TOLERANCE='5%',
 MATERIAL='CHIP',
 PHYS_PAGE='145',
 XY='(-850,-700)',
 ROT='0',
 VER='1',
 PACK_TYPE='0402LF',
 LOCATION='R3775',
 CDS_LIB='pure_quanta',
 CDS_PART_NAME='Q_RES_0402LF-0,5%,1/16W,CHIP,CS00002JB13',
 PART_NUMBER='CS00002JB13',
 VALUE='0',
 PRIM_FILE='./archive_libs/logical/q_res/chips/chips.prt';

PART_NAME
 R3776 'Q_RES_0402LF-0,5%,1/16W,CHIP,CS00002JB13':;

SECTION_NUMBER 1
 '@T6G_MB_LIB.T6G(SCH_1):PAGE348_I27@PURE_QUANTA.Q_RES(CHIPS)':
 C_PATH='@t6g_mb_lib.t6g(sch_1):page348_i27@pure_quanta.q_res(chips)',
 P_PATH='@t6g_mb_lib.t6g(sch_1):page150_i27@pure_quanta.q_res(chips)',
 PATH='I27',
 DRAWING='@T6G_MB_LIB.T6G(SCH_1):PAGE348',
 WATTAGE='1/16W',
 TOLERANCE='5%',
 MATERIAL='CHIP',
 PHYS_PAGE='150',
 XY='(-14975,5925)',
 ROT='0',
 VER='1',
 PACK_TYPE='0402LF',
 LOCATION='R3776',
 CDS_LIB='pure_quanta',
 CDS_PART_NAME='Q_RES_0402LF-0,5%,1/16W,CHIP,CS00002JB13',
 PART_NUMBER='CS00002JB13',
 VALUE='0',
 PRIM_FILE='./archive_libs/logical/q_res/chips/chips.prt';

PART_NAME
 R3777 'Q_RES_0402LF-0,5%,1/16W,CHIP,CS00002JB13':;

SECTION_NUMBER 1
 '@T6G_MB_LIB.T6G(SCH_1):PAGE348_I25@PURE_QUANTA.Q_RES(CHIPS)':
 C_PATH='@t6g_mb_lib.t6g(sch_1):page348_i25@pure_quanta.q_res(chips)',
 P_PATH='@t6g_mb_lib.t6g(sch_1):page150_i25@pure_quanta.q_res(chips)',
 PATH='I25',
 DRAWING='@T6G_MB_LIB.T6G(SCH_1):PAGE348',
 WATTAGE='1/16W',
 TOLERANCE='5%',
 MATERIAL='CHIP',
 PHYS_PAGE='150',
 XY='(-14975,5775)',
 ROT='0',
 VER='1',
 PACK_TYPE='0402LF',
 LOCATION='R3777',
 CDS_LIB='pure_quanta',
 CDS_PART_NAME='Q_RES_0402LF-0,5%,1/16W,CHIP,CS00002JB13',
 PART_NUMBER='CS00002JB13',
 VALUE='0',
 PRIM_FILE='./archive_libs/logical/q_res/chips/chips.prt';

PART_NAME
 R3778 'Q_RES_0402LF-0,5%,1/16W,CHIP,CS00002JB13':;

SECTION_NUMBER 1
 '@T6G_MB_LIB.T6G(SCH_1):PAGE348_I169@PURE_QUANTA.Q_RES(CHIPS)':
 C_PATH='@t6g_mb_lib.t6g(sch_1):page348_i169@pure_quanta.q_res(chips)',
 P_PATH='@t6g_mb_lib.t6g(sch_1):page150_i169@pure_quanta.q_res(chips)',
 PATH='I169',
 DRAWING='@T6G_MB_LIB.T6G(SCH_1):PAGE348',
 WATTAGE='1/16W',
 TOLERANCE='5%',
 MATERIAL='CHIP',
 PHYS_PAGE='150',
 XY='(-9450,8825)',
 ROT='0',
 VER='1',
 PACK_TYPE='0402LF',
 LOCATION='R3778',
 CDS_LIB='pure_quanta',
 CDS_PART_NAME='Q_RES_0402LF-0,5%,1/16W,CHIP,CS00002JB13',
 PART_NUMBER='CS00002JB13',
 VALUE='0',
 PRIM_FILE='./archive_libs/logical/q_res/chips/chips.prt';

PART_NAME
 R3779 'Q_RES_0402LF-0,5%,1/16W,CHIP,CS00002JB13':;

SECTION_NUMBER 1
 '@T6G_MB_LIB.T6G(SCH_1):PAGE297_I30@PURE_QUANTA.Q_RES(CHIPS)':
 C_PATH='@t6g_mb_lib.t6g(sch_1):page297_i30@pure_quanta.q_res(chips)',
 P_PATH='@t6g_mb_lib.t6g(sch_1):page145_i30@pure_quanta.q_res(chips)',
 PATH='I30',
 DRAWING='@T6G_MB_LIB.T6G(SCH_1):PAGE297',
 WATTAGE='1/16W',
 TOLERANCE='5%',
 MATERIAL='CHIP',
 PHYS_PAGE='145',
 XY='(-1850,4050)',
 ROT='0',
 VER='1',
 PACK_TYPE='0402LF',
 LOCATION='R3779',
 CDS_LIB='pure_quanta',
 CDS_PART_NAME='Q_RES_0402LF-0,5%,1/16W,CHIP,CS00002JB13',
 PART_NUMBER='CS00002JB13',
 VALUE='0',
 PRIM_FILE='./archive_libs/logical/q_res/chips/chips.prt';

PART_NAME
 R3783 'Q_RES_0402LF-100K,1%,1/16W,EMPTY,CS41002FB09':
 ROOM='NIC_P3V3_BOM1';

SECTION_NUMBER 1
 '@T6G_MB_LIB.T6G(SCH_1):PAGE338_I131@PURE_QUANTA.Q_RES(CHIPS)':
 C_PATH='@t6g_mb_lib.t6g(sch_1):page338_i131@pure_quanta.q_res(chips)',
 P_PATH='@t6g_mb_lib.t6g(sch_1):page134_i131@pure_quanta.q_res(chips)',
 PATH='I131',
 DRAWING='@T6G_MB_LIB.T6G(SCH_1):PAGE338',
 WATTAGE='1/16W',
 TOLERANCE='1%',
 MATERIAL='EMPTY',
 PHYS_PAGE='134',
 XY='(10225,13050)',
 ROT='0',
 VER='2',
 PACK_TYPE='0402LF',
 LOCATION='R3783',
 CDS_LIB='pure_quanta',
 CDS_PART_NAME='Q_RES_0402LF-100K,1%,1/16W,EMPTY,CS41002FB09',
 ROOM='NIC_P3V3_BOM1',
 PART_NUMBER='CS41002FB09',
 VALUE='100K',
 PRIM_FILE='./archive_libs/logical/q_res/chips/chips.prt';

PART_NAME
 R3784 'Q_RES_0402LF-0,5%,1/16W,CHIP,CS00002JB13':
 ROOM='NIC_P12V_MAM_TIC_BOM1';

SECTION_NUMBER 1
 '@T6G_MB_LIB.T6G(SCH_1):PAGE338_I40@PURE_QUANTA.Q_RES(CHIPS)':
 C_PATH='@t6g_mb_lib.t6g(sch_1):page338_i40@pure_quanta.q_res(chips)',
 P_PATH='@t6g_mb_lib.t6g(sch_1):page134_i40@pure_quanta.q_res(chips)',
 PATH='I40',
 DRAWING='@T6G_MB_LIB.T6G(SCH_1):PAGE338',
 WATTAGE='1/16W',
 TOLERANCE='5%',
 MATERIAL='CHIP',
 PHYS_PAGE='134',
 XY='(5500,10825)',
 ROT='0',
 VER='1',
 PACK_TYPE='0402LF',
 LOCATION='R3784',
 CDS_LIB='pure_quanta',
 CDS_PART_NAME='Q_RES_0402LF-0,5%,1/16W,CHIP,CS00002JB13',
 ROOM='NIC_P12V_MAM_TIC_BOM1',
 PART_NUMBER='CS00002JB13',
 VALUE='0',
 PRIM_FILE='./archive_libs/logical/q_res/chips/chips.prt';

PART_NAME
 R3785 'Q_RES_0402LF-0,5%,1/16W,CHIP,CS00002JB13':
 ROOM='NIC_P3V3_BOM1';

SECTION_NUMBER 1
 '@T6G_MB_LIB.T6G(SCH_1):PAGE338_I61@PURE_QUANTA.Q_RES(CHIPS)':
 C_PATH='@t6g_mb_lib.t6g(sch_1):page338_i61@pure_quanta.q_res(chips)',
 P_PATH='@t6g_mb_lib.t6g(sch_1):page134_i61@pure_quanta.q_res(chips)',
 PATH='I61',
 DRAWING='@T6G_MB_LIB.T6G(SCH_1):PAGE338',
 WATTAGE='1/16W',
 TOLERANCE='5%',
 MATERIAL='CHIP',
 PHYS_PAGE='134',
 XY='(5650,12875)',
 ROT='0',
 VER='1',
 PACK_TYPE='0402LF',
 LOCATION='R3785',
 CDS_LIB='pure_quanta',
 CDS_PART_NAME='Q_RES_0402LF-0,5%,1/16W,CHIP,CS00002JB13',
 ROOM='NIC_P3V3_BOM1',
 PART_NUMBER='CS00002JB13',
 VALUE='0',
 PRIM_FILE='./archive_libs/logical/q_res/chips/chips.prt';

PART_NAME
 R3794 'Q_RES_0402LF-0,5%,1/16W,EMPTY,CS00002JB13':
 ROOM='NIC_P3V3_BOM1';

SECTION_NUMBER 1
 '@T6G_MB_LIB.T6G(SCH_1):PAGE338_I132@PURE_QUANTA.Q_RES(CHIPS)':
 C_PATH='@t6g_mb_lib.t6g(sch_1):page338_i132@pure_quanta.q_res(chips)',
 P_PATH='@t6g_mb_lib.t6g(sch_1):page134_i132@pure_quanta.q_res(chips)',
 PATH='I132',
 DRAWING='@T6G_MB_LIB.T6G(SCH_1):PAGE338',
 WATTAGE='1/16W',
 TOLERANCE='5%',
 MATERIAL='EMPTY',
 PHYS_PAGE='134',
 XY='(9325,12775)',
 ROT='0',
 VER='1',
 PACK_TYPE='0402LF',
 LOCATION='R3794',
 CDS_LIB='pure_quanta',
 CDS_PART_NAME='Q_RES_0402LF-0,5%,1/16W,EMPTY,CS00002JB13',
 ROOM='NIC_P3V3_BOM1',
 PART_NUMBER='CS00002JB13',
 VALUE='0',
 PRIM_FILE='./archive_libs/logical/q_res/chips/chips.prt';

PART_NAME
 R3796 'Q_RES_0402LF-100K,1%,1/16W,CHIP,CS41002FB09':
 ROOM='NIC_P3V3_BOM1';

SECTION_NUMBER 1
 '@T6G_MB_LIB.T6G(SCH_1):PAGE338_I101@PURE_QUANTA.Q_RES(CHIPS)':
 C_PATH='@t6g_mb_lib.t6g(sch_1):page338_i101@pure_quanta.q_res(chips)',
 P_PATH='@t6g_mb_lib.t6g(sch_1):page134_i101@pure_quanta.q_res(chips)',
 PATH='I101',
 DRAWING='@T6G_MB_LIB.T6G(SCH_1):PAGE338',
 WATTAGE='1/16W',
 TOLERANCE='1%',
 MATERIAL='CHIP',
 PHYS_PAGE='134',
 XY='(9675,13050)',
 ROT='0',
 VER='2',
 PACK_TYPE='0402LF',
 LOCATION='R3796',
 CDS_LIB='pure_quanta',
 CDS_PART_NAME='Q_RES_0402LF-100K,1%,1/16W,CHIP,CS41002FB09',
 ROOM='NIC_P3V3_BOM1',
 PART_NUMBER='CS41002FB09',
 VALUE='100K',
 PRIM_FILE='./archive_libs/logical/q_res/chips/chips.prt';

PART_NAME
 R3797 'Q_RES_0402LF-100K,1%,1/16W,CHIP,CS41002FB09':
 ROOM='NIC_P12V_MAM_TIC_BOM1';

SECTION_NUMBER 1
 '@T6G_MB_LIB.T6G(SCH_1):PAGE338_I85@PURE_QUANTA.Q_RES(CHIPS)':
 C_PATH='@t6g_mb_lib.t6g(sch_1):page338_i85@pure_quanta.q_res(chips)',
 P_PATH='@t6g_mb_lib.t6g(sch_1):page134_i85@pure_quanta.q_res(chips)',
 PATH='I85',
 DRAWING='@T6G_MB_LIB.T6G(SCH_1):PAGE338',
 WATTAGE='1/16W',
 TOLERANCE='1%',
 MATERIAL='CHIP',
 PHYS_PAGE='134',
 XY='(9900,11000)',
 ROT='0',
 VER='2',
 PACK_TYPE='0402LF',
 LOCATION='R3797',
 CDS_LIB='pure_quanta',
 CDS_PART_NAME='Q_RES_0402LF-100K,1%,1/16W,CHIP,CS41002FB09',
 ROOM='NIC_P12V_MAM_TIC_BOM1',
 PART_NUMBER='CS41002FB09',
 VALUE='100K',
 PRIM_FILE='./archive_libs/logical/q_res/chips/chips.prt';

PART_NAME
 R3799 'Q_RES_0402LF-100K,1%,1/16W,CHIP,CS41002FB09':
 ROOM='NIC_P12V_MAM_TIC_BOM1';

SECTION_NUMBER 1
 '@T6G_MB_LIB.T6G(SCH_1):PAGE338_I83@PURE_QUANTA.Q_RES(CHIPS)':
 C_PATH='@t6g_mb_lib.t6g(sch_1):page338_i83@pure_quanta.q_res(chips)',
 P_PATH='@t6g_mb_lib.t6g(sch_1):page134_i83@pure_quanta.q_res(chips)',
 PATH='I83',
 DRAWING='@T6G_MB_LIB.T6G(SCH_1):PAGE338',
 WATTAGE='1/16W',
 TOLERANCE='1%',
 MATERIAL='CHIP',
 PHYS_PAGE='134',
 XY='(9475,11000)',
 ROT='0',
 VER='2',
 PACK_TYPE='0402LF',
 LOCATION='R3799',
 CDS_LIB='pure_quanta',
 CDS_PART_NAME='Q_RES_0402LF-100K,1%,1/16W,CHIP,CS41002FB09',
 ROOM='NIC_P12V_MAM_TIC_BOM1',
 PART_NUMBER='CS41002FB09',
 VALUE='100K',
 PRIM_FILE='./archive_libs/logical/q_res/chips/chips.prt';

PART_NAME
 R3807 'Q_RES_0402LF-0,5%,1/16W,CHIP,CS00002JB13':
 ROOM='NIC_P3V3_BOM1';

SECTION_NUMBER 1
 '@T6G_MB_LIB.T6G(SCH_1):PAGE343_I50@PURE_QUANTA.Q_RES(CHIPS)':
 C_PATH='@t6g_mb_lib.t6g(sch_1):page343_i50@pure_quanta.q_res(chips)',
 P_PATH='@t6g_mb_lib.t6g(sch_1):page140_i50@pure_quanta.q_res(chips)',
 PATH='I50',
 DRAWING='@T6G_MB_LIB.T6G(SCH_1):PAGE343',
 WATTAGE='1/16W',
 TOLERANCE='5%',
 MATERIAL='CHIP',
 PHYS_PAGE='140',
 XY='(-525,8725)',
 ROT='0',
 VER='1',
 PACK_TYPE='0402LF',
 LOCATION='R3807',
 CDS_LIB='pure_quanta',
 CDS_PART_NAME='Q_RES_0402LF-0,5%,1/16W,CHIP,CS00002JB13',
 ROOM='NIC_P3V3_BOM1',
 PART_NUMBER='CS00002JB13',
 VALUE='0',
 PRIM_FILE='./archive_libs/logical/q_res/chips/chips.prt';

PART_NAME
 R3816 'Q_RES_0402LF-100K,1%,1/16W,CHIP,CS41002FB09':
 ROOM='NIC_P12V_MAM_TIC_BOM1';

SECTION_NUMBER 1
 '@T6G_MB_LIB.T6G(SCH_1):PAGE343_I79@PURE_QUANTA.Q_RES(CHIPS)':
 C_PATH='@t6g_mb_lib.t6g(sch_1):page343_i79@pure_quanta.q_res(chips)',
 P_PATH='@t6g_mb_lib.t6g(sch_1):page140_i79@pure_quanta.q_res(chips)',
 PATH='I79',
 DRAWING='@T6G_MB_LIB.T6G(SCH_1):PAGE343',
 WATTAGE='1/16W',
 TOLERANCE='1%',
 MATERIAL='CHIP',
 PHYS_PAGE='140',
 XY='(3275,6550)',
 ROT='0',
 VER='2',
 PACK_TYPE='0402LF',
 LOCATION='R3816',
 CDS_LIB='pure_quanta',
 CDS_PART_NAME='Q_RES_0402LF-100K,1%,1/16W,CHIP,CS41002FB09',
 ROOM='NIC_P12V_MAM_TIC_BOM1',
 PART_NUMBER='CS41002FB09',
 VALUE='100K',
 PRIM_FILE='./archive_libs/logical/q_res/chips/chips.prt';

PART_NAME
 R3825 'Q_RES_0402LF-100K,1%,1/16W,CHIP,CS41002FB09':
 ROOM='NIC_P12V_MAM_TIC_BOM1';

SECTION_NUMBER 1
 '@T6G_MB_LIB.T6G(SCH_1):PAGE343_I80@PURE_QUANTA.Q_RES(CHIPS)':
 C_PATH='@t6g_mb_lib.t6g(sch_1):page343_i80@pure_quanta.q_res(chips)',
 P_PATH='@t6g_mb_lib.t6g(sch_1):page140_i80@pure_quanta.q_res(chips)',
 PATH='I80',
 DRAWING='@T6G_MB_LIB.T6G(SCH_1):PAGE343',
 WATTAGE='1/16W',
 TOLERANCE='1%',
 MATERIAL='CHIP',
 PHYS_PAGE='140',
 XY='(3700,6550)',
 ROT='0',
 VER='2',
 PACK_TYPE='0402LF',
 LOCATION='R3825',
 CDS_LIB='pure_quanta',
 CDS_PART_NAME='Q_RES_0402LF-100K,1%,1/16W,CHIP,CS41002FB09',
 ROOM='NIC_P12V_MAM_TIC_BOM1',
 PART_NUMBER='CS41002FB09',
 VALUE='100K',
 PRIM_FILE='./archive_libs/logical/q_res/chips/chips.prt';

PART_NAME
 R3826 'Q_RES_0402LF-100K,1%,1/16W,EMPTY,CS41002FB09':
 ROOM='NIC_P3V3_BOM1';

SECTION_NUMBER 1
 '@T6G_MB_LIB.T6G(SCH_1):PAGE343_I128@PURE_QUANTA.Q_RES(CHIPS)':
 C_PATH='@t6g_mb_lib.t6g(sch_1):page343_i128@pure_quanta.q_res(chips)',
 P_PATH='@t6g_mb_lib.t6g(sch_1):page140_i128@pure_quanta.q_res(chips)',
 PATH='I128',
 DRAWING='@T6G_MB_LIB.T6G(SCH_1):PAGE343',
 WATTAGE='1/16W',
 TOLERANCE='1%',
 MATERIAL='EMPTY',
 PHYS_PAGE='140',
 XY='(4100,8925)',
 ROT='0',
 VER='2',
 PACK_TYPE='0402LF',
 LOCATION='R3826',
 CDS_LIB='pure_quanta',
 CDS_PART_NAME='Q_RES_0402LF-100K,1%,1/16W,EMPTY,CS41002FB09',
 ROOM='NIC_P3V3_BOM1',
 PART_NUMBER='CS41002FB09',
 VALUE='100K',
 PRIM_FILE='./archive_libs/logical/q_res/chips/chips.prt';

PART_NAME
 R3827 'Q_RES_0402LF-0,5%,1/16W,CHIP,CS00002JB13':
 ROOM='NIC_P12V_MAM_TIC_BOM1';

SECTION_NUMBER 1
 '@T6G_MB_LIB.T6G(SCH_1):PAGE343_I33@PURE_QUANTA.Q_RES(CHIPS)':
 C_PATH='@t6g_mb_lib.t6g(sch_1):page343_i33@pure_quanta.q_res(chips)',
 P_PATH='@t6g_mb_lib.t6g(sch_1):page140_i33@pure_quanta.q_res(chips)',
 PATH='I33',
 DRAWING='@T6G_MB_LIB.T6G(SCH_1):PAGE343',
 WATTAGE='1/16W',
 TOLERANCE='5%',
 MATERIAL='CHIP',
 PHYS_PAGE='140',
 XY='(-750,6400)',
 ROT='0',
 VER='1',
 PACK_TYPE='0402LF',
 LOCATION='R3827',
 CDS_LIB='pure_quanta',
 CDS_PART_NAME='Q_RES_0402LF-0,5%,1/16W,CHIP,CS00002JB13',
 ROOM='NIC_P12V_MAM_TIC_BOM1',
 PART_NUMBER='CS00002JB13',
 VALUE='0',
 PRIM_FILE='./archive_libs/logical/q_res/chips/chips.prt';

PART_NAME
 R3831 'Q_RES_0402LF-0,5%,1/16W,CHIP,CS00002JB13':
 ROOM='NIC_P12V_MAM_TIC_BOM1';

SECTION_NUMBER 1
 '@T6G_MB_LIB.T6G(SCH_1):PAGE343_I77@PURE_QUANTA.Q_RES(CHIPS)':
 C_PATH='@t6g_mb_lib.t6g(sch_1):page343_i77@pure_quanta.q_res(chips)',
 P_PATH='@t6g_mb_lib.t6g(sch_1):page140_i77@pure_quanta.q_res(chips)',
 PATH='I77',
 DRAWING='@T6G_MB_LIB.T6G(SCH_1):PAGE343',
 WATTAGE='1/16W',
 TOLERANCE='5%',
 MATERIAL='CHIP',
 PHYS_PAGE='140',
 XY='(2925,6300)',
 ROT='0',
 VER='1',
 PACK_TYPE='0402LF',
 LOCATION='R3831',
 CDS_LIB='pure_quanta',
 CDS_PART_NAME='Q_RES_0402LF-0,5%,1/16W,CHIP,CS00002JB13',
 ROOM='NIC_P12V_MAM_TIC_BOM1',
 PART_NUMBER='CS00002JB13',
 VALUE='0',
 PRIM_FILE='./archive_libs/logical/q_res/chips/chips.prt';

PART_NAME
 R3832 'Q_RES_0402LF-0,5%,1/16W,EMPTY,CS00002JB13':
 ROOM='NIC_P3V3_BOM1';

SECTION_NUMBER 1
 '@T6G_MB_LIB.T6G(SCH_1):PAGE343_I127@PURE_QUANTA.Q_RES(CHIPS)':
 C_PATH='@t6g_mb_lib.t6g(sch_1):page343_i127@pure_quanta.q_res(chips)',
 P_PATH='@t6g_mb_lib.t6g(sch_1):page140_i127@pure_quanta.q_res(chips)',
 PATH='I127',
 DRAWING='@T6G_MB_LIB.T6G(SCH_1):PAGE343',
 WATTAGE='1/16W',
 TOLERANCE='5%',
 MATERIAL='EMPTY',
 PHYS_PAGE='140',
 XY='(3075,8625)',
 ROT='0',
 VER='1',
 PACK_TYPE='0402LF',
 LOCATION='R3832',
 CDS_LIB='pure_quanta',
 CDS_PART_NAME='Q_RES_0402LF-0,5%,1/16W,EMPTY,CS00002JB13',
 ROOM='NIC_P3V3_BOM1',
 PART_NUMBER='CS00002JB13',
 VALUE='0',
 PRIM_FILE='./archive_libs/logical/q_res/chips/chips.prt';

PART_NAME
 R3833 'Q_RES_0402LF-100K,1%,1/16W,CHIP,CS41002FB09':
 ROOM='NIC_P3V3_BOM1';

SECTION_NUMBER 1
 '@T6G_MB_LIB.T6G(SCH_1):PAGE343_I107@PURE_QUANTA.Q_RES(CHIPS)':
 C_PATH='@t6g_mb_lib.t6g(sch_1):page343_i107@pure_quanta.q_res(chips)',
 P_PATH='@t6g_mb_lib.t6g(sch_1):page140_i107@pure_quanta.q_res(chips)',
 PATH='I107',
 DRAWING='@T6G_MB_LIB.T6G(SCH_1):PAGE343',
 WATTAGE='1/16W',
 TOLERANCE='1%',
 MATERIAL='CHIP',
 PHYS_PAGE='140',
 XY='(3425,8925)',
 ROT='0',
 VER='2',
 PACK_TYPE='0402LF',
 LOCATION='R3833',
 CDS_LIB='pure_quanta',
 CDS_PART_NAME='Q_RES_0402LF-100K,1%,1/16W,CHIP,CS41002FB09',
 ROOM='NIC_P3V3_BOM1',
 PART_NUMBER='CS41002FB09',
 VALUE='100K',
 PRIM_FILE='./archive_libs/logical/q_res/chips/chips.prt';

PART_NAME
 R3834 'Q_RES_0402LF-0,5%,1/16W,EMPTY,CS00002JB13':
 ROOM='NIC_P12V_MPS_MAM_BOM2';

SECTION_NUMBER 1
 '@T6G_MB_LIB.T6G(SCH_1):PAGE339_I128@PURE_QUANTA.Q_RES(CHIPS)':
 C_PATH='@t6g_mb_lib.t6g(sch_1):page339_i128@pure_quanta.q_res(chips)',
 P_PATH='@t6g_mb_lib.t6g(sch_1):page135_i128@pure_quanta.q_res(chips)',
 PATH='I128',
 DRAWING='@T6G_MB_LIB.T6G(SCH_1):PAGE339',
 WATTAGE='1/16W',
 TOLERANCE='5%',
 MATERIAL='EMPTY',
 PHYS_PAGE='135',
 XY='(-7725,9600)',
 ROT='0',
 VER='1',
 PACK_TYPE='0402LF',
 LOCATION='R3834',
 CDS_LIB='pure_quanta',
 CDS_PART_NAME='Q_RES_0402LF-0,5%,1/16W,EMPTY,CS00002JB13',
 ROOM='NIC_P12V_MPS_MAM_BOM2',
 PART_NUMBER='CS00002JB13',
 VALUE='0',
 PRIM_FILE='./archive_libs/logical/q_res/chips/chips.prt';

PART_NAME
 R3836 'Q_RES_0402LF-10K,1%,1/16W,CHIP,CS31002FB08':
 ROOM='SCM_P12V_MPS_BOM2';

SECTION_NUMBER 1
 '@T6G_MB_LIB.T6G(SCH_1):PAGE350_I43@PURE_QUANTA.Q_RES(CHIPS)':
 C_PATH='@t6g_mb_lib.t6g(sch_1):page350_i43@pure_quanta.q_res(chips)',
 P_PATH='@t6g_mb_lib.t6g(sch_1):page152_i43@pure_quanta.q_res(chips)',
 PATH='I43',
 DRAWING='@T6G_MB_LIB.T6G(SCH_1):PAGE350',
 WATTAGE='1/16W',
 TOLERANCE='1%',
 MATERIAL='CHIP',
 PHYS_PAGE='152',
 XY='(2875,12775)',
 ROT='0',
 VER='2',
 PACK_TYPE='0402LF',
 LOCATION='R3836',
 CDS_LIB='pure_quanta',
 CDS_PART_NAME='Q_RES_0402LF-10K,1%,1/16W,CHIP,CS31002FB08',
 ROOM='SCM_P12V_MPS_BOM2',
 PART_NUMBER='CS31002FB08',
 VALUE='10K',
 PRIM_FILE='./archive_libs/logical/q_res/chips/chips.prt';

PART_NAME
 R3845 'Q_RES_0402LF-0,5%,1/16W,EMPTY,CS00002JB13':
 ROOM='NIC_P3V3_BOM2';

SECTION_NUMBER 1
 '@T6G_MB_LIB.T6G(SCH_1):PAGE339_I131@PURE_QUANTA.Q_RES(CHIPS)':
 C_PATH='@t6g_mb_lib.t6g(sch_1):page339_i131@pure_quanta.q_res(chips)',
 P_PATH='@t6g_mb_lib.t6g(sch_1):page135_i131@pure_quanta.q_res(chips)',
 PATH='I131',
 DRAWING='@T6G_MB_LIB.T6G(SCH_1):PAGE339',
 WATTAGE='1/16W',
 TOLERANCE='5%',
 MATERIAL='EMPTY',
 PHYS_PAGE='135',
 XY='(-3850,12575)',
 ROT='0',
 VER='1',
 PACK_TYPE='0402LF',
 LOCATION='R3845',
 CDS_LIB='pure_quanta',
 CDS_PART_NAME='Q_RES_0402LF-0,5%,1/16W,EMPTY,CS00002JB13',
 ROOM='NIC_P3V3_BOM2',
 PART_NUMBER='CS00002JB13',
 VALUE='0',
 PRIM_FILE='./archive_libs/logical/q_res/chips/chips.prt';

PART_NAME
 R3848 'Q_RES_0402LF-10K,1%,1/16W,CHIP,CS31002FB08':
 ROOM='NIC_P12V_MPS_MAM_BOM2';

SECTION_NUMBER 1
 '@T6G_MB_LIB.T6G(SCH_1):PAGE344_I27@PURE_QUANTA.Q_RES(CHIPS)':
 C_PATH='@t6g_mb_lib.t6g(sch_1):page344_i27@pure_quanta.q_res(chips)',
 P_PATH='@t6g_mb_lib.t6g(sch_1):page141_i27@pure_quanta.q_res(chips)',
 PATH='I27',
 DRAWING='@T6G_MB_LIB.T6G(SCH_1):PAGE344',
 WATTAGE='1/16W',
 TOLERANCE='1%',
 MATERIAL='CHIP',
 PHYS_PAGE='141',
 XY='(-1475,3600)',
 ROT='0',
 VER='2',
 PACK_TYPE='0402LF',
 LOCATION='R3848',
 CDS_LIB='pure_quanta',
 CDS_PART_NAME='Q_RES_0402LF-10K,1%,1/16W,CHIP,CS31002FB08',
 ROOM='NIC_P12V_MPS_MAM_BOM2',
 PART_NUMBER='CS31002FB08',
 VALUE='10K',
 PRIM_FILE='./archive_libs/logical/q_res/chips/chips.prt';

PART_NAME
 R3858 'Q_RES_0402LF-33.2,1%,1/16W,CHIP,CS03322FB03':;

SECTION_NUMBER 1
 '@T6G_MB_LIB.T6G(SCH_1):PAGE348_I96@PURE_QUANTA.Q_RES(CHIPS)':
 C_PATH='@t6g_mb_lib.t6g(sch_1):page348_i96@pure_quanta.q_res(chips)',
 P_PATH='@t6g_mb_lib.t6g(sch_1):page150_i96@pure_quanta.q_res(chips)',
 PATH='I96',
 DRAWING='@T6G_MB_LIB.T6G(SCH_1):PAGE348',
 WATTAGE='1/16W',
 TOLERANCE='1%',
 MATERIAL='CHIP',
 PHYS_PAGE='150',
 XY='(-14925,8125)',
 ROT='0',
 VER='1',
 PACK_TYPE='0402LF',
 LOCATION='R3858',
 CDS_LIB='pure_quanta',
 CDS_PART_NAME='Q_RES_0402LF-33.2,1%,1/16W,CHIP,CS03322FB03',
 PART_NUMBER='CS03322FB03',
 VALUE='33.2',
 PRIM_FILE='./archive_libs/logical/q_res/chips/chips.prt';

PART_NAME
 R3859 'Q_RES_0402LF-0,5%,1/16W,EMPTY,CS00002JB13':;

SECTION_NUMBER 1
 '@T6G_MB_LIB.T6G(SCH_1):PAGE369_I107@PURE_QUANTA.Q_RES(CHIPS)':
 C_PATH='@t6g_mb_lib.t6g(sch_1):page369_i107@pure_quanta.q_res(chips)',
 P_PATH='@t6g_mb_lib.t6g(sch_1):page257_i107@pure_quanta.q_res(chips)',
 PATH='I107',
 DRAWING='@T6G_MB_LIB.T6G(SCH_1):PAGE369',
 WATTAGE='1/16W',
 TOLERANCE='5%',
 MATERIAL='EMPTY',
 PHYS_PAGE='257',
 XY='(-5675,5025)',
 ROT='0',
 VER='1',
 PACK_TYPE='0402LF',
 LOCATION='R3859',
 CDS_LIB='pure_quanta',
 CDS_PART_NAME='Q_RES_0402LF-0,5%,1/16W,EMPTY,CS00002JB13',
 PART_NUMBER='CS00002JB13',
 VALUE='0',
 PRIM_FILE='./archive_libs/logical/q_res/chips/chips.prt';

PART_NAME
 R3860 'Q_RES_0402LF-0,5%,1/16W,EMPTY,CS00002JB13':
 ROOM='ADC_MAM_BOM2';

SECTION_NUMBER 1
 '@T6G_MB_LIB.T6G(SCH_1):PAGE369_I83@PURE_QUANTA.Q_RES(CHIPS)':
 C_PATH='@t6g_mb_lib.t6g(sch_1):page369_i83@pure_quanta.q_res(chips)',
 P_PATH='@t6g_mb_lib.t6g(sch_1):page257_i83@pure_quanta.q_res(chips)',
 PATH='I83',
 DRAWING='@T6G_MB_LIB.T6G(SCH_1):PAGE369',
 WATTAGE='1/16W',
 TOLERANCE='5%',
 MATERIAL='EMPTY',
 PHYS_PAGE='257',
 XY='(-5675,4875)',
 ROT='0',
 VER='1',
 PACK_TYPE='0402LF',
 LOCATION='R3860',
 CDS_LIB='pure_quanta',
 CDS_PART_NAME='Q_RES_0402LF-0,5%,1/16W,EMPTY,CS00002JB13',
 ROOM='ADC_MAM_BOM2',
 PART_NUMBER='CS00002JB13',
 VALUE='0',
 PRIM_FILE='./archive_libs/logical/q_res/chips/chips.prt';

PART_NAME
 R3861 'Q_RES_0402LF-0,5%,1/16W,CHIP,CS00002JB13':
 ROOM='ADC_TI_BOM1';

SECTION_NUMBER 1
 '@T6G_MB_LIB.T6G(SCH_1):PAGE369_I82@PURE_QUANTA.Q_RES(CHIPS)':
 C_PATH='@t6g_mb_lib.t6g(sch_1):page369_i82@pure_quanta.q_res(chips)',
 P_PATH='@t6g_mb_lib.t6g(sch_1):page257_i82@pure_quanta.q_res(chips)',
 PATH='I82',
 DRAWING='@T6G_MB_LIB.T6G(SCH_1):PAGE369',
 WATTAGE='1/16W',
 TOLERANCE='5%',
 MATERIAL='CHIP',
 PHYS_PAGE='257',
 XY='(-5675,4525)',
 ROT='0',
 VER='1',
 PACK_TYPE='0402LF',
 LOCATION='R3861',
 CDS_LIB='pure_quanta',
 CDS_PART_NAME='Q_RES_0402LF-0,5%,1/16W,CHIP,CS00002JB13',
 ROOM='ADC_TI_BOM1',
 PART_NUMBER='CS00002JB13',
 VALUE='0',
 PRIM_FILE='./archive_libs/logical/q_res/chips/chips.prt';

PART_NAME
 R3862 'Q_RES_0402LF-0,5%,1/16W,EMPTY,CS00002JB13':
 ROOM='ADC_TI_BOM3';

SECTION_NUMBER 1
 '@T6G_MB_LIB.T6G(SCH_1):PAGE369_I81@PURE_QUANTA.Q_RES(CHIPS)':
 C_PATH='@t6g_mb_lib.t6g(sch_1):page369_i81@pure_quanta.q_res(chips)',
 P_PATH='@t6g_mb_lib.t6g(sch_1):page257_i81@pure_quanta.q_res(chips)',
 PATH='I81',
 DRAWING='@T6G_MB_LIB.T6G(SCH_1):PAGE369',
 WATTAGE='1/16W',
 TOLERANCE='5%',
 MATERIAL='EMPTY',
 PHYS_PAGE='257',
 XY='(-5675,4375)',
 ROT='0',
 VER='1',
 PACK_TYPE='0402LF',
 LOCATION='R3862',
 CDS_LIB='pure_quanta',
 CDS_PART_NAME='Q_RES_0402LF-0,5%,1/16W,EMPTY,CS00002JB13',
 ROOM='ADC_TI_BOM3',
 PART_NUMBER='CS00002JB13',
 VALUE='0',
 PRIM_FILE='./archive_libs/logical/q_res/chips/chips.prt';

PART_NAME
 R3863 'Q_RES_0402LF-0,5%,1/16W,EMPTY,CS00002JB13':;

SECTION_NUMBER 1
 '@T6G_MB_LIB.T6G(SCH_1):PAGE369_I115@PURE_QUANTA.Q_RES(CHIPS)':
 C_PATH='@t6g_mb_lib.t6g(sch_1):page369_i115@pure_quanta.q_res(chips)',
 P_PATH='@t6g_mb_lib.t6g(sch_1):page257_i115@pure_quanta.q_res(chips)',
 PATH='I115',
 DRAWING='@T6G_MB_LIB.T6G(SCH_1):PAGE369',
 WATTAGE='1/16W',
 TOLERANCE='5%',
 MATERIAL='EMPTY',
 PHYS_PAGE='257',
 XY='(-5650,6000)',
 ROT='0',
 VER='1',
 PACK_TYPE='0402LF',
 LOCATION='R3863',
 CDS_LIB='pure_quanta',
 CDS_PART_NAME='Q_RES_0402LF-0,5%,1/16W,EMPTY,CS00002JB13',
 PART_NUMBER='CS00002JB13',
 VALUE='0',
 PRIM_FILE='./archive_libs/logical/q_res/chips/chips.prt';

PART_NAME
 R3864 'Q_RES_0402LF-0,5%,1/16W,EMPTY,CS00002JB13':
 ROOM='ADC_MAM_BOM2';

SECTION_NUMBER 1
 '@T6G_MB_LIB.T6G(SCH_1):PAGE369_I110@PURE_QUANTA.Q_RES(CHIPS)':
 C_PATH='@t6g_mb_lib.t6g(sch_1):page369_i110@pure_quanta.q_res(chips)',
 P_PATH='@t6g_mb_lib.t6g(sch_1):page257_i110@pure_quanta.q_res(chips)',
 PATH='I110',
 DRAWING='@T6G_MB_LIB.T6G(SCH_1):PAGE369',
 WATTAGE='1/16W',
 TOLERANCE='5%',
 MATERIAL='EMPTY',
 PHYS_PAGE='257',
 XY='(-5650,5850)',
 ROT='0',
 VER='1',
 PACK_TYPE='0402LF',
 LOCATION='R3864',
 CDS_LIB='pure_quanta',
 CDS_PART_NAME='Q_RES_0402LF-0,5%,1/16W,EMPTY,CS00002JB13',
 ROOM='ADC_MAM_BOM2',
 PART_NUMBER='CS00002JB13',
 VALUE='0',
 PRIM_FILE='./archive_libs/logical/q_res/chips/chips.prt';

PART_NAME
 R3865 'Q_RES_0402LF-0,5%,1/16W,CHIP,CS00002JB13':
 ROOM='ADC_TI_BOM1';

SECTION_NUMBER 1
 '@T6G_MB_LIB.T6G(SCH_1):PAGE369_I109@PURE_QUANTA.Q_RES(CHIPS)':
 C_PATH='@t6g_mb_lib.t6g(sch_1):page369_i109@pure_quanta.q_res(chips)',
 P_PATH='@t6g_mb_lib.t6g(sch_1):page257_i109@pure_quanta.q_res(chips)',
 PATH='I109',
 DRAWING='@T6G_MB_LIB.T6G(SCH_1):PAGE369',
 WATTAGE='1/16W',
 TOLERANCE='5%',
 MATERIAL='CHIP',
 PHYS_PAGE='257',
 XY='(-5650,5500)',
 ROT='0',
 VER='1',
 PACK_TYPE='0402LF',
 LOCATION='R3865',
 CDS_LIB='pure_quanta',
 CDS_PART_NAME='Q_RES_0402LF-0,5%,1/16W,CHIP,CS00002JB13',
 ROOM='ADC_TI_BOM1',
 PART_NUMBER='CS00002JB13',
 VALUE='0',
 PRIM_FILE='./archive_libs/logical/q_res/chips/chips.prt';

PART_NAME
 R3866 'Q_RES_0402LF-0,5%,1/16W,EMPTY,CS00002JB13':
 ROOM='ADC_TI_BOM3';

SECTION_NUMBER 1
 '@T6G_MB_LIB.T6G(SCH_1):PAGE369_I108@PURE_QUANTA.Q_RES(CHIPS)':
 C_PATH='@t6g_mb_lib.t6g(sch_1):page369_i108@pure_quanta.q_res(chips)',
 P_PATH='@t6g_mb_lib.t6g(sch_1):page257_i108@pure_quanta.q_res(chips)',
 PATH='I108',
 DRAWING='@T6G_MB_LIB.T6G(SCH_1):PAGE369',
 WATTAGE='1/16W',
 TOLERANCE='5%',
 MATERIAL='EMPTY',
 PHYS_PAGE='257',
 XY='(-5650,5350)',
 ROT='0',
 VER='1',
 PACK_TYPE='0402LF',
 LOCATION='R3866',
 CDS_LIB='pure_quanta',
 CDS_PART_NAME='Q_RES_0402LF-0,5%,1/16W,EMPTY,CS00002JB13',
 ROOM='ADC_TI_BOM3',
 PART_NUMBER='CS00002JB13',
 VALUE='0',
 PRIM_FILE='./archive_libs/logical/q_res/chips/chips.prt';

PART_NAME
 R3867 'Q_RES_0402LF-0,5%,1/16W,EMPTY,CS00002JB13':;

SECTION_NUMBER 1
 '@T6G_MB_LIB.T6G(SCH_1):PAGE343_I74@PURE_QUANTA.Q_RES(CHIPS)':
 C_PATH='@t6g_mb_lib.t6g(sch_1):page343_i74@pure_quanta.q_res(chips)',
 P_PATH='@t6g_mb_lib.t6g(sch_1):page140_i74@pure_quanta.q_res(chips)',
 PATH='I74',
 DRAWING='@T6G_MB_LIB.T6G(SCH_1):PAGE343',
 WATTAGE='1/16W',
 TOLERANCE='5%',
 MATERIAL='EMPTY',
 PHYS_PAGE='140',
 XY='(3075,6100)',
 ROT='0',
 VER='1',
 PACK_TYPE='0402LF',
 LOCATION='R3867',
 CDS_LIB='pure_quanta',
 CDS_PART_NAME='Q_RES_0402LF-0,5%,1/16W,EMPTY,CS00002JB13',
 PART_NUMBER='CS00002JB13',
 VALUE='0',
 PRIM_FILE='./archive_libs/logical/q_res/chips/chips.prt';

PART_NAME
 R3868 'Q_RES_0402LF-0,5%,1/16W,CHIP,CS00002JB13':
 ROOM='NIC_P12V_MAM_TIC_BOM1';

SECTION_NUMBER 1
 '@T6G_MB_LIB.T6G(SCH_1):PAGE343_I73@PURE_QUANTA.Q_RES(CHIPS)':
 C_PATH='@t6g_mb_lib.t6g(sch_1):page343_i73@pure_quanta.q_res(chips)',
 P_PATH='@t6g_mb_lib.t6g(sch_1):page140_i73@pure_quanta.q_res(chips)',
 PATH='I73',
 DRAWING='@T6G_MB_LIB.T6G(SCH_1):PAGE343',
 WATTAGE='1/16W',
 TOLERANCE='5%',
 MATERIAL='CHIP',
 PHYS_PAGE='140',
 XY='(3075,5975)',
 ROT='0',
 VER='1',
 PACK_TYPE='0402LF',
 LOCATION='R3868',
 CDS_LIB='pure_quanta',
 CDS_PART_NAME='Q_RES_0402LF-0,5%,1/16W,CHIP,CS00002JB13',
 ROOM='NIC_P12V_MAM_TIC_BOM1',
 PART_NUMBER='CS00002JB13',
 VALUE='0',
 PRIM_FILE='./archive_libs/logical/q_res/chips/chips.prt';

PART_NAME
 R3869 'Q_RES_0402LF-0,5%,1/16W,EMPTY,CS00002JB13':;

SECTION_NUMBER 1
 '@T6G_MB_LIB.T6G(SCH_1):PAGE338_I82@PURE_QUANTA.Q_RES(CHIPS)':
 C_PATH='@t6g_mb_lib.t6g(sch_1):page338_i82@pure_quanta.q_res(chips)',
 P_PATH='@t6g_mb_lib.t6g(sch_1):page134_i82@pure_quanta.q_res(chips)',
 PATH='I82',
 DRAWING='@T6G_MB_LIB.T6G(SCH_1):PAGE338',
 WATTAGE='1/16W',
 TOLERANCE='5%',
 MATERIAL='EMPTY',
 PHYS_PAGE='134',
 XY='(9375,10525)',
 ROT='0',
 VER='1',
 PACK_TYPE='0402LF',
 LOCATION='R3869',
 CDS_LIB='pure_quanta',
 CDS_PART_NAME='Q_RES_0402LF-0,5%,1/16W,EMPTY,CS00002JB13',
 PART_NUMBER='CS00002JB13',
 VALUE='0',
 PRIM_FILE='./archive_libs/logical/q_res/chips/chips.prt';

PART_NAME
 R3870 'Q_RES_0402LF-0,5%,1/16W,CHIP,CS00002JB13':
 ROOM='NIC_P12V_MAM_TIC_BOM1';

SECTION_NUMBER 1
 '@T6G_MB_LIB.T6G(SCH_1):PAGE338_I80@PURE_QUANTA.Q_RES(CHIPS)':
 C_PATH='@t6g_mb_lib.t6g(sch_1):page338_i80@pure_quanta.q_res(chips)',
 P_PATH='@t6g_mb_lib.t6g(sch_1):page134_i80@pure_quanta.q_res(chips)',
 PATH='I80',
 DRAWING='@T6G_MB_LIB.T6G(SCH_1):PAGE338',
 WATTAGE='1/16W',
 TOLERANCE='5%',
 MATERIAL='CHIP',
 PHYS_PAGE='134',
 XY='(9375,10400)',
 ROT='0',
 VER='1',
 PACK_TYPE='0402LF',
 LOCATION='R3870',
 CDS_LIB='pure_quanta',
 CDS_PART_NAME='Q_RES_0402LF-0,5%,1/16W,CHIP,CS00002JB13',
 ROOM='NIC_P12V_MAM_TIC_BOM1',
 PART_NUMBER='CS00002JB13',
 VALUE='0',
 PRIM_FILE='./archive_libs/logical/q_res/chips/chips.prt';

PART_NAME
 R3871 'Q_RES_0402LF-0,5%,1/16W,CHIP,CS00002JB13':
 ROOM='NIC_P12V_MPS_MAM_BOM2';

SECTION_NUMBER 1
 '@T6G_MB_LIB.T6G(SCH_1):PAGE339_I85@PURE_QUANTA.Q_RES(CHIPS)':
 C_PATH='@t6g_mb_lib.t6g(sch_1):page339_i85@pure_quanta.q_res(chips)',
 P_PATH='@t6g_mb_lib.t6g(sch_1):page135_i85@pure_quanta.q_res(chips)',
 PATH='I85',
 DRAWING='@T6G_MB_LIB.T6G(SCH_1):PAGE339',
 WATTAGE='1/16W',
 TOLERANCE='5%',
 MATERIAL='CHIP',
 PHYS_PAGE='135',
 XY='(-3975,8575)',
 ROT='0',
 VER='1',
 PACK_TYPE='0402LF',
 LOCATION='R3871',
 CDS_LIB='pure_quanta',
 CDS_PART_NAME='Q_RES_0402LF-0,5%,1/16W,CHIP,CS00002JB13',
 ROOM='NIC_P12V_MPS_MAM_BOM2',
 PART_NUMBER='CS00002JB13',
 VALUE='0',
 PRIM_FILE='./archive_libs/logical/q_res/chips/chips.prt';

PART_NAME
 R3872 'Q_RES_0402LF-0,5%,1/16W,EMPTY,CS00002JB13':
 ROOM='NIC_P12V_MPS_TIC_BOM3';

SECTION_NUMBER 1
 '@T6G_MB_LIB.T6G(SCH_1):PAGE339_I84@PURE_QUANTA.Q_RES(CHIPS)':
 C_PATH='@t6g_mb_lib.t6g(sch_1):page339_i84@pure_quanta.q_res(chips)',
 P_PATH='@t6g_mb_lib.t6g(sch_1):page135_i84@pure_quanta.q_res(chips)',
 PATH='I84',
 DRAWING='@T6G_MB_LIB.T6G(SCH_1):PAGE339',
 WATTAGE='1/16W',
 TOLERANCE='5%',
 MATERIAL='EMPTY',
 PHYS_PAGE='135',
 XY='(-3975,8400)',
 ROT='0',
 VER='1',
 PACK_TYPE='0402LF',
 LOCATION='R3872',
 CDS_LIB='pure_quanta',
 CDS_PART_NAME='Q_RES_0402LF-0,5%,1/16W,EMPTY,CS00002JB13',
 ROOM='NIC_P12V_MPS_TIC_BOM3',
 PART_NUMBER='CS00002JB13',
 VALUE='0',
 PRIM_FILE='./archive_libs/logical/q_res/chips/chips.prt';

PART_NAME
 R3873 'Q_RES_0402LF-0,5%,1/16W,CHIP,CS00002JB13':
 ROOM='NIC_P12V_MPS_MAM_BOM2';

SECTION_NUMBER 1
 '@T6G_MB_LIB.T6G(SCH_1):PAGE344_I23@PURE_QUANTA.Q_RES(CHIPS)':
 C_PATH='@t6g_mb_lib.t6g(sch_1):page344_i23@pure_quanta.q_res(chips)',
 P_PATH='@t6g_mb_lib.t6g(sch_1):page141_i23@pure_quanta.q_res(chips)',
 PATH='I23',
 DRAWING='@T6G_MB_LIB.T6G(SCH_1):PAGE344',
 WATTAGE='1/16W',
 TOLERANCE='5%',
 MATERIAL='CHIP',
 PHYS_PAGE='141',
 XY='(425,2075)',
 ROT='0',
 VER='1',
 PACK_TYPE='0402LF',
 LOCATION='R3873',
 CDS_LIB='pure_quanta',
 CDS_PART_NAME='Q_RES_0402LF-0,5%,1/16W,CHIP,CS00002JB13',
 ROOM='NIC_P12V_MPS_MAM_BOM2',
 PART_NUMBER='CS00002JB13',
 VALUE='0',
 PRIM_FILE='./archive_libs/logical/q_res/chips/chips.prt';

PART_NAME
 R3874 'Q_RES_0402LF-0,5%,1/16W,EMPTY,CS00002JB13':
 ROOM='NIC_P12V_MPS_TIC_BOM3';

SECTION_NUMBER 1
 '@T6G_MB_LIB.T6G(SCH_1):PAGE344_I22@PURE_QUANTA.Q_RES(CHIPS)':
 C_PATH='@t6g_mb_lib.t6g(sch_1):page344_i22@pure_quanta.q_res(chips)',
 P_PATH='@t6g_mb_lib.t6g(sch_1):page141_i22@pure_quanta.q_res(chips)',
 PATH='I22',
 DRAWING='@T6G_MB_LIB.T6G(SCH_1):PAGE344',
 WATTAGE='1/16W',
 TOLERANCE='5%',
 MATERIAL='EMPTY',
 PHYS_PAGE='141',
 XY='(425,1950)',
 ROT='0',
 VER='1',
 PACK_TYPE='0402LF',
 LOCATION='R3874',
 CDS_LIB='pure_quanta',
 CDS_PART_NAME='Q_RES_0402LF-0,5%,1/16W,EMPTY,CS00002JB13',
 ROOM='NIC_P12V_MPS_TIC_BOM3',
 PART_NUMBER='CS00002JB13',
 VALUE='0',
 PRIM_FILE='./archive_libs/logical/q_res/chips/chips.prt';

PART_NAME
 R3907 'Q_RES_0402LF-33K,1%,1/16W,CHIP,CS33302FB00':;

SECTION_NUMBER 1
 '@T6G_MB_LIB.T6G(SCH_1):PAGE372_I10@PURE_QUANTA.Q_RES(CHIPS)':
 C_PATH='@t6g_mb_lib.t6g(sch_1):page372_i10@pure_quanta.q_res(chips)',
 P_PATH='@t6g_mb_lib.t6g(sch_1):page268_i10@pure_quanta.q_res(chips)',
 PATH='I10',
 DRAWING='@T6G_MB_LIB.T6G(SCH_1):PAGE372',
 WATTAGE='1/16W',
 TOLERANCE='1%',
 MATERIAL='CHIP',
 PHYS_PAGE='268',
 XY='(-7950,600)',
 ROT='0',
 VER='2',
 PACK_TYPE='0402LF',
 LOCATION='R3907',
 CDS_LIB='pure_quanta',
 CDS_PART_NAME='Q_RES_0402LF-33K,1%,1/16W,CHIP,CS33302FB00',
 PART_NUMBER='CS33302FB00',
 VALUE='33K',
 PRIM_FILE='./archive_libs/logical/q_res/chips/chips.prt';

PART_NAME
 R3909 'Q_RES_0402LF-33.2,1%,1/16W,CHIP,CS03322FB03':
 ROOM='HSC BOM1';

SECTION_NUMBER 1
 '@T6G_MB_LIB.T6G(SCH_1):PAGE267_I37@PURE_QUANTA.Q_RES(CHIPS)':
 C_PATH='@t6g_mb_lib.t6g(sch_1):page267_i37@pure_quanta.q_res(chips)',
 P_PATH='@t6g_mb_lib.t6g(sch_1):page262_i37@pure_quanta.q_res(chips)',
 PATH='I37',
 DRAWING='@T6G_MB_LIB.T6G(SCH_1):PAGE267',
 WATTAGE='1/16W',
 TOLERANCE='1%',
 MATERIAL='CHIP',
 PHYS_PAGE='262',
 XY='(-13675,3175)',
 ROT='0',
 VER='1',
 PACK_TYPE='0402LF',
 LOCATION='R3909',
 CDS_LIB='pure_quanta',
 CDS_PART_NAME='Q_RES_0402LF-33.2,1%,1/16W,CHIP,CS03322FB03',
 ROOM='HSC BOM1',
 PART_NUMBER='CS03322FB03',
 VALUE='33.2',
 PRIM_FILE='./archive_libs/logical/q_res/chips/chips.prt';

PART_NAME
 R3923 'Q_RES_0402LF-63.4K,1%,1/16W,CHIP,CS36342FB04':;

SECTION_NUMBER 1
 '@T6G_MB_LIB.T6G(SCH_1):PAGE372_I16@PURE_QUANTA.Q_RES(CHIPS)':
 C_PATH='@t6g_mb_lib.t6g(sch_1):page372_i16@pure_quanta.q_res(chips)',
 P_PATH='@t6g_mb_lib.t6g(sch_1):page268_i16@pure_quanta.q_res(chips)',
 PATH='I16',
 DRAWING='@T6G_MB_LIB.T6G(SCH_1):PAGE372',
 WATTAGE='1/16W',
 TOLERANCE='1%',
 MATERIAL='CHIP',
 PHYS_PAGE='268',
 XY='(-8000,1100)',
 ROT='0',
 VER='2',
 PACK_TYPE='0402LF',
 LOCATION='R3923',
 CDS_LIB='pure_quanta',
 CDS_PART_NAME='Q_RES_0402LF-63.4K,1%,1/16W,CHIP,CS36342FB04',
 PART_NUMBER='CS36342FB04',
 VALUE='63.4K',
 PRIM_FILE='./archive_libs/logical/q_res/chips/chips.prt';

PART_NAME
 R3924 'Q_RES_0402LF-0,5%,1/16W,CHIP,CS00002JB13':
 ROOM='HSC BOM1';

SECTION_NUMBER 1
 '@T6G_MB_LIB.T6G(SCH_1):PAGE267_I24@PURE_QUANTA.Q_RES(CHIPS)':
 C_PATH='@t6g_mb_lib.t6g(sch_1):page267_i24@pure_quanta.q_res(chips)',
 P_PATH='@t6g_mb_lib.t6g(sch_1):page262_i24@pure_quanta.q_res(chips)',
 PATH='I24',
 DRAWING='@T6G_MB_LIB.T6G(SCH_1):PAGE267',
 WATTAGE='1/16W',
 TOLERANCE='5%',
 MATERIAL='CHIP',
 PHYS_PAGE='262',
 XY='(-14625,2500)',
 ROT='0',
 VER='1',
 PACK_TYPE='0402LF',
 LOCATION='R3924',
 CDS_LIB='pure_quanta',
 CDS_PART_NAME='Q_RES_0402LF-0,5%,1/16W,CHIP,CS00002JB13',
 ROOM='HSC BOM1',
 PART_NUMBER='CS00002JB13',
 VALUE='0',
 PRIM_FILE='./archive_libs/logical/q_res/chips/chips.prt';

PART_NAME
 R3925 'Q_RES_0402LF-1K,1%,1/16W,CHIP,CS21002FB06':
 ROOM='HSC BOM1';

SECTION_NUMBER 1
 '@T6G_MB_LIB.T6G(SCH_1):PAGE267_I34@PURE_QUANTA.Q_RES(CHIPS)':
 C_PATH='@t6g_mb_lib.t6g(sch_1):page267_i34@pure_quanta.q_res(chips)',
 P_PATH='@t6g_mb_lib.t6g(sch_1):page262_i34@pure_quanta.q_res(chips)',
 PATH='I34',
 DRAWING='@T6G_MB_LIB.T6G(SCH_1):PAGE267',
 WATTAGE='1/16W',
 TOLERANCE='1%',
 MATERIAL='CHIP',
 PHYS_PAGE='262',
 XY='(-14225,2675)',
 ROT='1',
 VER='1',
 PACK_TYPE='0402LF',
 LOCATION='R3925',
 CDS_LIB='pure_quanta',
 CDS_PART_NAME='Q_RES_0402LF-1K,1%,1/16W,CHIP,CS21002FB06',
 ROOM='HSC BOM1',
 PART_NUMBER='CS21002FB06',
 VALUE='1K',
 PRIM_FILE='./archive_libs/logical/q_res/chips/chips.prt';

PART_NAME
 R3933 'Q_RES_0402LF-16.9K,1%,1/16W,CHIP,CS31692FB03':
 ROOM='HSC BOM1';

SECTION_NUMBER 1
 '@T6G_MB_LIB.T6G(SCH_1):PAGE267_I63@PURE_QUANTA.Q_RES(CHIPS)':
 C_PATH='@t6g_mb_lib.t6g(sch_1):page267_i63@pure_quanta.q_res(chips)',
 P_PATH='@t6g_mb_lib.t6g(sch_1):page262_i63@pure_quanta.q_res(chips)',
 PATH='I63',
 DRAWING='@T6G_MB_LIB.T6G(SCH_1):PAGE267',
 WATTAGE='1/16W',
 TOLERANCE='1%',
 MATERIAL='CHIP',
 PHYS_PAGE='262',
 XY='(-9975,1900)',
 ROT='0',
 VER='2',
 PACK_TYPE='0402LF',
 LOCATION='R3933',
 CDS_LIB='pure_quanta',
 CDS_PART_NAME='Q_RES_0402LF-16.9K,1%,1/16W,CHIP,CS31692FB03',
 ROOM='HSC BOM1',
 PART_NUMBER='CS31692FB03',
 VALUE='16.9K',
 PRIM_FILE='./archive_libs/logical/q_res/chips/chips.prt';

PART_NAME
 R3934 'Q_RES_0402LF-22,1%,1/16W,CHIP,CS02202FB02':
 ROOM='HSC BOM1';

SECTION_NUMBER 1
 '@T6G_MB_LIB.T6G(SCH_1):PAGE267_I80@PURE_QUANTA.Q_RES(CHIPS)':
 C_PATH='@t6g_mb_lib.t6g(sch_1):page267_i80@pure_quanta.q_res(chips)',
 P_PATH='@t6g_mb_lib.t6g(sch_1):page262_i80@pure_quanta.q_res(chips)',
 PATH='I80',
 DRAWING='@T6G_MB_LIB.T6G(SCH_1):PAGE267',
 WATTAGE='1/16W',
 TOLERANCE='1%',
 MATERIAL='CHIP',
 PHYS_PAGE='262',
 XY='(-8950,3400)',
 ROT='0',
 VER='1',
 PACK_TYPE='0402LF',
 LOCATION='R3934',
 CDS_LIB='pure_quanta',
 CDS_PART_NAME='Q_RES_0402LF-22,1%,1/16W,CHIP,CS02202FB02',
 ROOM='HSC BOM1',
 PART_NUMBER='CS02202FB02',
 VALUE='22',
 PRIM_FILE='./archive_libs/logical/q_res/chips/chips.prt';

PART_NAME
 R3936 'Q_RES_0402LF-4.7K,1%,1/16W,CHIP,CS24702FB06':
 ROOM='HSC BOM1';

SECTION_NUMBER 1
 '@T6G_MB_LIB.T6G(SCH_1):PAGE267_I91@PURE_QUANTA.Q_RES(CHIPS)':
 C_PATH='@t6g_mb_lib.t6g(sch_1):page267_i91@pure_quanta.q_res(chips)',
 P_PATH='@t6g_mb_lib.t6g(sch_1):page262_i91@pure_quanta.q_res(chips)',
 PATH='I91',
 DRAWING='@T6G_MB_LIB.T6G(SCH_1):PAGE267',
 WATTAGE='1/16W',
 TOLERANCE='1%',
 MATERIAL='CHIP',
 PHYS_PAGE='262',
 XY='(-8425,3900)',
 ROT='0',
 VER='2',
 PACK_TYPE='0402LF',
 LOCATION='R3936',
 CDS_LIB='pure_quanta',
 CDS_PART_NAME='Q_RES_0402LF-4.7K,1%,1/16W,CHIP,CS24702FB06',
 ROOM='HSC BOM1',
 PART_NUMBER='CS24702FB06',
 VALUE='4.7K',
 PRIM_FILE='./archive_libs/logical/q_res/chips/chips.prt';

PART_NAME
 R3939 'Q_RES_0402LF-0,5%,1/16W,EMPTY,CS00002JB13':;

SECTION_NUMBER 1
 '@T6G_MB_LIB.T6G(SCH_1):PAGE369_I80@PURE_QUANTA.Q_RES(CHIPS)':
 C_PATH='@t6g_mb_lib.t6g(sch_1):page369_i80@pure_quanta.q_res(chips)',
 P_PATH='@t6g_mb_lib.t6g(sch_1):page257_i80@pure_quanta.q_res(chips)',
 PATH='I80',
 DRAWING='@T6G_MB_LIB.T6G(SCH_1):PAGE369',
 WATTAGE='1/16W',
 TOLERANCE='5%',
 MATERIAL='EMPTY',
 PHYS_PAGE='257',
 XY='(-5700,4025)',
 ROT='0',
 VER='1',
 PACK_TYPE='0402LF',
 LOCATION='R3939',
 CDS_LIB='pure_quanta',
 CDS_PART_NAME='Q_RES_0402LF-0,5%,1/16W,EMPTY,CS00002JB13',
 PART_NUMBER='CS00002JB13',
 VALUE='0',
 PRIM_FILE='./archive_libs/logical/q_res/chips/chips.prt';

PART_NAME
 R3940 'Q_RES_0402LF-0,5%,1/16W,EMPTY,CS00002JB13':
 ROOM='ADC_MAM_BOM2';

SECTION_NUMBER 1
 '@T6G_MB_LIB.T6G(SCH_1):PAGE369_I79@PURE_QUANTA.Q_RES(CHIPS)':
 C_PATH='@t6g_mb_lib.t6g(sch_1):page369_i79@pure_quanta.q_res(chips)',
 P_PATH='@t6g_mb_lib.t6g(sch_1):page257_i79@pure_quanta.q_res(chips)',
 PATH='I79',
 DRAWING='@T6G_MB_LIB.T6G(SCH_1):PAGE369',
 WATTAGE='1/16W',
 TOLERANCE='5%',
 MATERIAL='EMPTY',
 PHYS_PAGE='257',
 XY='(-5700,3875)',
 ROT='0',
 VER='1',
 PACK_TYPE='0402LF',
 LOCATION='R3940',
 CDS_LIB='pure_quanta',
 CDS_PART_NAME='Q_RES_0402LF-0,5%,1/16W,EMPTY,CS00002JB13',
 ROOM='ADC_MAM_BOM2',
 PART_NUMBER='CS00002JB13',
 VALUE='0',
 PRIM_FILE='./archive_libs/logical/q_res/chips/chips.prt';

PART_NAME
 R3941 'Q_RES_0402LF-0,5%,1/16W,CHIP,CS00002JB13':
 ROOM='ADC_TI_BOM1';

SECTION_NUMBER 1
 '@T6G_MB_LIB.T6G(SCH_1):PAGE369_I74@PURE_QUANTA.Q_RES(CHIPS)':
 C_PATH='@t6g_mb_lib.t6g(sch_1):page369_i74@pure_quanta.q_res(chips)',
 P_PATH='@t6g_mb_lib.t6g(sch_1):page257_i74@pure_quanta.q_res(chips)',
 PATH='I74',
 DRAWING='@T6G_MB_LIB.T6G(SCH_1):PAGE369',
 WATTAGE='1/16W',
 TOLERANCE='5%',
 MATERIAL='CHIP',
 PHYS_PAGE='257',
 XY='(-5700,3525)',
 ROT='0',
 VER='1',
 PACK_TYPE='0402LF',
 LOCATION='R3941',
 CDS_LIB='pure_quanta',
 CDS_PART_NAME='Q_RES_0402LF-0,5%,1/16W,CHIP,CS00002JB13',
 ROOM='ADC_TI_BOM1',
 PART_NUMBER='CS00002JB13',
 VALUE='0',
 PRIM_FILE='./archive_libs/logical/q_res/chips/chips.prt';

PART_NAME
 R3942 'Q_RES_0402LF-0,5%,1/16W,EMPTY,CS00002JB13':
 ROOM='ADC_TI_BOM3';

SECTION_NUMBER 1
 '@T6G_MB_LIB.T6G(SCH_1):PAGE369_I73@PURE_QUANTA.Q_RES(CHIPS)':
 C_PATH='@t6g_mb_lib.t6g(sch_1):page369_i73@pure_quanta.q_res(chips)',
 P_PATH='@t6g_mb_lib.t6g(sch_1):page257_i73@pure_quanta.q_res(chips)',
 PATH='I73',
 DRAWING='@T6G_MB_LIB.T6G(SCH_1):PAGE369',
 WATTAGE='1/16W',
 TOLERANCE='5%',
 MATERIAL='EMPTY',
 PHYS_PAGE='257',
 XY='(-5700,3375)',
 ROT='0',
 VER='1',
 PACK_TYPE='0402LF',
 LOCATION='R3942',
 CDS_LIB='pure_quanta',
 CDS_PART_NAME='Q_RES_0402LF-0,5%,1/16W,EMPTY,CS00002JB13',
 ROOM='ADC_TI_BOM3',
 PART_NUMBER='CS00002JB13',
 VALUE='0',
 PRIM_FILE='./archive_libs/logical/q_res/chips/chips.prt';

PART_NAME
 R3943 'Q_RES_0402LF-0,5%,1/16W,CHIP,CS00002JB13':
 ROOM='E1S_P12V_MPS_MAM_BOM2';

SECTION_NUMBER 1
 '@T6G_MB_LIB.T6G(SCH_1):PAGE323_I19@PURE_QUANTA.Q_RES(CHIPS)':
 C_PATH='@t6g_mb_lib.t6g(sch_1):page323_i19@pure_quanta.q_res(chips)',
 P_PATH='@t6g_mb_lib.t6g(sch_1):page147_i19@pure_quanta.q_res(chips)',
 PATH='I19',
 DRAWING='@T6G_MB_LIB.T6G(SCH_1):PAGE323',
 WATTAGE='1/16W',
 TOLERANCE='5%',
 MATERIAL='CHIP',
 PHYS_PAGE='147',
 XY='(-1275,1425)',
 ROT='0',
 VER='1',
 PACK_TYPE='0402LF',
 LOCATION='R3943',
 CDS_LIB='pure_quanta',
 CDS_PART_NAME='Q_RES_0402LF-0,5%,1/16W,CHIP,CS00002JB13',
 ROOM='E1S_P12V_MPS_MAM_BOM2',
 PART_NUMBER='CS00002JB13',
 VALUE='0',
 PRIM_FILE='./archive_libs/logical/q_res/chips/chips.prt';

PART_NAME
 R3946 'Q_RES_0402LF-0,5%,1/16W,CHIP,CS00002JB13':
 ROOM='E1S_P3V3_BOM2';

SECTION_NUMBER 1
 '@T6G_MB_LIB.T6G(SCH_1):PAGE323_I5@PURE_QUANTA.Q_RES(CHIPS)':
 C_PATH='@t6g_mb_lib.t6g(sch_1):page323_i5@pure_quanta.q_res(chips)',
 P_PATH='@t6g_mb_lib.t6g(sch_1):page147_i5@pure_quanta.q_res(chips)',
 PATH='I5',
 DRAWING='@T6G_MB_LIB.T6G(SCH_1):PAGE323',
 WATTAGE='1/16W',
 TOLERANCE='5%',
 MATERIAL='CHIP',
 PHYS_PAGE='147',
 XY='(750,-1350)',
 ROT='0',
 VER='1',
 PACK_TYPE='0402LF',
 LOCATION='R3946',
 CDS_LIB='pure_quanta',
 CDS_PART_NAME='Q_RES_0402LF-0,5%,1/16W,CHIP,CS00002JB13',
 ROOM='E1S_P3V3_BOM2',
 PART_NUMBER='CS00002JB13',
 VALUE='0',
 PRIM_FILE='./archive_libs/logical/q_res/chips/chips.prt';

PART_NAME
 R3948 'Q_RES_0402LF-10K,1%,1/16W,CHIP,CS31002FB08':
 ROOM='E1S_P12V_MPS_MAM_BOM2';

SECTION_NUMBER 1
 '@T6G_MB_LIB.T6G(SCH_1):PAGE323_I37@PURE_QUANTA.Q_RES(CHIPS)':
 C_PATH='@t6g_mb_lib.t6g(sch_1):page323_i37@pure_quanta.q_res(chips)',
 P_PATH='@t6g_mb_lib.t6g(sch_1):page147_i37@pure_quanta.q_res(chips)',
 PATH='I37',
 DRAWING='@T6G_MB_LIB.T6G(SCH_1):PAGE323',
 WATTAGE='1/16W',
 TOLERANCE='1%',
 MATERIAL='CHIP',
 PHYS_PAGE='147',
 XY='(525,2000)',
 ROT='0',
 VER='2',
 PACK_TYPE='0402LF',
 LOCATION='R3948',
 CDS_LIB='pure_quanta',
 CDS_PART_NAME='Q_RES_0402LF-10K,1%,1/16W,CHIP,CS31002FB08',
 ROOM='E1S_P12V_MPS_MAM_BOM2',
 PART_NUMBER='CS31002FB08',
 VALUE='10K',
 PRIM_FILE='./archive_libs/logical/q_res/chips/chips.prt';

PART_NAME
 R3955 'Q_RES_0402LF-0,5%,1/16W,CHIP,CS00002JB13':
 ROOM='E1S_P12V_MPS_MAM_BOM2';

SECTION_NUMBER 1
 '@T6G_MB_LIB.T6G(SCH_1):PAGE323_I48@PURE_QUANTA.Q_RES(CHIPS)':
 C_PATH='@t6g_mb_lib.t6g(sch_1):page323_i48@pure_quanta.q_res(chips)',
 P_PATH='@t6g_mb_lib.t6g(sch_1):page147_i48@pure_quanta.q_res(chips)',
 PATH='I48',
 DRAWING='@T6G_MB_LIB.T6G(SCH_1):PAGE323',
 WATTAGE='1/16W',
 TOLERANCE='5%',
 MATERIAL='CHIP',
 PHYS_PAGE='147',
 XY='(2475,400)',
 ROT='0',
 VER='1',
 PACK_TYPE='0402LF',
 LOCATION='R3955',
 CDS_LIB='pure_quanta',
 CDS_PART_NAME='Q_RES_0402LF-0,5%,1/16W,CHIP,CS00002JB13',
 ROOM='E1S_P12V_MPS_MAM_BOM2',
 PART_NUMBER='CS00002JB13',
 VALUE='0',
 PRIM_FILE='./archive_libs/logical/q_res/chips/chips.prt';

PART_NAME
 R3956 'Q_RES_0402LF-0,5%,1/16W,EMPTY,CS00002JB13':
 ROOM='E1S_P12V_MPS_TIC_BOM3';

SECTION_NUMBER 1
 '@T6G_MB_LIB.T6G(SCH_1):PAGE323_I47@PURE_QUANTA.Q_RES(CHIPS)':
 C_PATH='@t6g_mb_lib.t6g(sch_1):page323_i47@pure_quanta.q_res(chips)',
 P_PATH='@t6g_mb_lib.t6g(sch_1):page147_i47@pure_quanta.q_res(chips)',
 PATH='I47',
 DRAWING='@T6G_MB_LIB.T6G(SCH_1):PAGE323',
 WATTAGE='1/16W',
 TOLERANCE='5%',
 MATERIAL='EMPTY',
 PHYS_PAGE='147',
 XY='(2475,225)',
 ROT='0',
 VER='1',
 PACK_TYPE='0402LF',
 LOCATION='R3956',
 CDS_LIB='pure_quanta',
 CDS_PART_NAME='Q_RES_0402LF-0,5%,1/16W,EMPTY,CS00002JB13',
 ROOM='E1S_P12V_MPS_TIC_BOM3',
 PART_NUMBER='CS00002JB13',
 VALUE='0',
 PRIM_FILE='./archive_libs/logical/q_res/chips/chips.prt';

PART_NAME
 R3958 'Q_RES_0402LF-0,5%,1/16W,CHIP,CS00002JB13':
 ROOM='E1S_P12V_MAM_TIC_BOM1';

SECTION_NUMBER 1
 '@T6G_MB_LIB.T6G(SCH_1):PAGE324_I29@PURE_QUANTA.Q_RES(CHIPS)':
 C_PATH='@t6g_mb_lib.t6g(sch_1):page324_i29@pure_quanta.q_res(chips)',
 P_PATH='@t6g_mb_lib.t6g(sch_1):page146_i29@pure_quanta.q_res(chips)',
 PATH='I29',
 DRAWING='@T6G_MB_LIB.T6G(SCH_1):PAGE324',
 WATTAGE='1/16W',
 TOLERANCE='5%',
 MATERIAL='CHIP',
 PHYS_PAGE='146',
 XY='(-725,750)',
 ROT='0',
 VER='1',
 PACK_TYPE='0402LF',
 LOCATION='R3958',
 CDS_LIB='pure_quanta',
 CDS_PART_NAME='Q_RES_0402LF-0,5%,1/16W,CHIP,CS00002JB13',
 ROOM='E1S_P12V_MAM_TIC_BOM1',
 PART_NUMBER='CS00002JB13',
 VALUE='0',
 PRIM_FILE='./archive_libs/logical/q_res/chips/chips.prt';

PART_NAME
 R3959 'Q_RES_0402LF-0,5%,1/16W,CHIP,CS00002JB13':
 ROOM='E1S_P3V3_BOM1';

SECTION_NUMBER 1
 '@T6G_MB_LIB.T6G(SCH_1):PAGE324_I18@PURE_QUANTA.Q_RES(CHIPS)':
 C_PATH='@t6g_mb_lib.t6g(sch_1):page324_i18@pure_quanta.q_res(chips)',
 P_PATH='@t6g_mb_lib.t6g(sch_1):page146_i18@pure_quanta.q_res(chips)',
 PATH='I18',
 DRAWING='@T6G_MB_LIB.T6G(SCH_1):PAGE324',
 WATTAGE='1/16W',
 TOLERANCE='5%',
 MATERIAL='CHIP',
 PHYS_PAGE='146',
 XY='(-600,-1950)',
 ROT='0',
 VER='1',
 PACK_TYPE='0402LF',
 LOCATION='R3959',
 CDS_LIB='pure_quanta',
 CDS_PART_NAME='Q_RES_0402LF-0,5%,1/16W,CHIP,CS00002JB13',
 ROOM='E1S_P3V3_BOM1',
 PART_NUMBER='CS00002JB13',
 VALUE='0',
 PRIM_FILE='./archive_libs/logical/q_res/chips/chips.prt';

PART_NAME
 R3972 'Q_RES_0402LF-0,5%,1/16W,CHIP,CS00002JB13':
 ROOM='E1S_P12V_MAM_TIC_BOM1';

SECTION_NUMBER 1
 '@T6G_MB_LIB.T6G(SCH_1):PAGE324_I71@PURE_QUANTA.Q_RES(CHIPS)':
 C_PATH='@t6g_mb_lib.t6g(sch_1):page324_i71@pure_quanta.q_res(chips)',
 P_PATH='@t6g_mb_lib.t6g(sch_1):page146_i71@pure_quanta.q_res(chips)',
 PATH='I71',
 DRAWING='@T6G_MB_LIB.T6G(SCH_1):PAGE324',
 WATTAGE='1/16W',
 TOLERANCE='5%',
 MATERIAL='CHIP',
 PHYS_PAGE='146',
 XY='(2950,650)',
 ROT='0',
 VER='1',
 PACK_TYPE='0402LF',
 LOCATION='R3972',
 CDS_LIB='pure_quanta',
 CDS_PART_NAME='Q_RES_0402LF-0,5%,1/16W,CHIP,CS00002JB13',
 ROOM='E1S_P12V_MAM_TIC_BOM1',
 PART_NUMBER='CS00002JB13',
 VALUE='0',
 PRIM_FILE='./archive_libs/logical/q_res/chips/chips.prt';

PART_NAME
 R3973 'Q_RES_0402LF-0,5%,1/16W,CHIP,CS00002JB13':
 ROOM='E1S_P3V3_BOM1';

SECTION_NUMBER 1
 '@T6G_MB_LIB.T6G(SCH_1):PAGE324_I48@PURE_QUANTA.Q_RES(CHIPS)':
 C_PATH='@t6g_mb_lib.t6g(sch_1):page324_i48@pure_quanta.q_res(chips)',
 P_PATH='@t6g_mb_lib.t6g(sch_1):page146_i48@pure_quanta.q_res(chips)',
 PATH='I48',
 DRAWING='@T6G_MB_LIB.T6G(SCH_1):PAGE324',
 WATTAGE='1/16W',
 TOLERANCE='5%',
 MATERIAL='CHIP',
 PHYS_PAGE='146',
 XY='(2975,-2050)',
 ROT='0',
 VER='1',
 PACK_TYPE='0402LF',
 LOCATION='R3973',
 CDS_LIB='pure_quanta',
 CDS_PART_NAME='Q_RES_0402LF-0,5%,1/16W,CHIP,CS00002JB13',
 ROOM='E1S_P3V3_BOM1',
 PART_NUMBER='CS00002JB13',
 VALUE='0',
 PRIM_FILE='./archive_libs/logical/q_res/chips/chips.prt';

PART_NAME
 R3974 'Q_RES_0402LF-0,5%,1/16W,EMPTY,CS00002JB13':;

SECTION_NUMBER 1
 '@T6G_MB_LIB.T6G(SCH_1):PAGE324_I70@PURE_QUANTA.Q_RES(CHIPS)':
 C_PATH='@t6g_mb_lib.t6g(sch_1):page324_i70@pure_quanta.q_res(chips)',
 P_PATH='@t6g_mb_lib.t6g(sch_1):page146_i70@pure_quanta.q_res(chips)',
 PATH='I70',
 DRAWING='@T6G_MB_LIB.T6G(SCH_1):PAGE324',
 WATTAGE='1/16W',
 TOLERANCE='5%',
 MATERIAL='EMPTY',
 PHYS_PAGE='146',
 XY='(3100,450)',
 ROT='0',
 VER='1',
 PACK_TYPE='0402LF',
 LOCATION='R3974',
 CDS_LIB='pure_quanta',
 CDS_PART_NAME='Q_RES_0402LF-0,5%,1/16W,EMPTY,CS00002JB13',
 PART_NUMBER='CS00002JB13',
 VALUE='0',
 PRIM_FILE='./archive_libs/logical/q_res/chips/chips.prt';

PART_NAME
 R3975 'Q_RES_0402LF-0,5%,1/16W,CHIP,CS00002JB13':
 ROOM='E1S_P12V_MAM_TIC_BOM1';

SECTION_NUMBER 1
 '@T6G_MB_LIB.T6G(SCH_1):PAGE324_I87@PURE_QUANTA.Q_RES(CHIPS)':
 C_PATH='@t6g_mb_lib.t6g(sch_1):page324_i87@pure_quanta.q_res(chips)',
 P_PATH='@t6g_mb_lib.t6g(sch_1):page146_i87@pure_quanta.q_res(chips)',
 PATH='I87',
 DRAWING='@T6G_MB_LIB.T6G(SCH_1):PAGE324',
 WATTAGE='1/16W',
 TOLERANCE='5%',
 MATERIAL='CHIP',
 PHYS_PAGE='146',
 XY='(3100,225)',
 ROT='0',
 VER='1',
 PACK_TYPE='0402LF',
 LOCATION='R3975',
 CDS_LIB='pure_quanta',
 CDS_PART_NAME='Q_RES_0402LF-0,5%,1/16W,CHIP,CS00002JB13',
 ROOM='E1S_P12V_MAM_TIC_BOM1',
 PART_NUMBER='CS00002JB13',
 VALUE='0',
 PRIM_FILE='./archive_libs/logical/q_res/chips/chips.prt';

PART_NAME
 R3976 'Q_RES_0402LF-100K,1%,1/16W,CHIP,CS41002FB09':
 ROOM='E1S_P12V_MAM_TIC_BOM1';

SECTION_NUMBER 1
 '@T6G_MB_LIB.T6G(SCH_1):PAGE324_I76@PURE_QUANTA.Q_RES(CHIPS)':
 C_PATH='@t6g_mb_lib.t6g(sch_1):page324_i76@pure_quanta.q_res(chips)',
 P_PATH='@t6g_mb_lib.t6g(sch_1):page146_i76@pure_quanta.q_res(chips)',
 PATH='I76',
 DRAWING='@T6G_MB_LIB.T6G(SCH_1):PAGE324',
 WATTAGE='1/16W',
 TOLERANCE='1%',
 MATERIAL='CHIP',
 PHYS_PAGE='146',
 XY='(3300,900)',
 ROT='0',
 VER='2',
 PACK_TYPE='0402LF',
 LOCATION='R3976',
 CDS_LIB='pure_quanta',
 CDS_PART_NAME='Q_RES_0402LF-100K,1%,1/16W,CHIP,CS41002FB09',
 ROOM='E1S_P12V_MAM_TIC_BOM1',
 PART_NUMBER='CS41002FB09',
 VALUE='100K',
 PRIM_FILE='./archive_libs/logical/q_res/chips/chips.prt';

PART_NAME
 R3977 'Q_RES_0402LF-100K,1%,1/16W,CHIP,CS41002FB09':
 ROOM='E1S_P3V3_BOM1';

SECTION_NUMBER 1
 '@T6G_MB_LIB.T6G(SCH_1):PAGE324_I52@PURE_QUANTA.Q_RES(CHIPS)':
 C_PATH='@t6g_mb_lib.t6g(sch_1):page324_i52@pure_quanta.q_res(chips)',
 P_PATH='@t6g_mb_lib.t6g(sch_1):page146_i52@pure_quanta.q_res(chips)',
 PATH='I52',
 DRAWING='@T6G_MB_LIB.T6G(SCH_1):PAGE324',
 WATTAGE='1/16W',
 TOLERANCE='1%',
 MATERIAL='CHIP',
 PHYS_PAGE='146',
 XY='(3325,-1750)',
 ROT='0',
 VER='2',
 PACK_TYPE='0402LF',
 LOCATION='R3977',
 CDS_LIB='pure_quanta',
 CDS_PART_NAME='Q_RES_0402LF-100K,1%,1/16W,CHIP,CS41002FB09',
 ROOM='E1S_P3V3_BOM1',
 PART_NUMBER='CS41002FB09',
 VALUE='100K',
 PRIM_FILE='./archive_libs/logical/q_res/chips/chips.prt';

PART_NAME
 R3978 'Q_RES_0402LF-100K,1%,1/16W,CHIP,CS41002FB09':
 ROOM='E1S_P12V_MAM_TIC_BOM1';

SECTION_NUMBER 1
 '@T6G_MB_LIB.T6G(SCH_1):PAGE324_I86@PURE_QUANTA.Q_RES(CHIPS)':
 C_PATH='@t6g_mb_lib.t6g(sch_1):page324_i86@pure_quanta.q_res(chips)',
 P_PATH='@t6g_mb_lib.t6g(sch_1):page146_i86@pure_quanta.q_res(chips)',
 PATH='I86',
 DRAWING='@T6G_MB_LIB.T6G(SCH_1):PAGE324',
 WATTAGE='1/16W',
 TOLERANCE='1%',
 MATERIAL='CHIP',
 PHYS_PAGE='146',
 XY='(3725,900)',
 ROT='0',
 VER='2',
 PACK_TYPE='0402LF',
 LOCATION='R3978',
 CDS_LIB='pure_quanta',
 CDS_PART_NAME='Q_RES_0402LF-100K,1%,1/16W,CHIP,CS41002FB09',
 ROOM='E1S_P12V_MAM_TIC_BOM1',
 PART_NUMBER='CS41002FB09',
 VALUE='100K',
 PRIM_FILE='./archive_libs/logical/q_res/chips/chips.prt';

PART_NAME
 R3979 'Q_RES_0402LF-100K,1%,1/16W,CHIP,CS41002FB09':
 ROOM='E1S_P3V3_BOM1';

SECTION_NUMBER 1
 '@T6G_MB_LIB.T6G(SCH_1):PAGE324_I54@PURE_QUANTA.Q_RES(CHIPS)':
 C_PATH='@t6g_mb_lib.t6g(sch_1):page324_i54@pure_quanta.q_res(chips)',
 P_PATH='@t6g_mb_lib.t6g(sch_1):page146_i54@pure_quanta.q_res(chips)',
 PATH='I54',
 DRAWING='@T6G_MB_LIB.T6G(SCH_1):PAGE324',
 WATTAGE='1/16W',
 TOLERANCE='1%',
 MATERIAL='CHIP',
 PHYS_PAGE='146',
 XY='(3725,-1750)',
 ROT='0',
 VER='2',
 PACK_TYPE='0402LF',
 LOCATION='R3979',
 CDS_LIB='pure_quanta',
 CDS_PART_NAME='Q_RES_0402LF-100K,1%,1/16W,CHIP,CS41002FB09',
 ROOM='E1S_P3V3_BOM1',
 PART_NUMBER='CS41002FB09',
 VALUE='100K',
 PRIM_FILE='./archive_libs/logical/q_res/chips/chips.prt';

PART_NAME
 R3996 'Q_RES_0402LF-0,5%,1/16W,CHIP,CS00002JB13':;

SECTION_NUMBER 1
 '@T6G_MB_LIB.T6G(SCH_1):PAGE350_I17@PURE_QUANTA.Q_RES(CHIPS)':
 C_PATH='@t6g_mb_lib.t6g(sch_1):page350_i17@pure_quanta.q_res(chips)',
 P_PATH='@t6g_mb_lib.t6g(sch_1):page152_i17@pure_quanta.q_res(chips)',
 PATH='I17',
 DRAWING='@T6G_MB_LIB.T6G(SCH_1):PAGE350',
 WATTAGE='1/16W',
 TOLERANCE='5%',
 MATERIAL='CHIP',
 PHYS_PAGE='152',
 XY='(-2825,14275)',
 ROT='0',
 VER='1',
 PACK_TYPE='0402LF',
 LOCATION='R3996',
 CDS_LIB='pure_quanta',
 CDS_PART_NAME='Q_RES_0402LF-0,5%,1/16W,CHIP,CS00002JB13',
 PART_NUMBER='CS00002JB13',
 VALUE='0',
 PRIM_FILE='./archive_libs/logical/q_res/chips/chips.prt';

PART_NAME
 R3997 'Q_RES_0402LF-0,5%,1/16W,CHIP,CS00002JB13':
 ROOM='SCM_P12V_MAM_BOM1';

SECTION_NUMBER 1
 '@T6G_MB_LIB.T6G(SCH_1):PAGE350_I27@PURE_QUANTA.Q_RES(CHIPS)':
 C_PATH='@t6g_mb_lib.t6g(sch_1):page350_i27@pure_quanta.q_res(chips)',
 P_PATH='@t6g_mb_lib.t6g(sch_1):page152_i27@pure_quanta.q_res(chips)',
 PATH='I27',
 DRAWING='@T6G_MB_LIB.T6G(SCH_1):PAGE350',
 WATTAGE='1/16W',
 TOLERANCE='5%',
 MATERIAL='CHIP',
 PHYS_PAGE='152',
 XY='(100,15000)',
 ROT='0',
 VER='1',
 PACK_TYPE='0402LF',
 LOCATION='R3997',
 CDS_LIB='pure_quanta',
 CDS_PART_NAME='Q_RES_0402LF-0,5%,1/16W,CHIP,CS00002JB13',
 ROOM='SCM_P12V_MAM_BOM1',
 PART_NUMBER='CS00002JB13',
 VALUE='0',
 PRIM_FILE='./archive_libs/logical/q_res/chips/chips.prt';

PART_NAME
 R3998 'Q_RES_0402LF-0,5%,1/16W,CHIP,CS00002JB13':
 ROOM='SCM_P12V_MPS_BOM2';

SECTION_NUMBER 1
 '@T6G_MB_LIB.T6G(SCH_1):PAGE350_I14@PURE_QUANTA.Q_RES(CHIPS)':
 C_PATH='@t6g_mb_lib.t6g(sch_1):page350_i14@pure_quanta.q_res(chips)',
 P_PATH='@t6g_mb_lib.t6g(sch_1):page152_i14@pure_quanta.q_res(chips)',
 PATH='I14',
 DRAWING='@T6G_MB_LIB.T6G(SCH_1):PAGE350',
 WATTAGE='1/16W',
 TOLERANCE='5%',
 MATERIAL='CHIP',
 PHYS_PAGE='152',
 XY='(300,12150)',
 ROT='0',
 VER='1',
 PACK_TYPE='0402LF',
 LOCATION='R3998',
 CDS_LIB='pure_quanta',
 CDS_PART_NAME='Q_RES_0402LF-0,5%,1/16W,CHIP,CS00002JB13',
 ROOM='SCM_P12V_MPS_BOM2',
 PART_NUMBER='CS00002JB13',
 VALUE='0',
 PRIM_FILE='./archive_libs/logical/q_res/chips/chips.prt';

PART_NAME
 R4013 'Q_RES_0402LF-100K,1%,1/16W,CHIP,CS41002FB09':
 ROOM='SCM_P12V_MAM_BOM1';

SECTION_NUMBER 1
 '@T6G_MB_LIB.T6G(SCH_1):PAGE350_I76@PURE_QUANTA.Q_RES(CHIPS)':
 C_PATH='@t6g_mb_lib.t6g(sch_1):page350_i76@pure_quanta.q_res(chips)',
 P_PATH='@t6g_mb_lib.t6g(sch_1):page152_i76@pure_quanta.q_res(chips)',
 PATH='I76',
 DRAWING='@T6G_MB_LIB.T6G(SCH_1):PAGE350',
 WATTAGE='1/16W',
 TOLERANCE='1%',
 MATERIAL='CHIP',
 PHYS_PAGE='152',
 XY='(4100,15150)',
 ROT='0',
 VER='2',
 PACK_TYPE='0402LF',
 LOCATION='R4013',
 CDS_LIB='pure_quanta',
 CDS_PART_NAME='Q_RES_0402LF-100K,1%,1/16W,CHIP,CS41002FB09',
 ROOM='SCM_P12V_MAM_BOM1',
 PART_NUMBER='CS41002FB09',
 VALUE='100K',
 PRIM_FILE='./archive_libs/logical/q_res/chips/chips.prt';

PART_NAME
 R4015 'Q_RES_0402LF-100K,1%,1/16W,CHIP,CS41002FB09':
 ROOM='SCM_P12V_MAM_BOM1';

SECTION_NUMBER 1
 '@T6G_MB_LIB.T6G(SCH_1):PAGE350_I78@PURE_QUANTA.Q_RES(CHIPS)':
 C_PATH='@t6g_mb_lib.t6g(sch_1):page350_i78@pure_quanta.q_res(chips)',
 P_PATH='@t6g_mb_lib.t6g(sch_1):page152_i78@pure_quanta.q_res(chips)',
 PATH='I78',
 DRAWING='@T6G_MB_LIB.T6G(SCH_1):PAGE350',
 WATTAGE='1/16W',
 TOLERANCE='1%',
 MATERIAL='CHIP',
 PHYS_PAGE='152',
 XY='(4525,15150)',
 ROT='0',
 VER='2',
 PACK_TYPE='0402LF',
 LOCATION='R4015',
 CDS_LIB='pure_quanta',
 CDS_PART_NAME='Q_RES_0402LF-100K,1%,1/16W,CHIP,CS41002FB09',
 ROOM='SCM_P12V_MAM_BOM1',
 PART_NUMBER='CS41002FB09',
 VALUE='100K',
 PRIM_FILE='./archive_libs/logical/q_res/chips/chips.prt';

PART_NAME
 R4058 'Q_RES_0402LF-10K,1%,1/16W,CHIP,CS31002FB08':;

SECTION_NUMBER 1
 '@T6G_MB_LIB.T6G(SCH_1):PAGE330_I13@PURE_QUANTA.Q_RES(CHIPS)':
 C_PATH='@t6g_mb_lib.t6g(sch_1):page330_i13@pure_quanta.q_res(chips)',
 P_PATH='@t6g_mb_lib.t6g(sch_1):page123_i13@pure_quanta.q_res(chips)',
 PATH='I13',
 DRAWING='@T6G_MB_LIB.T6G(SCH_1):PAGE330',
 SEC_TYPE='0402LF',
 WATTAGE='1/16W',
 TOLERANCE='1%',
 MATERIAL='CHIP',
 PHYS_PAGE='123',
 XY='(-6300,8150)',
 ROT='2',
 VER='2',
 PACK_TYPE='0402LF',
 LOCATION='R4058',
 SEC='1',
 CDS_LIB='pure_quanta',
 CDS_PART_NAME='Q_RES_0402LF-10K,1%,1/16W,CHIP,CS31002FB08',
 PART_NUMBER='CS31002FB08',
 VALUE='10K',
 PRIM_FILE='./archive_libs/logical/q_res/chips/chips.prt';

PART_NAME
 R4059 'Q_RES_0402LF-0,5%,1/16W,EMPTY,CS00002JB13':
 ROOM='NIC_P12V_MAM_TIC_BOM1';

SECTION_NUMBER 1
 '@T6G_MB_LIB.T6G(SCH_1):PAGE343_I119@PURE_QUANTA.Q_RES(CHIPS)':
 C_PATH='@t6g_mb_lib.t6g(sch_1):page343_i119@pure_quanta.q_res(chips)',
 P_PATH='@t6g_mb_lib.t6g(sch_1):page140_i119@pure_quanta.q_res(chips)',
 PATH='I119',
 DRAWING='@T6G_MB_LIB.T6G(SCH_1):PAGE343',
 WATTAGE='1/16W',
 TOLERANCE='5%',
 MATERIAL='EMPTY',
 PHYS_PAGE='140',
 XY='(-3775,5825)',
 ROT='0',
 VER='1',
 PACK_TYPE='0402LF',
 LOCATION='R4059',
 CDS_LIB='pure_quanta',
 CDS_PART_NAME='Q_RES_0402LF-0,5%,1/16W,EMPTY,CS00002JB13',
 ROOM='NIC_P12V_MAM_TIC_BOM1',
 PART_NUMBER='CS00002JB13',
 VALUE='0',
 PRIM_FILE='./archive_libs/logical/q_res/chips/chips.prt';

PART_NAME
 R4060 'Q_RES_0402LF-0,5%,1/16W,EMPTY,CS00002JB13':
 ROOM='NIC_P3V3_BOM1';

SECTION_NUMBER 1
 '@T6G_MB_LIB.T6G(SCH_1):PAGE343_I122@PURE_QUANTA.Q_RES(CHIPS)':
 C_PATH='@t6g_mb_lib.t6g(sch_1):page343_i122@pure_quanta.q_res(chips)',
 P_PATH='@t6g_mb_lib.t6g(sch_1):page140_i122@pure_quanta.q_res(chips)',
 PATH='I122',
 DRAWING='@T6G_MB_LIB.T6G(SCH_1):PAGE343',
 WATTAGE='1/16W',
 TOLERANCE='5%',
 MATERIAL='EMPTY',
 PHYS_PAGE='140',
 XY='(-3175,7825)',
 ROT='0',
 VER='1',
 PACK_TYPE='0402LF',
 LOCATION='R4060',
 CDS_LIB='pure_quanta',
 CDS_PART_NAME='Q_RES_0402LF-0,5%,1/16W,EMPTY,CS00002JB13',
 ROOM='NIC_P3V3_BOM1',
 PART_NUMBER='CS00002JB13',
 VALUE='0',
 PRIM_FILE='./archive_libs/logical/q_res/chips/chips.prt';

PART_NAME
 R4061 'Q_RES_0402LF-0,5%,1/16W,EMPTY,CS00002JB13':
 ROOM='NIC_P12V_MAM_TIC_BOM1';

SECTION_NUMBER 1
 '@T6G_MB_LIB.T6G(SCH_1):PAGE338_I123@PURE_QUANTA.Q_RES(CHIPS)':
 C_PATH='@t6g_mb_lib.t6g(sch_1):page338_i123@pure_quanta.q_res(chips)',
 P_PATH='@t6g_mb_lib.t6g(sch_1):page134_i123@pure_quanta.q_res(chips)',
 PATH='I123',
 DRAWING='@T6G_MB_LIB.T6G(SCH_1):PAGE338',
 WATTAGE='1/16W',
 TOLERANCE='5%',
 MATERIAL='EMPTY',
 PHYS_PAGE='134',
 XY='(2600,10225)',
 ROT='0',
 VER='1',
 PACK_TYPE='0402LF',
 LOCATION='R4061',
 CDS_LIB='pure_quanta',
 CDS_PART_NAME='Q_RES_0402LF-0,5%,1/16W,EMPTY,CS00002JB13',
 ROOM='NIC_P12V_MAM_TIC_BOM1',
 PART_NUMBER='CS00002JB13',
 VALUE='0',
 PRIM_FILE='./archive_libs/logical/q_res/chips/chips.prt';

PART_NAME
 R4062 'Q_RES_0402LF-0,5%,1/16W,CHIP,CS00002JB13':
 ROOM='SCM_P12V_MAM_BOM1';

SECTION_NUMBER 1
 '@T6G_MB_LIB.T6G(SCH_1):PAGE350_I20@PURE_QUANTA.Q_RES(CHIPS)':
 C_PATH='@t6g_mb_lib.t6g(sch_1):page350_i20@pure_quanta.q_res(chips)',
 P_PATH='@t6g_mb_lib.t6g(sch_1):page152_i20@pure_quanta.q_res(chips)',
 PATH='I20',
 DRAWING='@T6G_MB_LIB.T6G(SCH_1):PAGE350',
 WATTAGE='1/16W',
 TOLERANCE='5%',
 MATERIAL='CHIP',
 PHYS_PAGE='152',
 XY='(-2025,14275)',
 ROT='0',
 VER='1',
 PACK_TYPE='0402LF',
 LOCATION='R4062',
 CDS_LIB='pure_quanta',
 CDS_PART_NAME='Q_RES_0402LF-0,5%,1/16W,CHIP,CS00002JB13',
 ROOM='SCM_P12V_MAM_BOM1',
 PART_NUMBER='CS00002JB13',
 VALUE='0',
 PRIM_FILE='./archive_libs/logical/q_res/chips/chips.prt';

PART_NAME
 R4063 'Q_RES_0402LF-0,5%,1/16W,CHIP,CS00002JB13':
 ROOM='E1S_P3V3_BOM1';

SECTION_NUMBER 1
 '@T6G_MB_LIB.T6G(SCH_1):PAGE324_I2@PURE_QUANTA.Q_RES(CHIPS)':
 C_PATH='@t6g_mb_lib.t6g(sch_1):page324_i2@pure_quanta.q_res(chips)',
 P_PATH='@t6g_mb_lib.t6g(sch_1):page146_i2@pure_quanta.q_res(chips)',
 PATH='I2',
 DRAWING='@T6G_MB_LIB.T6G(SCH_1):PAGE324',
 WATTAGE='1/16W',
 TOLERANCE='5%',
 MATERIAL='CHIP',
 PHYS_PAGE='146',
 XY='(-3650,-2650)',
 ROT='0',
 VER='1',
 PACK_TYPE='0402LF',
 LOCATION='R4063',
 CDS_LIB='pure_quanta',
 CDS_PART_NAME='Q_RES_0402LF-0,5%,1/16W,CHIP,CS00002JB13',
 ROOM='E1S_P3V3_BOM1',
 PART_NUMBER='CS00002JB13',
 VALUE='0',
 PRIM_FILE='./archive_libs/logical/q_res/chips/chips.prt';

PART_NAME
 R4064 'Q_RES_0402LF-0,5%,1/16W,CHIP,CS00002JB13':
 ROOM='E1S_P12V_MAM_TIC_BOM1';

SECTION_NUMBER 1
 '@T6G_MB_LIB.T6G(SCH_1):PAGE324_I24@PURE_QUANTA.Q_RES(CHIPS)':
 C_PATH='@t6g_mb_lib.t6g(sch_1):page324_i24@pure_quanta.q_res(chips)',
 P_PATH='@t6g_mb_lib.t6g(sch_1):page146_i24@pure_quanta.q_res(chips)',
 PATH='I24',
 DRAWING='@T6G_MB_LIB.T6G(SCH_1):PAGE324',
 WATTAGE='1/16W',
 TOLERANCE='5%',
 MATERIAL='CHIP',
 PHYS_PAGE='146',
 XY='(-3375,-150)',
 ROT='0',
 VER='1',
 PACK_TYPE='0402LF',
 LOCATION='R4064',
 CDS_LIB='pure_quanta',
 CDS_PART_NAME='Q_RES_0402LF-0,5%,1/16W,CHIP,CS00002JB13',
 ROOM='E1S_P12V_MAM_TIC_BOM1',
 PART_NUMBER='CS00002JB13',
 VALUE='0',
 PRIM_FILE='./archive_libs/logical/q_res/chips/chips.prt';

PART_NAME
 R4065 'Q_RES_0402LF-10K,1%,1/16W,CHIP,CS31002FB08':
 ROOM='NIC_P12V_MAM_TIC_BOM1';

SECTION_NUMBER 1
 '@T6G_MB_LIB.T6G(SCH_1):PAGE343_I17@PURE_QUANTA.Q_RES(CHIPS)':
 C_PATH='@t6g_mb_lib.t6g(sch_1):page343_i17@pure_quanta.q_res(chips)',
 P_PATH='@t6g_mb_lib.t6g(sch_1):page140_i17@pure_quanta.q_res(chips)',
 PATH='I17',
 DRAWING='@T6G_MB_LIB.T6G(SCH_1):PAGE343',
 WATTAGE='1/16W',
 TOLERANCE='1%',
 MATERIAL='CHIP',
 PHYS_PAGE='140',
 XY='(-2750,6475)',
 ROT='0',
 VER='2',
 PACK_TYPE='0402LF',
 LOCATION='R4065',
 CDS_LIB='pure_quanta',
 CDS_PART_NAME='Q_RES_0402LF-10K,1%,1/16W,CHIP,CS31002FB08',
 ROOM='NIC_P12V_MAM_TIC_BOM1',
 PART_NUMBER='CS31002FB08',
 VALUE='10K',
 PRIM_FILE='./archive_libs/logical/q_res/chips/chips.prt';

PART_NAME
 R4066 'Q_RES_0402LF-4.7K,5%,1/16W,EMPTY,CS24702JB10':
 ROOM='NIC_P3V3_BOM1';

SECTION_NUMBER 1
 '@T6G_MB_LIB.T6G(SCH_1):PAGE343_I121@PURE_QUANTA.Q_RES(CHIPS)':
 C_PATH='@t6g_mb_lib.t6g(sch_1):page343_i121@pure_quanta.q_res(chips)',
 P_PATH='@t6g_mb_lib.t6g(sch_1):page140_i121@pure_quanta.q_res(chips)',
 PATH='I121',
 DRAWING='@T6G_MB_LIB.T6G(SCH_1):PAGE343',
 WATTAGE='1/16W',
 TOLERANCE='5%',
 MATERIAL='EMPTY',
 PHYS_PAGE='140',
 XY='(-2725,7500)',
 ROT='2',
 VER='2',
 PACK_TYPE='0402LF',
 LOCATION='R4066',
 CDS_LIB='pure_quanta',
 CDS_PART_NAME='Q_RES_0402LF-4.7K,5%,1/16W,EMPTY,CS24702JB10',
 ROOM='NIC_P3V3_BOM1',
 PART_NUMBER='CS24702JB10',
 VALUE='4.7K',
 PRIM_FILE='./archive_libs/logical/q_res/chips/chips.prt';

PART_NAME
 R4067 'Q_RES_0402LF-10K,1%,1/16W,CHIP,CS31002FB08':
 ROOM='NIC_P3V3_BOM1';

SECTION_NUMBER 1
 '@T6G_MB_LIB.T6G(SCH_1):PAGE343_I43@PURE_QUANTA.Q_RES(CHIPS)':
 C_PATH='@t6g_mb_lib.t6g(sch_1):page343_i43@pure_quanta.q_res(chips)',
 P_PATH='@t6g_mb_lib.t6g(sch_1):page140_i43@pure_quanta.q_res(chips)',
 PATH='I43',
 DRAWING='@T6G_MB_LIB.T6G(SCH_1):PAGE343',
 WATTAGE='1/16W',
 TOLERANCE='1%',
 MATERIAL='CHIP',
 PHYS_PAGE='140',
 XY='(-2225,8475)',
 ROT='0',
 VER='2',
 PACK_TYPE='0402LF',
 LOCATION='R4067',
 CDS_LIB='pure_quanta',
 CDS_PART_NAME='Q_RES_0402LF-10K,1%,1/16W,CHIP,CS31002FB08',
 ROOM='NIC_P3V3_BOM1',
 PART_NUMBER='CS31002FB08',
 VALUE='10K',
 PRIM_FILE='./archive_libs/logical/q_res/chips/chips.prt';

PART_NAME
 R4068 'Q_RES_0402LF-10K,1%,1/16W,CHIP,CS31002FB08':
 ROOM='NIC_P12V_MAM_TIC_BOM1';

SECTION_NUMBER 1
 '@T6G_MB_LIB.T6G(SCH_1):PAGE338_I17@PURE_QUANTA.Q_RES(CHIPS)':
 C_PATH='@t6g_mb_lib.t6g(sch_1):page338_i17@pure_quanta.q_res(chips)',
 P_PATH='@t6g_mb_lib.t6g(sch_1):page134_i17@pure_quanta.q_res(chips)',
 PATH='I17',
 DRAWING='@T6G_MB_LIB.T6G(SCH_1):PAGE338',
 WATTAGE='1/16W',
 TOLERANCE='1%',
 MATERIAL='CHIP',
 PHYS_PAGE='134',
 XY='(3475,10800)',
 ROT='0',
 VER='2',
 PACK_TYPE='0402LF',
 LOCATION='R4068',
 CDS_LIB='pure_quanta',
 CDS_PART_NAME='Q_RES_0402LF-10K,1%,1/16W,CHIP,CS31002FB08',
 ROOM='NIC_P12V_MAM_TIC_BOM1',
 PART_NUMBER='CS31002FB08',
 VALUE='10K',
 PRIM_FILE='./archive_libs/logical/q_res/chips/chips.prt';

PART_NAME
 R4069 'Q_RES_0402LF-4.7K,5%,1/16W,EMPTY,CS24702JB10':
 ROOM='NIC_P3V3_BOM1';

SECTION_NUMBER 1
 '@T6G_MB_LIB.T6G(SCH_1):PAGE338_I127@PURE_QUANTA.Q_RES(CHIPS)':
 C_PATH='@t6g_mb_lib.t6g(sch_1):page338_i127@pure_quanta.q_res(chips)',
 P_PATH='@t6g_mb_lib.t6g(sch_1):page134_i127@pure_quanta.q_res(chips)',
 PATH='I127',
 DRAWING='@T6G_MB_LIB.T6G(SCH_1):PAGE338',
 WATTAGE='1/16W',
 TOLERANCE='5%',
 MATERIAL='EMPTY',
 PHYS_PAGE='134',
 XY='(3650,11500)',
 ROT='2',
 VER='2',
 PACK_TYPE='0402LF',
 LOCATION='R4069',
 CDS_LIB='pure_quanta',
 CDS_PART_NAME='Q_RES_0402LF-4.7K,5%,1/16W,EMPTY,CS24702JB10',
 ROOM='NIC_P3V3_BOM1',
 PART_NUMBER='CS24702JB10',
 VALUE='4.7K',
 PRIM_FILE='./archive_libs/logical/q_res/chips/chips.prt';

PART_NAME
 R4070 'Q_RES_0402LF-10K,1%,1/16W,CHIP,CS31002FB08':
 ROOM='NIC_P3V3_BOM1';

SECTION_NUMBER 1
 '@T6G_MB_LIB.T6G(SCH_1):PAGE338_I59@PURE_QUANTA.Q_RES(CHIPS)':
 C_PATH='@t6g_mb_lib.t6g(sch_1):page338_i59@pure_quanta.q_res(chips)',
 P_PATH='@t6g_mb_lib.t6g(sch_1):page134_i59@pure_quanta.q_res(chips)',
 PATH='I59',
 DRAWING='@T6G_MB_LIB.T6G(SCH_1):PAGE338',
 WATTAGE='1/16W',
 TOLERANCE='1%',
 MATERIAL='CHIP',
 PHYS_PAGE='134',
 XY='(4225,12475)',
 ROT='0',
 VER='2',
 PACK_TYPE='0402LF',
 LOCATION='R4070',
 CDS_LIB='pure_quanta',
 CDS_PART_NAME='Q_RES_0402LF-10K,1%,1/16W,CHIP,CS31002FB08',
 ROOM='NIC_P3V3_BOM1',
 PART_NUMBER='CS31002FB08',
 VALUE='10K',
 PRIM_FILE='./archive_libs/logical/q_res/chips/chips.prt';

PART_NAME
 R4071 'Q_RES_0402LF-10K,1%,1/16W,CHIP,CS31002FB08':
 ROOM='SCM_P12V_MAM_BOM1';

SECTION_NUMBER 1
 '@T6G_MB_LIB.T6G(SCH_1):PAGE350_I25@PURE_QUANTA.Q_RES(CHIPS)':
 C_PATH='@t6g_mb_lib.t6g(sch_1):page350_i25@pure_quanta.q_res(chips)',
 P_PATH='@t6g_mb_lib.t6g(sch_1):page152_i25@pure_quanta.q_res(chips)',
 PATH='I25',
 DRAWING='@T6G_MB_LIB.T6G(SCH_1):PAGE350',
 WATTAGE='1/16W',
 TOLERANCE='1%',
 MATERIAL='CHIP',
 PHYS_PAGE='152',
 XY='(-1125,14925)',
 ROT='0',
 VER='2',
 PACK_TYPE='0402LF',
 LOCATION='R4071',
 CDS_LIB='pure_quanta',
 CDS_PART_NAME='Q_RES_0402LF-10K,1%,1/16W,CHIP,CS31002FB08',
 ROOM='SCM_P12V_MAM_BOM1',
 PART_NUMBER='CS31002FB08',
 VALUE='10K',
 PRIM_FILE='./archive_libs/logical/q_res/chips/chips.prt';

PART_NAME
 R4072 'Q_RES_0402LF-10K,1%,1/16W,CHIP,CS31002FB08':
 ROOM='E1S_P3V3_BOM1';

SECTION_NUMBER 1
 '@T6G_MB_LIB.T6G(SCH_1):PAGE324_I8@PURE_QUANTA.Q_RES(CHIPS)':
 C_PATH='@t6g_mb_lib.t6g(sch_1):page324_i8@pure_quanta.q_res(chips)',
 P_PATH='@t6g_mb_lib.t6g(sch_1):page146_i8@pure_quanta.q_res(chips)',
 PATH='I8',
 DRAWING='@T6G_MB_LIB.T6G(SCH_1):PAGE324',
 WATTAGE='1/16W',
 TOLERANCE='1%',
 MATERIAL='CHIP',
 PHYS_PAGE='146',
 XY='(-2725,-2000)',
 ROT='0',
 VER='2',
 PACK_TYPE='0402LF',
 LOCATION='R4072',
 CDS_LIB='pure_quanta',
 CDS_PART_NAME='Q_RES_0402LF-10K,1%,1/16W,CHIP,CS31002FB08',
 ROOM='E1S_P3V3_BOM1',
 PART_NUMBER='CS31002FB08',
 VALUE='10K',
 PRIM_FILE='./archive_libs/logical/q_res/chips/chips.prt';

PART_NAME
 R4073 'Q_RES_0402LF-4.7K,5%,1/16W,CHIP,CS24702JB10':
 ROOM='E1S_P12V_MAM_TIC_BOM1';

SECTION_NUMBER 1
 '@T6G_MB_LIB.T6G(SCH_1):PAGE324_I11@PURE_QUANTA.Q_RES(CHIPS)':
 C_PATH='@t6g_mb_lib.t6g(sch_1):page324_i11@pure_quanta.q_res(chips)',
 P_PATH='@t6g_mb_lib.t6g(sch_1):page146_i11@pure_quanta.q_res(chips)',
 PATH='I11',
 DRAWING='@T6G_MB_LIB.T6G(SCH_1):PAGE324',
 WATTAGE='1/16W',
 TOLERANCE='5%',
 MATERIAL='CHIP',
 PHYS_PAGE='146',
 XY='(-3000,-475)',
 ROT='0',
 VER='2',
 PACK_TYPE='0402LF',
 LOCATION='R4073',
 CDS_LIB='pure_quanta',
 CDS_PART_NAME='Q_RES_0402LF-4.7K,5%,1/16W,CHIP,CS24702JB10',
 ROOM='E1S_P12V_MAM_TIC_BOM1',
 PART_NUMBER='CS24702JB10',
 VALUE='4.7K',
 PRIM_FILE='./archive_libs/logical/q_res/chips/chips.prt';

PART_NAME
 R4074 'Q_RES_0402LF-10K,1%,1/16W,CHIP,CS31002FB08':
 ROOM='E1S_P12V_MAM_TIC_BOM1';

SECTION_NUMBER 1
 '@T6G_MB_LIB.T6G(SCH_1):PAGE324_I25@PURE_QUANTA.Q_RES(CHIPS)':
 C_PATH='@t6g_mb_lib.t6g(sch_1):page324_i25@pure_quanta.q_res(chips)',
 P_PATH='@t6g_mb_lib.t6g(sch_1):page146_i25@pure_quanta.q_res(chips)',
 PATH='I25',
 DRAWING='@T6G_MB_LIB.T6G(SCH_1):PAGE324',
 WATTAGE='1/16W',
 TOLERANCE='1%',
 MATERIAL='CHIP',
 PHYS_PAGE='146',
 XY='(-2500,500)',
 ROT='0',
 VER='2',
 PACK_TYPE='0402LF',
 LOCATION='R4074',
 CDS_LIB='pure_quanta',
 CDS_PART_NAME='Q_RES_0402LF-10K,1%,1/16W,CHIP,CS31002FB08',
 ROOM='E1S_P12V_MAM_TIC_BOM1',
 PART_NUMBER='CS31002FB08',
 VALUE='10K',
 PRIM_FILE='./archive_libs/logical/q_res/chips/chips.prt';

PART_NAME
 R4075 'Q_RES_0402LF-0,5%,1/16W,CHIP,CS00002JB13':;

SECTION_NUMBER 1
 '@T6G_MB_LIB.T6G(SCH_1):PAGE232_I22@PURE_QUANTA.Q_RES(CHIPS)':
 C_PATH='@t6g_mb_lib.t6g(sch_1):page232_i22@pure_quanta.q_res(chips)',
 P_PATH='@t6g_mb_lib.t6g(sch_1):page233_i22@pure_quanta.q_res(chips)',
 PATH='I22',
 DRAWING='@T6G_MB_LIB.T6G(SCH_1):PAGE232',
 WATTAGE='1/16W',
 TOLERANCE='5%',
 MATERIAL='CHIP',
 PHYS_PAGE='233',
 XY='(-6200,3550)',
 ROT='0',
 VER='1',
 PACK_TYPE='0402LF',
 LOCATION='R4075',
 CDS_LIB='pure_quanta',
 CDS_PART_NAME='Q_RES_0402LF-0,5%,1/16W,CHIP,CS00002JB13',
 PART_NUMBER='CS00002JB13',
 VALUE='0',
 PRIM_FILE='./archive_libs/logical/q_res/chips/chips.prt';

PART_NAME
 R4076 'Q_RES_0402LF-0,5%,1/16W,CHIP,CS00002JB13':;

SECTION_NUMBER 1
 '@T6G_MB_LIB.T6G(SCH_1):PAGE232_I16@PURE_QUANTA.Q_RES(CHIPS)':
 C_PATH='@t6g_mb_lib.t6g(sch_1):page232_i16@pure_quanta.q_res(chips)',
 P_PATH='@t6g_mb_lib.t6g(sch_1):page233_i16@pure_quanta.q_res(chips)',
 PATH='I16',
 DRAWING='@T6G_MB_LIB.T6G(SCH_1):PAGE232',
 WATTAGE='1/16W',
 TOLERANCE='5%',
 MATERIAL='CHIP',
 PHYS_PAGE='233',
 XY='(-6200,3500)',
 ROT='0',
 VER='1',
 PACK_TYPE='0402LF',
 LOCATION='R4076',
 CDS_LIB='pure_quanta',
 CDS_PART_NAME='Q_RES_0402LF-0,5%,1/16W,CHIP,CS00002JB13',
 PART_NUMBER='CS00002JB13',
 VALUE='0',
 PRIM_FILE='./archive_libs/logical/q_res/chips/chips.prt';

PART_NAME
 R4077 'Q_RES_0402LF-1,1%,1/16W,CHIP,CS-1002FB04':;

SECTION_NUMBER 1
 '@T6G_MB_LIB.T6G(SCH_1):PAGE232_I43@PURE_QUANTA.Q_RES(CHIPS)':
 C_PATH='@t6g_mb_lib.t6g(sch_1):page232_i43@pure_quanta.q_res(chips)',
 P_PATH='@t6g_mb_lib.t6g(sch_1):page233_i43@pure_quanta.q_res(chips)',
 PATH='I43',
 DRAWING='@T6G_MB_LIB.T6G(SCH_1):PAGE232',
 WATTAGE='1/16W',
 TOLERANCE='1%',
 MATERIAL='CHIP',
 PHYS_PAGE='233',
 XY='(-4175,5400)',
 ROT='0',
 VER='1',
 PACK_TYPE='0402LF',
 LOCATION='R4077',
 CDS_LIB='pure_quanta',
 CDS_PART_NAME='Q_RES_0402LF-1,1%,1/16W,CHIP,CS-1002FB04',
 PART_NUMBER='CS-1002FB04',
 VALUE='1',
 PRIM_FILE='./archive_libs/logical/q_res/chips/chips.prt';

PART_NAME
 R4078 'Q_RES_0402LF-10K,1%,1/16W,EMPTY,CS31002FB08':;

SECTION_NUMBER 1
 '@T6G_MB_LIB.T6G(SCH_1):PAGE232_I47@PURE_QUANTA.Q_RES(CHIPS)':
 C_PATH='@t6g_mb_lib.t6g(sch_1):page232_i47@pure_quanta.q_res(chips)',
 P_PATH='@t6g_mb_lib.t6g(sch_1):page233_i47@pure_quanta.q_res(chips)',
 PATH='I47',
 DRAWING='@T6G_MB_LIB.T6G(SCH_1):PAGE232',
 WATTAGE='1/16W',
 TOLERANCE='1%',
 MATERIAL='EMPTY',
 PHYS_PAGE='233',
 XY='(-2650,1675)',
 ROT='2',
 VER='2',
 PACK_TYPE='0402LF',
 LOCATION='R4078',
 CDS_LIB='pure_quanta',
 CDS_PART_NAME='Q_RES_0402LF-10K,1%,1/16W,EMPTY,CS31002FB08',
 PART_NUMBER='CS31002FB08',
 VALUE='10K',
 PRIM_FILE='./archive_libs/logical/q_res/chips/chips.prt';

PART_NAME
 R4079 'Q_RES_0402LF-10K,1%,1/16W,CHIP,CS31002FB08':;

SECTION_NUMBER 1
 '@T6G_MB_LIB.T6G(SCH_1):PAGE232_I46@PURE_QUANTA.Q_RES(CHIPS)':
 C_PATH='@t6g_mb_lib.t6g(sch_1):page232_i46@pure_quanta.q_res(chips)',
 P_PATH='@t6g_mb_lib.t6g(sch_1):page233_i46@pure_quanta.q_res(chips)',
 PATH='I46',
 DRAWING='@T6G_MB_LIB.T6G(SCH_1):PAGE232',
 WATTAGE='1/16W',
 TOLERANCE='1%',
 MATERIAL='CHIP',
 PHYS_PAGE='233',
 XY='(-2650,1200)',
 ROT='2',
 VER='2',
 PACK_TYPE='0402LF',
 LOCATION='R4079',
 CDS_LIB='pure_quanta',
 CDS_PART_NAME='Q_RES_0402LF-10K,1%,1/16W,CHIP,CS31002FB08',
 PART_NUMBER='CS31002FB08',
 VALUE='10K',
 PRIM_FILE='./archive_libs/logical/q_res/chips/chips.prt';

PART_NAME
 R4080 'Q_RES_0402LF-10K,1%,1/16W,CHIP,CS31002FB08':;

SECTION_NUMBER 1
 '@T6G_MB_LIB.T6G(SCH_1):PAGE232_I59@PURE_QUANTA.Q_RES(CHIPS)':
 C_PATH='@t6g_mb_lib.t6g(sch_1):page232_i59@pure_quanta.q_res(chips)',
 P_PATH='@t6g_mb_lib.t6g(sch_1):page233_i59@pure_quanta.q_res(chips)',
 PATH='I59',
 DRAWING='@T6G_MB_LIB.T6G(SCH_1):PAGE232',
 WATTAGE='1/16W',
 TOLERANCE='1%',
 MATERIAL='CHIP',
 PHYS_PAGE='233',
 XY='(-1325,2500)',
 ROT='2',
 VER='2',
 PACK_TYPE='0402LF',
 LOCATION='R4080',
 CDS_LIB='pure_quanta',
 CDS_PART_NAME='Q_RES_0402LF-10K,1%,1/16W,CHIP,CS31002FB08',
 PART_NUMBER='CS31002FB08',
 VALUE='10K',
 PRIM_FILE='./archive_libs/logical/q_res/chips/chips.prt';

PART_NAME
 R4081 'Q_RES_0402LF-10K,1%,1/16W,CHIP,CS31002FB08':;

SECTION_NUMBER 1
 '@T6G_MB_LIB.T6G(SCH_1):PAGE232_I56@PURE_QUANTA.Q_RES(CHIPS)':
 C_PATH='@t6g_mb_lib.t6g(sch_1):page232_i56@pure_quanta.q_res(chips)',
 P_PATH='@t6g_mb_lib.t6g(sch_1):page233_i56@pure_quanta.q_res(chips)',
 PATH='I56',
 DRAWING='@T6G_MB_LIB.T6G(SCH_1):PAGE232',
 WATTAGE='1/16W',
 TOLERANCE='1%',
 MATERIAL='CHIP',
 PHYS_PAGE='233',
 XY='(-1325,1700)',
 ROT='2',
 VER='2',
 PACK_TYPE='0402LF',
 LOCATION='R4081',
 CDS_LIB='pure_quanta',
 CDS_PART_NAME='Q_RES_0402LF-10K,1%,1/16W,CHIP,CS31002FB08',
 PART_NUMBER='CS31002FB08',
 VALUE='10K',
 PRIM_FILE='./archive_libs/logical/q_res/chips/chips.prt';

PART_NAME
 R4082 'Q_RES_0402LF-10K,1%,1/16W,EMPTY,CS31002FB08':;

SECTION_NUMBER 1
 '@T6G_MB_LIB.T6G(SCH_1):PAGE232_I55@PURE_QUANTA.Q_RES(CHIPS)':
 C_PATH='@t6g_mb_lib.t6g(sch_1):page232_i55@pure_quanta.q_res(chips)',
 P_PATH='@t6g_mb_lib.t6g(sch_1):page233_i55@pure_quanta.q_res(chips)',
 PATH='I55',
 DRAWING='@T6G_MB_LIB.T6G(SCH_1):PAGE232',
 WATTAGE='1/16W',
 TOLERANCE='1%',
 MATERIAL='EMPTY',
 PHYS_PAGE='233',
 XY='(-1325,1225)',
 ROT='2',
 VER='2',
 PACK_TYPE='0402LF',
 LOCATION='R4082',
 CDS_LIB='pure_quanta',
 CDS_PART_NAME='Q_RES_0402LF-10K,1%,1/16W,EMPTY,CS31002FB08',
 PART_NUMBER='CS31002FB08',
 VALUE='10K',
 PRIM_FILE='./archive_libs/logical/q_res/chips/chips.prt';

PART_NAME
 R4087 'Q_RES_0402LF-0,5%,1/16W,CHIP,CS00002JB13':;

SECTION_NUMBER 1
 '@T6G_MB_LIB.T6G(SCH_1):PAGE348_I31@PURE_QUANTA.Q_RES(CHIPS)':
 C_PATH='@t6g_mb_lib.t6g(sch_1):page348_i31@pure_quanta.q_res(chips)',
 P_PATH='@t6g_mb_lib.t6g(sch_1):page150_i31@pure_quanta.q_res(chips)',
 PATH='I31',
 DRAWING='@T6G_MB_LIB.T6G(SCH_1):PAGE348',
 WATTAGE='1/16W',
 TOLERANCE='5%',
 MATERIAL='CHIP',
 PHYS_PAGE='150',
 XY='(-14950,6375)',
 ROT='0',
 VER='1',
 PACK_TYPE='0402LF',
 LOCATION='R4087',
 CDS_LIB='pure_quanta',
 CDS_PART_NAME='Q_RES_0402LF-0,5%,1/16W,CHIP,CS00002JB13',
 PART_NUMBER='CS00002JB13',
 VALUE='0',
 PRIM_FILE='./archive_libs/logical/q_res/chips/chips.prt';

PART_NAME
 R4090 'Q_RES_0402LF-1K,1%,1/16W,CHIP,CS21002FB06':;

SECTION_NUMBER 1
 '@T6G_MB_LIB.T6G(SCH_1):PAGE360_I124@PURE_QUANTA.Q_RES(CHIPS)':
 C_PATH='@t6g_mb_lib.t6g(sch_1):page360_i124@pure_quanta.q_res(chips)',
 P_PATH='@t6g_mb_lib.t6g(sch_1):page237_i124@pure_quanta.q_res(chips)',
 PATH='I124',
 DRAWING='@T6G_MB_LIB.T6G(SCH_1):PAGE360',
 WATTAGE='1/16W',
 TOLERANCE='1%',
 MATERIAL='CHIP',
 PHYS_PAGE='237',
 XY='(2600,-1275)',
 ROT='0',
 VER='2',
 PACK_TYPE='0402LF',
 LOCATION='R4090',
 CDS_LIB='pure_quanta',
 CDS_PART_NAME='Q_RES_0402LF-1K,1%,1/16W,CHIP,CS21002FB06',
 PART_NUMBER='CS21002FB06',
 VALUE='1K',
 PRIM_FILE='./archive_libs/logical/q_res/chips/chips.prt';

PART_NAME
 R4091 'Q_RES_0402LF-1K,1%,1/16W,CHIP,CS21002FB06':;

SECTION_NUMBER 1
 '@T6G_MB_LIB.T6G(SCH_1):PAGE360_I122@PURE_QUANTA.Q_RES(CHIPS)':
 C_PATH='@t6g_mb_lib.t6g(sch_1):page360_i122@pure_quanta.q_res(chips)',
 P_PATH='@t6g_mb_lib.t6g(sch_1):page237_i122@pure_quanta.q_res(chips)',
 PATH='I122',
 DRAWING='@T6G_MB_LIB.T6G(SCH_1):PAGE360',
 WATTAGE='1/16W',
 TOLERANCE='1%',
 MATERIAL='CHIP',
 PHYS_PAGE='237',
 XY='(2675,-3425)',
 ROT='0',
 VER='2',
 PACK_TYPE='0402LF',
 LOCATION='R4091',
 CDS_LIB='pure_quanta',
 CDS_PART_NAME='Q_RES_0402LF-1K,1%,1/16W,CHIP,CS21002FB06',
 PART_NUMBER='CS21002FB06',
 VALUE='1K',
 PRIM_FILE='./archive_libs/logical/q_res/chips/chips.prt';

PART_NAME
 R4092 'Q_RES_0402LF-1K,1%,1/16W,CHIP,CS21002FB06':;

SECTION_NUMBER 1
 '@T6G_MB_LIB.T6G(SCH_1):PAGE360_I126@PURE_QUANTA.Q_RES(CHIPS)':
 C_PATH='@t6g_mb_lib.t6g(sch_1):page360_i126@pure_quanta.q_res(chips)',
 P_PATH='@t6g_mb_lib.t6g(sch_1):page237_i126@pure_quanta.q_res(chips)',
 PATH='I126',
 DRAWING='@T6G_MB_LIB.T6G(SCH_1):PAGE360',
 WATTAGE='1/16W',
 TOLERANCE='1%',
 MATERIAL='CHIP',
 PHYS_PAGE='237',
 XY='(3175,825)',
 ROT='0',
 VER='2',
 PACK_TYPE='0402LF',
 LOCATION='R4092',
 CDS_LIB='pure_quanta',
 CDS_PART_NAME='Q_RES_0402LF-1K,1%,1/16W,CHIP,CS21002FB06',
 PART_NUMBER='CS21002FB06',
 VALUE='1K',
 PRIM_FILE='./archive_libs/logical/q_res/chips/chips.prt';

PART_NAME
 R4093 'Q_RES_0402LF-1K,1%,1/16W,CHIP,CS21002FB06':;

SECTION_NUMBER 1
 '@T6G_MB_LIB.T6G(SCH_1):PAGE295_I149@PURE_QUANTA.Q_RES(CHIPS)':
 C_PATH='@t6g_mb_lib.t6g(sch_1):page295_i149@pure_quanta.q_res(chips)',
 P_PATH='@t6g_mb_lib.t6g(sch_1):page236_i149@pure_quanta.q_res(chips)',
 PATH='I149',
 DRAWING='@T6G_MB_LIB.T6G(SCH_1):PAGE295',
 WATTAGE='1/16W',
 TOLERANCE='1%',
 MATERIAL='CHIP',
 PHYS_PAGE='236',
 XY='(4225,1175)',
 ROT='0',
 VER='2',
 PACK_TYPE='0402LF',
 LOCATION='R4093',
 CDS_LIB='pure_quanta',
 CDS_PART_NAME='Q_RES_0402LF-1K,1%,1/16W,CHIP,CS21002FB06',
 PART_NUMBER='CS21002FB06',
 VALUE='1K',
 PRIM_FILE='./archive_libs/logical/q_res/chips/chips.prt';

PART_NAME
 R4094 'Q_RES_0402LF-1K,1%,1/16W,CHIP,CS21002FB06':;

SECTION_NUMBER 1
 '@T6G_MB_LIB.T6G(SCH_1):PAGE295_I151@PURE_QUANTA.Q_RES(CHIPS)':
 C_PATH='@t6g_mb_lib.t6g(sch_1):page295_i151@pure_quanta.q_res(chips)',
 P_PATH='@t6g_mb_lib.t6g(sch_1):page236_i151@pure_quanta.q_res(chips)',
 PATH='I151',
 DRAWING='@T6G_MB_LIB.T6G(SCH_1):PAGE295',
 WATTAGE='1/16W',
 TOLERANCE='1%',
 MATERIAL='CHIP',
 PHYS_PAGE='236',
 XY='(4250,3775)',
 ROT='0',
 VER='2',
 PACK_TYPE='0402LF',
 LOCATION='R4094',
 CDS_LIB='pure_quanta',
 CDS_PART_NAME='Q_RES_0402LF-1K,1%,1/16W,CHIP,CS21002FB06',
 PART_NUMBER='CS21002FB06',
 VALUE='1K',
 PRIM_FILE='./archive_libs/logical/q_res/chips/chips.prt';

PART_NAME
 R4119 'Q_RES_0402LF-54.9K,1%,1/16W,EMPTY,CS35492FB03':;

SECTION_NUMBER 1
 '@T6G_MB_LIB.T6G(SCH_1):PAGE332_I23@PURE_QUANTA.Q_RES(CHIPS)':
 C_PATH='@t6g_mb_lib.t6g(sch_1):page332_i23@pure_quanta.q_res(chips)',
 P_PATH='@t6g_mb_lib.t6g(sch_1):page125_i23@pure_quanta.q_res(chips)',
 PATH='I23',
 DRAWING='@T6G_MB_LIB.T6G(SCH_1):PAGE332',
 WATTAGE='1/16W',
 TOLERANCE='1%',
 MATERIAL='EMPTY',
 PHYS_PAGE='125',
 XY='(-2150,3650)',
 ROT='0',
 VER='2',
 PACK_TYPE='0402LF',
 LOCATION='R4119',
 CDS_LIB='pure_quanta',
 CDS_PART_NAME='Q_RES_0402LF-54.9K,1%,1/16W,EMPTY,CS35492FB03',
 PART_NUMBER='CS35492FB03',
 VALUE='54.9K',
 PRIM_FILE='./archive_libs/logical/q_res/chips/chips.prt';

PART_NAME
 R4120 'Q_RES_0402LF-100K,1%,1/16W,EMPTY,CS41002FB09':;

SECTION_NUMBER 1
 '@T6G_MB_LIB.T6G(SCH_1):PAGE332_I22@PURE_QUANTA.Q_RES(CHIPS)':
 C_PATH='@t6g_mb_lib.t6g(sch_1):page332_i22@pure_quanta.q_res(chips)',
 P_PATH='@t6g_mb_lib.t6g(sch_1):page125_i22@pure_quanta.q_res(chips)',
 PATH='I22',
 DRAWING='@T6G_MB_LIB.T6G(SCH_1):PAGE332',
 WATTAGE='1/16W',
 TOLERANCE='1%',
 MATERIAL='EMPTY',
 PHYS_PAGE='125',
 XY='(-2125,3175)',
 ROT='0',
 VER='2',
 PACK_TYPE='0402LF',
 LOCATION='R4120',
 CDS_LIB='pure_quanta',
 CDS_PART_NAME='Q_RES_0402LF-100K,1%,1/16W,EMPTY,CS41002FB09',
 PART_NUMBER='CS41002FB09',
 VALUE='100K',
 PRIM_FILE='./archive_libs/logical/q_res/chips/chips.prt';

PART_NAME
 R4121 'Q_RES_0402LF-10K,1%,1/16W,CHIP,CS31002FB08':;

SECTION_NUMBER 1
 '@T6G_MB_LIB.T6G(SCH_1):PAGE332_I14@PURE_QUANTA.Q_RES(CHIPS)':
 C_PATH='@t6g_mb_lib.t6g(sch_1):page332_i14@pure_quanta.q_res(chips)',
 P_PATH='@t6g_mb_lib.t6g(sch_1):page125_i14@pure_quanta.q_res(chips)',
 PATH='I14',
 DRAWING='@T6G_MB_LIB.T6G(SCH_1):PAGE332',
 WATTAGE='1/16W',
 TOLERANCE='1%',
 MATERIAL='CHIP',
 PHYS_PAGE='125',
 XY='(-2150,825)',
 ROT='0',
 VER='2',
 PACK_TYPE='0402LF',
 LOCATION='R4121',
 CDS_LIB='pure_quanta',
 CDS_PART_NAME='Q_RES_0402LF-10K,1%,1/16W,CHIP,CS31002FB08',
 PART_NUMBER='CS31002FB08',
 VALUE='10K',
 PRIM_FILE='./archive_libs/logical/q_res/chips/chips.prt';

PART_NAME
 R4122 'Q_RES_0402LF-100K,1%,1/16W,EMPTY,CS41002FB09':;

SECTION_NUMBER 1
 '@T6G_MB_LIB.T6G(SCH_1):PAGE332_I13@PURE_QUANTA.Q_RES(CHIPS)':
 C_PATH='@t6g_mb_lib.t6g(sch_1):page332_i13@pure_quanta.q_res(chips)',
 P_PATH='@t6g_mb_lib.t6g(sch_1):page125_i13@pure_quanta.q_res(chips)',
 PATH='I13',
 DRAWING='@T6G_MB_LIB.T6G(SCH_1):PAGE332',
 WATTAGE='1/16W',
 TOLERANCE='1%',
 MATERIAL='EMPTY',
 PHYS_PAGE='125',
 XY='(-2125,350)',
 ROT='0',
 VER='2',
 PACK_TYPE='0402LF',
 LOCATION='R4122',
 CDS_LIB='pure_quanta',
 CDS_PART_NAME='Q_RES_0402LF-100K,1%,1/16W,EMPTY,CS41002FB09',
 PART_NUMBER='CS41002FB09',
 VALUE='100K',
 PRIM_FILE='./archive_libs/logical/q_res/chips/chips.prt';

PART_NAME
 R4123 'Q_RES_0402LF-54.9K,1%,1/16W,EMPTY,CS35492FB03':;

SECTION_NUMBER 1
 '@T6G_MB_LIB.T6G(SCH_1):PAGE332_I18@PURE_QUANTA.Q_RES(CHIPS)':
 C_PATH='@t6g_mb_lib.t6g(sch_1):page332_i18@pure_quanta.q_res(chips)',
 P_PATH='@t6g_mb_lib.t6g(sch_1):page125_i18@pure_quanta.q_res(chips)',
 PATH='I18',
 DRAWING='@T6G_MB_LIB.T6G(SCH_1):PAGE332',
 WATTAGE='1/16W',
 TOLERANCE='1%',
 MATERIAL='EMPTY',
 PHYS_PAGE='125',
 XY='(-2125,2275)',
 ROT='0',
 VER='2',
 PACK_TYPE='0402LF',
 LOCATION='R4123',
 CDS_LIB='pure_quanta',
 CDS_PART_NAME='Q_RES_0402LF-54.9K,1%,1/16W,EMPTY,CS35492FB03',
 PART_NUMBER='CS35492FB03',
 VALUE='54.9K',
 PRIM_FILE='./archive_libs/logical/q_res/chips/chips.prt';

PART_NAME
 R4124 'Q_RES_0402LF-100K,1%,1/16W,EMPTY,CS41002FB09':;

SECTION_NUMBER 1
 '@T6G_MB_LIB.T6G(SCH_1):PAGE332_I135@PURE_QUANTA.Q_RES(CHIPS)':
 C_PATH='@t6g_mb_lib.t6g(sch_1):page332_i135@pure_quanta.q_res(chips)',
 P_PATH='@t6g_mb_lib.t6g(sch_1):page125_i135@pure_quanta.q_res(chips)',
 PATH='I135',
 DRAWING='@T6G_MB_LIB.T6G(SCH_1):PAGE332',
 WATTAGE='1/16W',
 TOLERANCE='1%',
 MATERIAL='EMPTY',
 PHYS_PAGE='125',
 XY='(-2100,1800)',
 ROT='0',
 VER='2',
 PACK_TYPE='0402LF',
 LOCATION='R4124',
 CDS_LIB='pure_quanta',
 CDS_PART_NAME='Q_RES_0402LF-100K,1%,1/16W,EMPTY,CS41002FB09',
 PART_NUMBER='CS41002FB09',
 VALUE='100K',
 PRIM_FILE='./archive_libs/logical/q_res/chips/chips.prt';

PART_NAME
 R4125 'Q_RES_0402LF-4.7K,5%,1/16W,CHIP,CS24702JB10':;

SECTION_NUMBER 1
 '@T6G_MB_LIB.T6G(SCH_1):PAGE332_I39@PURE_QUANTA.Q_RES(CHIPS)':
 C_PATH='@t6g_mb_lib.t6g(sch_1):page332_i39@pure_quanta.q_res(chips)',
 P_PATH='@t6g_mb_lib.t6g(sch_1):page125_i39@pure_quanta.q_res(chips)',
 PATH='I39',
 DRAWING='@T6G_MB_LIB.T6G(SCH_1):PAGE332',
 WATTAGE='1/16W',
 TOLERANCE='5%',
 MATERIAL='CHIP',
 PHYS_PAGE='125',
 XY='(-975,4025)',
 ROT='0',
 VER='2',
 PACK_TYPE='0402LF',
 LOCATION='R4125',
 CDS_LIB='pure_quanta',
 CDS_PART_NAME='Q_RES_0402LF-4.7K,5%,1/16W,CHIP,CS24702JB10',
 PART_NUMBER='CS24702JB10',
 VALUE='4.7K',
 PRIM_FILE='./archive_libs/logical/q_res/chips/chips.prt';

PART_NAME
 R4126 'Q_RES_0402LF-4.7K,5%,1/16W,CHIP,CS24702JB10':;

SECTION_NUMBER 1
 '@T6G_MB_LIB.T6G(SCH_1):PAGE332_I27@PURE_QUANTA.Q_RES(CHIPS)':
 C_PATH='@t6g_mb_lib.t6g(sch_1):page332_i27@pure_quanta.q_res(chips)',
 P_PATH='@t6g_mb_lib.t6g(sch_1):page125_i27@pure_quanta.q_res(chips)',
 PATH='I27',
 DRAWING='@T6G_MB_LIB.T6G(SCH_1):PAGE332',
 WATTAGE='1/16W',
 TOLERANCE='5%',
 MATERIAL='CHIP',
 PHYS_PAGE='125',
 XY='(-975,1200)',
 ROT='0',
 VER='2',
 PACK_TYPE='0402LF',
 LOCATION='R4126',
 CDS_LIB='pure_quanta',
 CDS_PART_NAME='Q_RES_0402LF-4.7K,5%,1/16W,CHIP,CS24702JB10',
 PART_NUMBER='CS24702JB10',
 VALUE='4.7K',
 PRIM_FILE='./archive_libs/logical/q_res/chips/chips.prt';

PART_NAME
 R4127 'Q_RES_0402LF-4.7K,5%,1/16W,CHIP,CS24702JB10':;

SECTION_NUMBER 1
 '@T6G_MB_LIB.T6G(SCH_1):PAGE332_I35@PURE_QUANTA.Q_RES(CHIPS)':
 C_PATH='@t6g_mb_lib.t6g(sch_1):page332_i35@pure_quanta.q_res(chips)',
 P_PATH='@t6g_mb_lib.t6g(sch_1):page125_i35@pure_quanta.q_res(chips)',
 PATH='I35',
 DRAWING='@T6G_MB_LIB.T6G(SCH_1):PAGE332',
 WATTAGE='1/16W',
 TOLERANCE='5%',
 MATERIAL='CHIP',
 PHYS_PAGE='125',
 XY='(-950,2650)',
 ROT='0',
 VER='2',
 PACK_TYPE='0402LF',
 LOCATION='R4127',
 CDS_LIB='pure_quanta',
 CDS_PART_NAME='Q_RES_0402LF-4.7K,5%,1/16W,CHIP,CS24702JB10',
 PART_NUMBER='CS24702JB10',
 VALUE='4.7K',
 PRIM_FILE='./archive_libs/logical/q_res/chips/chips.prt';

PART_NAME
 R4128 'Q_RES_0402LF-100K,1%,1/16W,CHIP,CS41002FB09':;

SECTION_NUMBER 1
 '@T6G_MB_LIB.T6G(SCH_1):PAGE332_I104@PURE_QUANTA.Q_RES(CHIPS)':
 C_PATH='@t6g_mb_lib.t6g(sch_1):page332_i104@pure_quanta.q_res(chips)',
 P_PATH='@t6g_mb_lib.t6g(sch_1):page125_i104@pure_quanta.q_res(chips)',
 PATH='I104',
 DRAWING='@T6G_MB_LIB.T6G(SCH_1):PAGE332',
 WATTAGE='1/16W',
 TOLERANCE='1%',
 MATERIAL='CHIP',
 PHYS_PAGE='125',
 XY='(175,4150)',
 ROT='0',
 VER='2',
 PACK_TYPE='0402LF',
 LOCATION='R4128',
 CDS_LIB='pure_quanta',
 CDS_PART_NAME='Q_RES_0402LF-100K,1%,1/16W,CHIP,CS41002FB09',
 PART_NUMBER='CS41002FB09',
 VALUE='100K',
 PRIM_FILE='./archive_libs/logical/q_res/chips/chips.prt';

PART_NAME
 R4129 'Q_RES_0402LF-100K,1%,1/16W,CHIP,CS41002FB09':;

SECTION_NUMBER 1
 '@T6G_MB_LIB.T6G(SCH_1):PAGE332_I66@PURE_QUANTA.Q_RES(CHIPS)':
 C_PATH='@t6g_mb_lib.t6g(sch_1):page332_i66@pure_quanta.q_res(chips)',
 P_PATH='@t6g_mb_lib.t6g(sch_1):page125_i66@pure_quanta.q_res(chips)',
 PATH='I66',
 DRAWING='@T6G_MB_LIB.T6G(SCH_1):PAGE332',
 WATTAGE='1/16W',
 TOLERANCE='1%',
 MATERIAL='CHIP',
 PHYS_PAGE='125',
 XY='(175,1325)',
 ROT='0',
 VER='2',
 PACK_TYPE='0402LF',
 LOCATION='R4129',
 CDS_LIB='pure_quanta',
 CDS_PART_NAME='Q_RES_0402LF-100K,1%,1/16W,CHIP,CS41002FB09',
 PART_NUMBER='CS41002FB09',
 VALUE='100K',
 PRIM_FILE='./archive_libs/logical/q_res/chips/chips.prt';

PART_NAME
 R4130 'Q_RES_0402LF-100K,1%,1/16W,CHIP,CS41002FB09':;

SECTION_NUMBER 1
 '@T6G_MB_LIB.T6G(SCH_1):PAGE332_I70@PURE_QUANTA.Q_RES(CHIPS)':
 C_PATH='@t6g_mb_lib.t6g(sch_1):page332_i70@pure_quanta.q_res(chips)',
 P_PATH='@t6g_mb_lib.t6g(sch_1):page125_i70@pure_quanta.q_res(chips)',
 PATH='I70',
 DRAWING='@T6G_MB_LIB.T6G(SCH_1):PAGE332',
 WATTAGE='1/16W',
 TOLERANCE='1%',
 MATERIAL='CHIP',
 PHYS_PAGE='125',
 XY='(200,2775)',
 ROT='0',
 VER='2',
 PACK_TYPE='0402LF',
 LOCATION='R4130',
 CDS_LIB='pure_quanta',
 CDS_PART_NAME='Q_RES_0402LF-100K,1%,1/16W,CHIP,CS41002FB09',
 PART_NUMBER='CS41002FB09',
 VALUE='100K',
 PRIM_FILE='./archive_libs/logical/q_res/chips/chips.prt';

PART_NAME
 R4131 'Q_RES_0402LF-54.9K,1%,1/16W,EMPTY,CS35492FB03':;

SECTION_NUMBER 1
 '@T6G_MB_LIB.T6G(SCH_1):PAGE332_I97@PURE_QUANTA.Q_RES(CHIPS)':
 C_PATH='@t6g_mb_lib.t6g(sch_1):page332_i97@pure_quanta.q_res(chips)',
 P_PATH='@t6g_mb_lib.t6g(sch_1):page125_i97@pure_quanta.q_res(chips)',
 PATH='I97',
 DRAWING='@T6G_MB_LIB.T6G(SCH_1):PAGE332',
 WATTAGE='1/16W',
 TOLERANCE='1%',
 MATERIAL='EMPTY',
 PHYS_PAGE='125',
 XY='(2475,3950)',
 ROT='0',
 VER='2',
 PACK_TYPE='0402LF',
 LOCATION='R4131',
 CDS_LIB='pure_quanta',
 CDS_PART_NAME='Q_RES_0402LF-54.9K,1%,1/16W,EMPTY,CS35492FB03',
 PART_NUMBER='CS35492FB03',
 VALUE='54.9K',
 PRIM_FILE='./archive_libs/logical/q_res/chips/chips.prt';

PART_NAME
 R4132 'Q_RES_0402LF-100K,1%,1/16W,EMPTY,CS41002FB09':;

SECTION_NUMBER 1
 '@T6G_MB_LIB.T6G(SCH_1):PAGE332_I96@PURE_QUANTA.Q_RES(CHIPS)':
 C_PATH='@t6g_mb_lib.t6g(sch_1):page332_i96@pure_quanta.q_res(chips)',
 P_PATH='@t6g_mb_lib.t6g(sch_1):page125_i96@pure_quanta.q_res(chips)',
 PATH='I96',
 DRAWING='@T6G_MB_LIB.T6G(SCH_1):PAGE332',
 WATTAGE='1/16W',
 TOLERANCE='1%',
 MATERIAL='EMPTY',
 PHYS_PAGE='125',
 XY='(2500,3475)',
 ROT='0',
 VER='2',
 PACK_TYPE='0402LF',
 LOCATION='R4132',
 CDS_LIB='pure_quanta',
 CDS_PART_NAME='Q_RES_0402LF-100K,1%,1/16W,EMPTY,CS41002FB09',
 PART_NUMBER='CS41002FB09',
 VALUE='100K',
 PRIM_FILE='./archive_libs/logical/q_res/chips/chips.prt';

PART_NAME
 R4133 'Q_RES_0402LF-54.9K,1%,1/16W,EMPTY,CS35492FB03':;

SECTION_NUMBER 1
 '@T6G_MB_LIB.T6G(SCH_1):PAGE332_I82@PURE_QUANTA.Q_RES(CHIPS)':
 C_PATH='@t6g_mb_lib.t6g(sch_1):page332_i82@pure_quanta.q_res(chips)',
 P_PATH='@t6g_mb_lib.t6g(sch_1):page125_i82@pure_quanta.q_res(chips)',
 PATH='I82',
 DRAWING='@T6G_MB_LIB.T6G(SCH_1):PAGE332',
 WATTAGE='1/16W',
 TOLERANCE='1%',
 MATERIAL='EMPTY',
 PHYS_PAGE='125',
 XY='(2475,1125)',
 ROT='0',
 VER='2',
 PACK_TYPE='0402LF',
 LOCATION='R4133',
 CDS_LIB='pure_quanta',
 CDS_PART_NAME='Q_RES_0402LF-54.9K,1%,1/16W,EMPTY,CS35492FB03',
 PART_NUMBER='CS35492FB03',
 VALUE='54.9K',
 PRIM_FILE='./archive_libs/logical/q_res/chips/chips.prt';

PART_NAME
 R4134 'Q_RES_0402LF-100K,1%,1/16W,EMPTY,CS41002FB09':;

SECTION_NUMBER 1
 '@T6G_MB_LIB.T6G(SCH_1):PAGE332_I81@PURE_QUANTA.Q_RES(CHIPS)':
 C_PATH='@t6g_mb_lib.t6g(sch_1):page332_i81@pure_quanta.q_res(chips)',
 P_PATH='@t6g_mb_lib.t6g(sch_1):page125_i81@pure_quanta.q_res(chips)',
 PATH='I81',
 DRAWING='@T6G_MB_LIB.T6G(SCH_1):PAGE332',
 WATTAGE='1/16W',
 TOLERANCE='1%',
 MATERIAL='EMPTY',
 PHYS_PAGE='125',
 XY='(2500,650)',
 ROT='0',
 VER='2',
 PACK_TYPE='0402LF',
 LOCATION='R4134',
 CDS_LIB='pure_quanta',
 CDS_PART_NAME='Q_RES_0402LF-100K,1%,1/16W,EMPTY,CS41002FB09',
 PART_NUMBER='CS41002FB09',
 VALUE='100K',
 PRIM_FILE='./archive_libs/logical/q_res/chips/chips.prt';

PART_NAME
 R4135 'Q_RES_0402LF-10K,1%,1/16W,CHIP,CS31002FB08':;

SECTION_NUMBER 1
 '@T6G_MB_LIB.T6G(SCH_1):PAGE332_I93@PURE_QUANTA.Q_RES(CHIPS)':
 C_PATH='@t6g_mb_lib.t6g(sch_1):page332_i93@pure_quanta.q_res(chips)',
 P_PATH='@t6g_mb_lib.t6g(sch_1):page125_i93@pure_quanta.q_res(chips)',
 PATH='I93',
 DRAWING='@T6G_MB_LIB.T6G(SCH_1):PAGE332',
 WATTAGE='1/16W',
 TOLERANCE='1%',
 MATERIAL='CHIP',
 PHYS_PAGE='125',
 XY='(2500,2575)',
 ROT='0',
 VER='2',
 PACK_TYPE='0402LF',
 LOCATION='R4135',
 CDS_LIB='pure_quanta',
 CDS_PART_NAME='Q_RES_0402LF-10K,1%,1/16W,CHIP,CS31002FB08',
 PART_NUMBER='CS31002FB08',
 VALUE='10K',
 PRIM_FILE='./archive_libs/logical/q_res/chips/chips.prt';

PART_NAME
 R4136 'Q_RES_0402LF-100K,1%,1/16W,EMPTY,CS41002FB09':;

SECTION_NUMBER 1
 '@T6G_MB_LIB.T6G(SCH_1):PAGE332_I92@PURE_QUANTA.Q_RES(CHIPS)':
 C_PATH='@t6g_mb_lib.t6g(sch_1):page332_i92@pure_quanta.q_res(chips)',
 P_PATH='@t6g_mb_lib.t6g(sch_1):page125_i92@pure_quanta.q_res(chips)',
 PATH='I92',
 DRAWING='@T6G_MB_LIB.T6G(SCH_1):PAGE332',
 WATTAGE='1/16W',
 TOLERANCE='1%',
 MATERIAL='EMPTY',
 PHYS_PAGE='125',
 XY='(2525,2100)',
 ROT='0',
 VER='2',
 PACK_TYPE='0402LF',
 LOCATION='R4136',
 CDS_LIB='pure_quanta',
 CDS_PART_NAME='Q_RES_0402LF-100K,1%,1/16W,EMPTY,CS41002FB09',
 PART_NUMBER='CS41002FB09',
 VALUE='100K',
 PRIM_FILE='./archive_libs/logical/q_res/chips/chips.prt';

PART_NAME
 R4137 'Q_RES_0402LF-4.7K,5%,1/16W,CHIP,CS24702JB10':;

SECTION_NUMBER 1
 '@T6G_MB_LIB.T6G(SCH_1):PAGE332_I107@PURE_QUANTA.Q_RES(CHIPS)':
 C_PATH='@t6g_mb_lib.t6g(sch_1):page332_i107@pure_quanta.q_res(chips)',
 P_PATH='@t6g_mb_lib.t6g(sch_1):page125_i107@pure_quanta.q_res(chips)',
 PATH='I107',
 DRAWING='@T6G_MB_LIB.T6G(SCH_1):PAGE332',
 WATTAGE='1/16W',
 TOLERANCE='5%',
 MATERIAL='CHIP',
 PHYS_PAGE='125',
 XY='(3650,4325)',
 ROT='0',
 VER='2',
 PACK_TYPE='0402LF',
 LOCATION='R4137',
 CDS_LIB='pure_quanta',
 CDS_PART_NAME='Q_RES_0402LF-4.7K,5%,1/16W,CHIP,CS24702JB10',
 PART_NUMBER='CS24702JB10',
 VALUE='4.7K',
 PRIM_FILE='./archive_libs/logical/q_res/chips/chips.prt';

PART_NAME
 R4138 'Q_RES_0402LF-4.7K,5%,1/16W,CHIP,CS24702JB10':;

SECTION_NUMBER 1
 '@T6G_MB_LIB.T6G(SCH_1):PAGE332_I88@PURE_QUANTA.Q_RES(CHIPS)':
 C_PATH='@t6g_mb_lib.t6g(sch_1):page332_i88@pure_quanta.q_res(chips)',
 P_PATH='@t6g_mb_lib.t6g(sch_1):page125_i88@pure_quanta.q_res(chips)',
 PATH='I88',
 DRAWING='@T6G_MB_LIB.T6G(SCH_1):PAGE332',
 WATTAGE='1/16W',
 TOLERANCE='5%',
 MATERIAL='CHIP',
 PHYS_PAGE='125',
 XY='(3650,1500)',
 ROT='0',
 VER='2',
 PACK_TYPE='0402LF',
 LOCATION='R4138',
 CDS_LIB='pure_quanta',
 CDS_PART_NAME='Q_RES_0402LF-4.7K,5%,1/16W,CHIP,CS24702JB10',
 PART_NUMBER='CS24702JB10',
 VALUE='4.7K',
 PRIM_FILE='./archive_libs/logical/q_res/chips/chips.prt';

PART_NAME
 R4139 'Q_RES_0402LF-4.7K,5%,1/16W,CHIP,CS24702JB10':;

SECTION_NUMBER 1
 '@T6G_MB_LIB.T6G(SCH_1):PAGE332_I99@PURE_QUANTA.Q_RES(CHIPS)':
 C_PATH='@t6g_mb_lib.t6g(sch_1):page332_i99@pure_quanta.q_res(chips)',
 P_PATH='@t6g_mb_lib.t6g(sch_1):page125_i99@pure_quanta.q_res(chips)',
 PATH='I99',
 DRAWING='@T6G_MB_LIB.T6G(SCH_1):PAGE332',
 WATTAGE='1/16W',
 TOLERANCE='5%',
 MATERIAL='CHIP',
 PHYS_PAGE='125',
 XY='(3675,2950)',
 ROT='0',
 VER='2',
 PACK_TYPE='0402LF',
 LOCATION='R4139',
 CDS_LIB='pure_quanta',
 CDS_PART_NAME='Q_RES_0402LF-4.7K,5%,1/16W,CHIP,CS24702JB10',
 PART_NUMBER='CS24702JB10',
 VALUE='4.7K',
 PRIM_FILE='./archive_libs/logical/q_res/chips/chips.prt';

PART_NAME
 R4140 'Q_RES_0402LF-100K,1%,1/16W,CHIP,CS41002FB09':;

SECTION_NUMBER 1
 '@T6G_MB_LIB.T6G(SCH_1):PAGE332_I131@PURE_QUANTA.Q_RES(CHIPS)':
 C_PATH='@t6g_mb_lib.t6g(sch_1):page332_i131@pure_quanta.q_res(chips)',
 P_PATH='@t6g_mb_lib.t6g(sch_1):page125_i131@pure_quanta.q_res(chips)',
 PATH='I131',
 DRAWING='@T6G_MB_LIB.T6G(SCH_1):PAGE332',
 WATTAGE='1/16W',
 TOLERANCE='1%',
 MATERIAL='CHIP',
 PHYS_PAGE='125',
 XY='(4800,4450)',
 ROT='0',
 VER='2',
 PACK_TYPE='0402LF',
 LOCATION='R4140',
 CDS_LIB='pure_quanta',
 CDS_PART_NAME='Q_RES_0402LF-100K,1%,1/16W,CHIP,CS41002FB09',
 PART_NUMBER='CS41002FB09',
 VALUE='100K',
 PRIM_FILE='./archive_libs/logical/q_res/chips/chips.prt';

PART_NAME
 R4141 'Q_RES_0402LF-100K,1%,1/16W,CHIP,CS41002FB09':;

SECTION_NUMBER 1
 '@T6G_MB_LIB.T6G(SCH_1):PAGE332_I114@PURE_QUANTA.Q_RES(CHIPS)':
 C_PATH='@t6g_mb_lib.t6g(sch_1):page332_i114@pure_quanta.q_res(chips)',
 P_PATH='@t6g_mb_lib.t6g(sch_1):page125_i114@pure_quanta.q_res(chips)',
 PATH='I114',
 DRAWING='@T6G_MB_LIB.T6G(SCH_1):PAGE332',
 WATTAGE='1/16W',
 TOLERANCE='1%',
 MATERIAL='CHIP',
 PHYS_PAGE='125',
 XY='(4800,1625)',
 ROT='0',
 VER='2',
 PACK_TYPE='0402LF',
 LOCATION='R4141',
 CDS_LIB='pure_quanta',
 CDS_PART_NAME='Q_RES_0402LF-100K,1%,1/16W,CHIP,CS41002FB09',
 PART_NUMBER='CS41002FB09',
 VALUE='100K',
 PRIM_FILE='./archive_libs/logical/q_res/chips/chips.prt';

PART_NAME
 R4142 'Q_RES_0402LF-100K,1%,1/16W,CHIP,CS41002FB09':;

SECTION_NUMBER 1
 '@T6G_MB_LIB.T6G(SCH_1):PAGE332_I122@PURE_QUANTA.Q_RES(CHIPS)':
 C_PATH='@t6g_mb_lib.t6g(sch_1):page332_i122@pure_quanta.q_res(chips)',
 P_PATH='@t6g_mb_lib.t6g(sch_1):page125_i122@pure_quanta.q_res(chips)',
 PATH='I122',
 DRAWING='@T6G_MB_LIB.T6G(SCH_1):PAGE332',
 WATTAGE='1/16W',
 TOLERANCE='1%',
 MATERIAL='CHIP',
 PHYS_PAGE='125',
 XY='(4825,3075)',
 ROT='0',
 VER='2',
 PACK_TYPE='0402LF',
 LOCATION='R4142',
 CDS_LIB='pure_quanta',
 CDS_PART_NAME='Q_RES_0402LF-100K,1%,1/16W,CHIP,CS41002FB09',
 PART_NUMBER='CS41002FB09',
 VALUE='100K',
 PRIM_FILE='./archive_libs/logical/q_res/chips/chips.prt';

PART_NAME
 R4143 'Q_RES_0402LF-33.2,1%,1/16W,CHIP,CS03322FB03':;

SECTION_NUMBER 1
 '@T6G_MB_LIB.T6G(SCH_1):PAGE80_I231@PURE_QUANTA.Q_RES(CHIPS)':
 C_PATH='@t6g_mb_lib.t6g(sch_1):page80_i231@pure_quanta.q_res(chips)',
 P_PATH='@t6g_mb_lib.t6g(sch_1):page81_i231@pure_quanta.q_res(chips)',
 PATH='I231',
 DRAWING='@T6G_MB_LIB.T6G(SCH_1):PAGE80',
 WATTAGE='1/16W',
 TOLERANCE='1%',
 MATERIAL='CHIP',
 PHYS_PAGE='81',
 XY='(-2300,2625)',
 ROT='0',
 VER='1',
 PACK_TYPE='0402LF',
 LOCATION='R4143',
 CDS_LIB='pure_quanta',
 CDS_PART_NAME='Q_RES_0402LF-33.2,1%,1/16W,CHIP,CS03322FB03',
 PART_NUMBER='CS03322FB03',
 VALUE='33.2',
 PRIM_FILE='./archive_libs/logical/q_res/chips/chips.prt';

PART_NAME
 R4144 'Q_RES_0402LF-33.2,1%,1/16W,CHIP,CS03322FB03':;

SECTION_NUMBER 1
 '@T6G_MB_LIB.T6G(SCH_1):PAGE80_I233@PURE_QUANTA.Q_RES(CHIPS)':
 C_PATH='@t6g_mb_lib.t6g(sch_1):page80_i233@pure_quanta.q_res(chips)',
 P_PATH='@t6g_mb_lib.t6g(sch_1):page81_i233@pure_quanta.q_res(chips)',
 PATH='I233',
 DRAWING='@T6G_MB_LIB.T6G(SCH_1):PAGE80',
 WATTAGE='1/16W',
 TOLERANCE='1%',
 MATERIAL='CHIP',
 PHYS_PAGE='81',
 XY='(-2300,2575)',
 ROT='0',
 VER='1',
 PACK_TYPE='0402LF',
 LOCATION='R4144',
 CDS_LIB='pure_quanta',
 CDS_PART_NAME='Q_RES_0402LF-33.2,1%,1/16W,CHIP,CS03322FB03',
 PART_NUMBER='CS03322FB03',
 VALUE='33.2',
 PRIM_FILE='./archive_libs/logical/q_res/chips/chips.prt';

PART_NAME
 R4145 'Q_RES_0402LF-33.2,1%,1/16W,CHIP,CS03322FB03':;

SECTION_NUMBER 1
 '@T6G_MB_LIB.T6G(SCH_1):PAGE79_I121@PURE_QUANTA.Q_RES(CHIPS)':
 C_PATH='@t6g_mb_lib.t6g(sch_1):page79_i121@pure_quanta.q_res(chips)',
 P_PATH='@t6g_mb_lib.t6g(sch_1):page80_i121@pure_quanta.q_res(chips)',
 PATH='I121',
 DRAWING='@T6G_MB_LIB.T6G(SCH_1):PAGE79',
 WATTAGE='1/16W',
 TOLERANCE='1%',
 MATERIAL='CHIP',
 PHYS_PAGE='80',
 XY='(-2775,4850)',
 ROT='0',
 VER='1',
 PACK_TYPE='0402LF',
 LOCATION='R4145',
 CDS_LIB='pure_quanta',
 CDS_PART_NAME='Q_RES_0402LF-33.2,1%,1/16W,CHIP,CS03322FB03',
 PART_NUMBER='CS03322FB03',
 VALUE='33.2',
 PRIM_FILE='./archive_libs/logical/q_res/chips/chips.prt';

PART_NAME
 R4146 'Q_RES_0402LF-33.2,1%,1/16W,CHIP,CS03322FB03':;

SECTION_NUMBER 1
 '@T6G_MB_LIB.T6G(SCH_1):PAGE79_I122@PURE_QUANTA.Q_RES(CHIPS)':
 C_PATH='@t6g_mb_lib.t6g(sch_1):page79_i122@pure_quanta.q_res(chips)',
 P_PATH='@t6g_mb_lib.t6g(sch_1):page80_i122@pure_quanta.q_res(chips)',
 PATH='I122',
 DRAWING='@T6G_MB_LIB.T6G(SCH_1):PAGE79',
 WATTAGE='1/16W',
 TOLERANCE='1%',
 MATERIAL='CHIP',
 PHYS_PAGE='80',
 XY='(-2775,4800)',
 ROT='0',
 VER='1',
 PACK_TYPE='0402LF',
 LOCATION='R4146',
 CDS_LIB='pure_quanta',
 CDS_PART_NAME='Q_RES_0402LF-33.2,1%,1/16W,CHIP,CS03322FB03',
 PART_NUMBER='CS03322FB03',
 VALUE='33.2',
 PRIM_FILE='./archive_libs/logical/q_res/chips/chips.prt';

PART_NAME
 R4147 'Q_RES_0402LF-33.2,1%,1/16W,CHIP,CS03322FB03':;

SECTION_NUMBER 1
 '@T6G_MB_LIB.T6G(SCH_1):PAGE80_I240@PURE_QUANTA.Q_RES(CHIPS)':
 C_PATH='@t6g_mb_lib.t6g(sch_1):page80_i240@pure_quanta.q_res(chips)',
 P_PATH='@t6g_mb_lib.t6g(sch_1):page81_i240@pure_quanta.q_res(chips)',
 PATH='I240',
 DRAWING='@T6G_MB_LIB.T6G(SCH_1):PAGE80',
 WATTAGE='1/16W',
 TOLERANCE='1%',
 MATERIAL='CHIP',
 PHYS_PAGE='81',
 XY='(-2300,2425)',
 ROT='0',
 VER='1',
 PACK_TYPE='0402LF',
 LOCATION='R4147',
 CDS_LIB='pure_quanta',
 CDS_PART_NAME='Q_RES_0402LF-33.2,1%,1/16W,CHIP,CS03322FB03',
 PART_NUMBER='CS03322FB03',
 VALUE='33.2',
 PRIM_FILE='./archive_libs/logical/q_res/chips/chips.prt';

PART_NAME
 R4148 'Q_RES_0402LF-33.2,1%,1/16W,CHIP,CS03322FB03':;

SECTION_NUMBER 1
 '@T6G_MB_LIB.T6G(SCH_1):PAGE80_I242@PURE_QUANTA.Q_RES(CHIPS)':
 C_PATH='@t6g_mb_lib.t6g(sch_1):page80_i242@pure_quanta.q_res(chips)',
 P_PATH='@t6g_mb_lib.t6g(sch_1):page81_i242@pure_quanta.q_res(chips)',
 PATH='I242',
 DRAWING='@T6G_MB_LIB.T6G(SCH_1):PAGE80',
 WATTAGE='1/16W',
 TOLERANCE='1%',
 MATERIAL='CHIP',
 PHYS_PAGE='81',
 XY='(-2300,2375)',
 ROT='0',
 VER='1',
 PACK_TYPE='0402LF',
 LOCATION='R4148',
 CDS_LIB='pure_quanta',
 CDS_PART_NAME='Q_RES_0402LF-33.2,1%,1/16W,CHIP,CS03322FB03',
 PART_NUMBER='CS03322FB03',
 VALUE='33.2',
 PRIM_FILE='./archive_libs/logical/q_res/chips/chips.prt';

PART_NAME
 R4149 'Q_RES_0402LF-33.2,1%,1/16W,CHIP,CS03322FB03':;

SECTION_NUMBER 1
 '@T6G_MB_LIB.T6G(SCH_1):PAGE349_I89@PURE_QUANTA.Q_RES(CHIPS)':
 C_PATH='@t6g_mb_lib.t6g(sch_1):page349_i89@pure_quanta.q_res(chips)',
 P_PATH='@t6g_mb_lib.t6g(sch_1):page151_i89@pure_quanta.q_res(chips)',
 PATH='I89',
 DRAWING='@T6G_MB_LIB.T6G(SCH_1):PAGE349',
 WATTAGE='1/16W',
 TOLERANCE='1%',
 MATERIAL='CHIP',
 PHYS_PAGE='151',
 XY='(1950,6350)',
 ROT='0',
 VER='1',
 PACK_TYPE='0402LF',
 LOCATION='R4149',
 CDS_LIB='pure_quanta',
 CDS_PART_NAME='Q_RES_0402LF-33.2,1%,1/16W,CHIP,CS03322FB03',
 PART_NUMBER='CS03322FB03',
 VALUE='33.2',
 PRIM_FILE='./archive_libs/logical/q_res/chips/chips.prt';

PART_NAME
 R4150 'Q_RES_0402LF-33.2,1%,1/16W,CHIP,CS03322FB03':;

SECTION_NUMBER 1
 '@T6G_MB_LIB.T6G(SCH_1):PAGE349_I90@PURE_QUANTA.Q_RES(CHIPS)':
 C_PATH='@t6g_mb_lib.t6g(sch_1):page349_i90@pure_quanta.q_res(chips)',
 P_PATH='@t6g_mb_lib.t6g(sch_1):page151_i90@pure_quanta.q_res(chips)',
 PATH='I90',
 DRAWING='@T6G_MB_LIB.T6G(SCH_1):PAGE349',
 WATTAGE='1/16W',
 TOLERANCE='1%',
 MATERIAL='CHIP',
 PHYS_PAGE='151',
 XY='(1950,6300)',
 ROT='0',
 VER='1',
 PACK_TYPE='0402LF',
 LOCATION='R4150',
 CDS_LIB='pure_quanta',
 CDS_PART_NAME='Q_RES_0402LF-33.2,1%,1/16W,CHIP,CS03322FB03',
 PART_NUMBER='CS03322FB03',
 VALUE='33.2',
 PRIM_FILE='./archive_libs/logical/q_res/chips/chips.prt';

PART_NAME
 R4151 'Q_RES_0402LF-33.2,1%,1/16W,CHIP,CS03322FB03':;

SECTION_NUMBER 1
 '@T6G_MB_LIB.T6G(SCH_1):PAGE349_I83@PURE_QUANTA.Q_RES(CHIPS)':
 C_PATH='@t6g_mb_lib.t6g(sch_1):page349_i83@pure_quanta.q_res(chips)',
 P_PATH='@t6g_mb_lib.t6g(sch_1):page151_i83@pure_quanta.q_res(chips)',
 PATH='I83',
 DRAWING='@T6G_MB_LIB.T6G(SCH_1):PAGE349',
 WATTAGE='1/16W',
 TOLERANCE='1%',
 MATERIAL='CHIP',
 PHYS_PAGE='151',
 XY='(1950,6075)',
 ROT='0',
 VER='1',
 PACK_TYPE='0402LF',
 LOCATION='R4151',
 CDS_LIB='pure_quanta',
 CDS_PART_NAME='Q_RES_0402LF-33.2,1%,1/16W,CHIP,CS03322FB03',
 PART_NUMBER='CS03322FB03',
 VALUE='33.2',
 PRIM_FILE='./archive_libs/logical/q_res/chips/chips.prt';

PART_NAME
 R4152 'Q_RES_0402LF-33.2,1%,1/16W,CHIP,CS03322FB03':;

SECTION_NUMBER 1
 '@T6G_MB_LIB.T6G(SCH_1):PAGE349_I84@PURE_QUANTA.Q_RES(CHIPS)':
 C_PATH='@t6g_mb_lib.t6g(sch_1):page349_i84@pure_quanta.q_res(chips)',
 P_PATH='@t6g_mb_lib.t6g(sch_1):page151_i84@pure_quanta.q_res(chips)',
 PATH='I84',
 DRAWING='@T6G_MB_LIB.T6G(SCH_1):PAGE349',
 WATTAGE='1/16W',
 TOLERANCE='1%',
 MATERIAL='CHIP',
 PHYS_PAGE='151',
 XY='(1950,6025)',
 ROT='0',
 VER='1',
 PACK_TYPE='0402LF',
 LOCATION='R4152',
 CDS_LIB='pure_quanta',
 CDS_PART_NAME='Q_RES_0402LF-33.2,1%,1/16W,CHIP,CS03322FB03',
 PART_NUMBER='CS03322FB03',
 VALUE='33.2',
 PRIM_FILE='./archive_libs/logical/q_res/chips/chips.prt';

PART_NAME
 R4153 'Q_RES_0402LF-10K,1%,1/16W,CHIP,CS31002FB08':;

SECTION_NUMBER 1
 '@T6G_MB_LIB.T6G(SCH_1):PAGE332_I4@PURE_QUANTA.Q_RES(CHIPS)':
 C_PATH='@t6g_mb_lib.t6g(sch_1):page332_i4@pure_quanta.q_res(chips)',
 P_PATH='@t6g_mb_lib.t6g(sch_1):page125_i4@pure_quanta.q_res(chips)',
 PATH='I4',
 DRAWING='@T6G_MB_LIB.T6G(SCH_1):PAGE332',
 WATTAGE='1/16W',
 TOLERANCE='1%',
 MATERIAL='CHIP',
 PHYS_PAGE='125',
 XY='(-2075,-725)',
 ROT='0',
 VER='2',
 PACK_TYPE='0402LF',
 LOCATION='R4153',
 CDS_LIB='pure_quanta',
 CDS_PART_NAME='Q_RES_0402LF-10K,1%,1/16W,CHIP,CS31002FB08',
 PART_NUMBER='CS31002FB08',
 VALUE='10K',
 PRIM_FILE='./archive_libs/logical/q_res/chips/chips.prt';

PART_NAME
 R4154 'Q_RES_0402LF-100K,1%,1/16W,EMPTY,CS41002FB09':;

SECTION_NUMBER 1
 '@T6G_MB_LIB.T6G(SCH_1):PAGE332_I2@PURE_QUANTA.Q_RES(CHIPS)':
 C_PATH='@t6g_mb_lib.t6g(sch_1):page332_i2@pure_quanta.q_res(chips)',
 P_PATH='@t6g_mb_lib.t6g(sch_1):page125_i2@pure_quanta.q_res(chips)',
 PATH='I2',
 DRAWING='@T6G_MB_LIB.T6G(SCH_1):PAGE332',
 WATTAGE='1/16W',
 TOLERANCE='1%',
 MATERIAL='EMPTY',
 PHYS_PAGE='125',
 XY='(-2050,-1200)',
 ROT='0',
 VER='2',
 PACK_TYPE='0402LF',
 LOCATION='R4154',
 CDS_LIB='pure_quanta',
 CDS_PART_NAME='Q_RES_0402LF-100K,1%,1/16W,EMPTY,CS41002FB09',
 PART_NUMBER='CS41002FB09',
 VALUE='100K',
 PRIM_FILE='./archive_libs/logical/q_res/chips/chips.prt';

PART_NAME
 R4155 'Q_RES_0402LF-4.7K,5%,1/16W,CHIP,CS24702JB10':;

SECTION_NUMBER 1
 '@T6G_MB_LIB.T6G(SCH_1):PAGE332_I8@PURE_QUANTA.Q_RES(CHIPS)':
 C_PATH='@t6g_mb_lib.t6g(sch_1):page332_i8@pure_quanta.q_res(chips)',
 P_PATH='@t6g_mb_lib.t6g(sch_1):page125_i8@pure_quanta.q_res(chips)',
 PATH='I8',
 DRAWING='@T6G_MB_LIB.T6G(SCH_1):PAGE332',
 WATTAGE='1/16W',
 TOLERANCE='5%',
 MATERIAL='CHIP',
 PHYS_PAGE='125',
 XY='(-900,-350)',
 ROT='0',
 VER='2',
 PACK_TYPE='0402LF',
 LOCATION='R4155',
 CDS_LIB='pure_quanta',
 CDS_PART_NAME='Q_RES_0402LF-4.7K,5%,1/16W,CHIP,CS24702JB10',
 PART_NUMBER='CS24702JB10',
 VALUE='4.7K',
 PRIM_FILE='./archive_libs/logical/q_res/chips/chips.prt';

PART_NAME
 R4156 'Q_RES_0402LF-100K,1%,1/16W,CHIP,CS41002FB09':;

SECTION_NUMBER 1
 '@T6G_MB_LIB.T6G(SCH_1):PAGE332_I48@PURE_QUANTA.Q_RES(CHIPS)':
 C_PATH='@t6g_mb_lib.t6g(sch_1):page332_i48@pure_quanta.q_res(chips)',
 P_PATH='@t6g_mb_lib.t6g(sch_1):page125_i48@pure_quanta.q_res(chips)',
 PATH='I48',
 DRAWING='@T6G_MB_LIB.T6G(SCH_1):PAGE332',
 WATTAGE='1/16W',
 TOLERANCE='1%',
 MATERIAL='CHIP',
 PHYS_PAGE='125',
 XY='(250,-225)',
 ROT='0',
 VER='2',
 PACK_TYPE='0402LF',
 LOCATION='R4156',
 CDS_LIB='pure_quanta',
 CDS_PART_NAME='Q_RES_0402LF-100K,1%,1/16W,CHIP,CS41002FB09',
 PART_NUMBER='CS41002FB09',
 VALUE='100K',
 PRIM_FILE='./archive_libs/logical/q_res/chips/chips.prt';

PART_NAME
 R4157 'Q_RES_0402LF-33.2,1%,1/16W,CHIP,CS03322FB03':;

SECTION_NUMBER 1
 '@T6G_MB_LIB.T6G(SCH_1):PAGE80_I246@PURE_QUANTA.Q_RES(CHIPS)':
 C_PATH='@t6g_mb_lib.t6g(sch_1):page80_i246@pure_quanta.q_res(chips)',
 P_PATH='@t6g_mb_lib.t6g(sch_1):page81_i246@pure_quanta.q_res(chips)',
 PATH='I246',
 DRAWING='@T6G_MB_LIB.T6G(SCH_1):PAGE80',
 WATTAGE='1/16W',
 TOLERANCE='1%',
 MATERIAL='CHIP',
 PHYS_PAGE='81',
 XY='(-2300,2325)',
 ROT='0',
 VER='1',
 PACK_TYPE='0402LF',
 LOCATION='R4157',
 CDS_LIB='pure_quanta',
 CDS_PART_NAME='Q_RES_0402LF-33.2,1%,1/16W,CHIP,CS03322FB03',
 PART_NUMBER='CS03322FB03',
 VALUE='33.2',
 PRIM_FILE='./archive_libs/logical/q_res/chips/chips.prt';

PART_NAME
 R4158 'Q_RES_0402LF-54.9K,1%,1/16W,EMPTY,CS35492FB03':;

SECTION_NUMBER 1
 '@T6G_MB_LIB.T6G(SCH_1):PAGE331_I14@PURE_QUANTA.Q_RES(CHIPS)':
 C_PATH='@t6g_mb_lib.t6g(sch_1):page331_i14@pure_quanta.q_res(chips)',
 P_PATH='@t6g_mb_lib.t6g(sch_1):page124_i14@pure_quanta.q_res(chips)',
 PATH='I14',
 DRAWING='@T6G_MB_LIB.T6G(SCH_1):PAGE331',
 WATTAGE='1/16W',
 TOLERANCE='1%',
 MATERIAL='EMPTY',
 PHYS_PAGE='124',
 XY='(-2000,5200)',
 ROT='0',
 VER='2',
 PACK_TYPE='0402LF',
 LOCATION='R4158',
 CDS_LIB='pure_quanta',
 CDS_PART_NAME='Q_RES_0402LF-54.9K,1%,1/16W,EMPTY,CS35492FB03',
 PART_NUMBER='CS35492FB03',
 VALUE='54.9K',
 PRIM_FILE='./archive_libs/logical/q_res/chips/chips.prt';

PART_NAME
 R4159 'Q_RES_0402LF-100K,1%,1/16W,EMPTY,CS41002FB09':;

SECTION_NUMBER 1
 '@T6G_MB_LIB.T6G(SCH_1):PAGE331_I13@PURE_QUANTA.Q_RES(CHIPS)':
 C_PATH='@t6g_mb_lib.t6g(sch_1):page331_i13@pure_quanta.q_res(chips)',
 P_PATH='@t6g_mb_lib.t6g(sch_1):page124_i13@pure_quanta.q_res(chips)',
 PATH='I13',
 DRAWING='@T6G_MB_LIB.T6G(SCH_1):PAGE331',
 WATTAGE='1/16W',
 TOLERANCE='1%',
 MATERIAL='EMPTY',
 PHYS_PAGE='124',
 XY='(-1975,4725)',
 ROT='0',
 VER='2',
 PACK_TYPE='0402LF',
 LOCATION='R4159',
 CDS_LIB='pure_quanta',
 CDS_PART_NAME='Q_RES_0402LF-100K,1%,1/16W,EMPTY,CS41002FB09',
 PART_NUMBER='CS41002FB09',
 VALUE='100K',
 PRIM_FILE='./archive_libs/logical/q_res/chips/chips.prt';

PART_NAME
 R4160 'Q_RES_0402LF-54.9K,1%,1/16W,EMPTY,CS35492FB03':;

SECTION_NUMBER 1
 '@T6G_MB_LIB.T6G(SCH_1):PAGE331_I4@PURE_QUANTA.Q_RES(CHIPS)':
 C_PATH='@t6g_mb_lib.t6g(sch_1):page331_i4@pure_quanta.q_res(chips)',
 P_PATH='@t6g_mb_lib.t6g(sch_1):page124_i4@pure_quanta.q_res(chips)',
 PATH='I4',
 DRAWING='@T6G_MB_LIB.T6G(SCH_1):PAGE331',
 WATTAGE='1/16W',
 TOLERANCE='1%',
 MATERIAL='EMPTY',
 PHYS_PAGE='124',
 XY='(-2000,2375)',
 ROT='0',
 VER='2',
 PACK_TYPE='0402LF',
 LOCATION='R4160',
 CDS_LIB='pure_quanta',
 CDS_PART_NAME='Q_RES_0402LF-54.9K,1%,1/16W,EMPTY,CS35492FB03',
 PART_NUMBER='CS35492FB03',
 VALUE='54.9K',
 PRIM_FILE='./archive_libs/logical/q_res/chips/chips.prt';

PART_NAME
 R4161 'Q_RES_0402LF-100K,1%,1/16W,EMPTY,CS41002FB09':;

SECTION_NUMBER 1
 '@T6G_MB_LIB.T6G(SCH_1):PAGE331_I2@PURE_QUANTA.Q_RES(CHIPS)':
 C_PATH='@t6g_mb_lib.t6g(sch_1):page331_i2@pure_quanta.q_res(chips)',
 P_PATH='@t6g_mb_lib.t6g(sch_1):page124_i2@pure_quanta.q_res(chips)',
 PATH='I2',
 DRAWING='@T6G_MB_LIB.T6G(SCH_1):PAGE331',
 WATTAGE='1/16W',
 TOLERANCE='1%',
 MATERIAL='EMPTY',
 PHYS_PAGE='124',
 XY='(-1975,1900)',
 ROT='0',
 VER='2',
 PACK_TYPE='0402LF',
 LOCATION='R4161',
 CDS_LIB='pure_quanta',
 CDS_PART_NAME='Q_RES_0402LF-100K,1%,1/16W,EMPTY,CS41002FB09',
 PART_NUMBER='CS41002FB09',
 VALUE='100K',
 PRIM_FILE='./archive_libs/logical/q_res/chips/chips.prt';

PART_NAME
 R4162 'Q_RES_0402LF-54.9K,1%,1/16W,EMPTY,CS35492FB03':;

SECTION_NUMBER 1
 '@T6G_MB_LIB.T6G(SCH_1):PAGE331_I9@PURE_QUANTA.Q_RES(CHIPS)':
 C_PATH='@t6g_mb_lib.t6g(sch_1):page331_i9@pure_quanta.q_res(chips)',
 P_PATH='@t6g_mb_lib.t6g(sch_1):page124_i9@pure_quanta.q_res(chips)',
 PATH='I9',
 DRAWING='@T6G_MB_LIB.T6G(SCH_1):PAGE331',
 WATTAGE='1/16W',
 TOLERANCE='1%',
 MATERIAL='EMPTY',
 PHYS_PAGE='124',
 XY='(-1975,3825)',
 ROT='0',
 VER='2',
 PACK_TYPE='0402LF',
 LOCATION='R4162',
 CDS_LIB='pure_quanta',
 CDS_PART_NAME='Q_RES_0402LF-54.9K,1%,1/16W,EMPTY,CS35492FB03',
 PART_NUMBER='CS35492FB03',
 VALUE='54.9K',
 PRIM_FILE='./archive_libs/logical/q_res/chips/chips.prt';

PART_NAME
 R4163 'Q_RES_0402LF-100K,1%,1/16W,EMPTY,CS41002FB09':;

SECTION_NUMBER 1
 '@T6G_MB_LIB.T6G(SCH_1):PAGE331_I8@PURE_QUANTA.Q_RES(CHIPS)':
 C_PATH='@t6g_mb_lib.t6g(sch_1):page331_i8@pure_quanta.q_res(chips)',
 P_PATH='@t6g_mb_lib.t6g(sch_1):page124_i8@pure_quanta.q_res(chips)',
 PATH='I8',
 DRAWING='@T6G_MB_LIB.T6G(SCH_1):PAGE331',
 WATTAGE='1/16W',
 TOLERANCE='1%',
 MATERIAL='EMPTY',
 PHYS_PAGE='124',
 XY='(-1950,3350)',
 ROT='0',
 VER='2',
 PACK_TYPE='0402LF',
 LOCATION='R4163',
 CDS_LIB='pure_quanta',
 CDS_PART_NAME='Q_RES_0402LF-100K,1%,1/16W,EMPTY,CS41002FB09',
 PART_NUMBER='CS41002FB09',
 VALUE='100K',
 PRIM_FILE='./archive_libs/logical/q_res/chips/chips.prt';

PART_NAME
 R4164 'Q_RES_0402LF-4.7K,5%,1/16W,CHIP,CS24702JB10':;

SECTION_NUMBER 1
 '@T6G_MB_LIB.T6G(SCH_1):PAGE331_I27@PURE_QUANTA.Q_RES(CHIPS)':
 C_PATH='@t6g_mb_lib.t6g(sch_1):page331_i27@pure_quanta.q_res(chips)',
 P_PATH='@t6g_mb_lib.t6g(sch_1):page124_i27@pure_quanta.q_res(chips)',
 PATH='I27',
 DRAWING='@T6G_MB_LIB.T6G(SCH_1):PAGE331',
 WATTAGE='1/16W',
 TOLERANCE='5%',
 MATERIAL='CHIP',
 PHYS_PAGE='124',
 XY='(-825,5575)',
 ROT='0',
 VER='2',
 PACK_TYPE='0402LF',
 LOCATION='R4164',
 CDS_LIB='pure_quanta',
 CDS_PART_NAME='Q_RES_0402LF-4.7K,5%,1/16W,CHIP,CS24702JB10',
 PART_NUMBER='CS24702JB10',
 VALUE='4.7K',
 PRIM_FILE='./archive_libs/logical/q_res/chips/chips.prt';

PART_NAME
 R4165 'Q_RES_0402LF-4.7K,5%,1/16W,CHIP,CS24702JB10':;

SECTION_NUMBER 1
 '@T6G_MB_LIB.T6G(SCH_1):PAGE331_I18@PURE_QUANTA.Q_RES(CHIPS)':
 C_PATH='@t6g_mb_lib.t6g(sch_1):page331_i18@pure_quanta.q_res(chips)',
 P_PATH='@t6g_mb_lib.t6g(sch_1):page124_i18@pure_quanta.q_res(chips)',
 PATH='I18',
 DRAWING='@T6G_MB_LIB.T6G(SCH_1):PAGE331',
 WATTAGE='1/16W',
 TOLERANCE='5%',
 MATERIAL='CHIP',
 PHYS_PAGE='124',
 XY='(-825,2750)',
 ROT='0',
 VER='2',
 PACK_TYPE='0402LF',
 LOCATION='R4165',
 CDS_LIB='pure_quanta',
 CDS_PART_NAME='Q_RES_0402LF-4.7K,5%,1/16W,CHIP,CS24702JB10',
 PART_NUMBER='CS24702JB10',
 VALUE='4.7K',
 PRIM_FILE='./archive_libs/logical/q_res/chips/chips.prt';

PART_NAME
 R4166 'Q_RES_0402LF-4.7K,5%,1/16W,CHIP,CS24702JB10':;

SECTION_NUMBER 1
 '@T6G_MB_LIB.T6G(SCH_1):PAGE331_I23@PURE_QUANTA.Q_RES(CHIPS)':
 C_PATH='@t6g_mb_lib.t6g(sch_1):page331_i23@pure_quanta.q_res(chips)',
 P_PATH='@t6g_mb_lib.t6g(sch_1):page124_i23@pure_quanta.q_res(chips)',
 PATH='I23',
 DRAWING='@T6G_MB_LIB.T6G(SCH_1):PAGE331',
 WATTAGE='1/16W',
 TOLERANCE='5%',
 MATERIAL='CHIP',
 PHYS_PAGE='124',
 XY='(-800,4200)',
 ROT='0',
 VER='2',
 PACK_TYPE='0402LF',
 LOCATION='R4166',
 CDS_LIB='pure_quanta',
 CDS_PART_NAME='Q_RES_0402LF-4.7K,5%,1/16W,CHIP,CS24702JB10',
 PART_NUMBER='CS24702JB10',
 VALUE='4.7K',
 PRIM_FILE='./archive_libs/logical/q_res/chips/chips.prt';

PART_NAME
 R4167 'Q_RES_0402LF-100K,1%,1/16W,CHIP,CS41002FB09':;

SECTION_NUMBER 1
 '@T6G_MB_LIB.T6G(SCH_1):PAGE331_I47@PURE_QUANTA.Q_RES(CHIPS)':
 C_PATH='@t6g_mb_lib.t6g(sch_1):page331_i47@pure_quanta.q_res(chips)',
 P_PATH='@t6g_mb_lib.t6g(sch_1):page124_i47@pure_quanta.q_res(chips)',
 PATH='I47',
 DRAWING='@T6G_MB_LIB.T6G(SCH_1):PAGE331',
 WATTAGE='1/16W',
 TOLERANCE='1%',
 MATERIAL='CHIP',
 PHYS_PAGE='124',
 XY='(325,5700)',
 ROT='0',
 VER='2',
 PACK_TYPE='0402LF',
 LOCATION='R4167',
 CDS_LIB='pure_quanta',
 CDS_PART_NAME='Q_RES_0402LF-100K,1%,1/16W,CHIP,CS41002FB09',
 PART_NUMBER='CS41002FB09',
 VALUE='100K',
 PRIM_FILE='./archive_libs/logical/q_res/chips/chips.prt';

PART_NAME
 R4168 'Q_RES_0402LF-100K,1%,1/16W,CHIP,CS41002FB09':;

SECTION_NUMBER 1
 '@T6G_MB_LIB.T6G(SCH_1):PAGE331_I35@PURE_QUANTA.Q_RES(CHIPS)':
 C_PATH='@t6g_mb_lib.t6g(sch_1):page331_i35@pure_quanta.q_res(chips)',
 P_PATH='@t6g_mb_lib.t6g(sch_1):page124_i35@pure_quanta.q_res(chips)',
 PATH='I35',
 DRAWING='@T6G_MB_LIB.T6G(SCH_1):PAGE331',
 WATTAGE='1/16W',
 TOLERANCE='1%',
 MATERIAL='CHIP',
 PHYS_PAGE='124',
 XY='(325,2875)',
 ROT='0',
 VER='2',
 PACK_TYPE='0402LF',
 LOCATION='R4168',
 CDS_LIB='pure_quanta',
 CDS_PART_NAME='Q_RES_0402LF-100K,1%,1/16W,CHIP,CS41002FB09',
 PART_NUMBER='CS41002FB09',
 VALUE='100K',
 PRIM_FILE='./archive_libs/logical/q_res/chips/chips.prt';

PART_NAME
 R4169 'Q_RES_0402LF-100K,1%,1/16W,CHIP,CS41002FB09':;

SECTION_NUMBER 1
 '@T6G_MB_LIB.T6G(SCH_1):PAGE331_I39@PURE_QUANTA.Q_RES(CHIPS)':
 C_PATH='@t6g_mb_lib.t6g(sch_1):page331_i39@pure_quanta.q_res(chips)',
 P_PATH='@t6g_mb_lib.t6g(sch_1):page124_i39@pure_quanta.q_res(chips)',
 PATH='I39',
 DRAWING='@T6G_MB_LIB.T6G(SCH_1):PAGE331',
 WATTAGE='1/16W',
 TOLERANCE='1%',
 MATERIAL='CHIP',
 PHYS_PAGE='124',
 XY='(350,4325)',
 ROT='0',
 VER='2',
 PACK_TYPE='0402LF',
 LOCATION='R4169',
 CDS_LIB='pure_quanta',
 CDS_PART_NAME='Q_RES_0402LF-100K,1%,1/16W,CHIP,CS41002FB09',
 PART_NUMBER='CS41002FB09',
 VALUE='100K',
 PRIM_FILE='./archive_libs/logical/q_res/chips/chips.prt';

PART_NAME
 R4170 'Q_RES_0402LF-33.2,1%,1/16W,CHIP,CS03322FB03':;

SECTION_NUMBER 1
 '@T6G_MB_LIB.T6G(SCH_1):PAGE80_I220@PURE_QUANTA.Q_RES(CHIPS)':
 C_PATH='@t6g_mb_lib.t6g(sch_1):page80_i220@pure_quanta.q_res(chips)',
 P_PATH='@t6g_mb_lib.t6g(sch_1):page81_i220@pure_quanta.q_res(chips)',
 PATH='I220',
 DRAWING='@T6G_MB_LIB.T6G(SCH_1):PAGE80',
 WATTAGE='1/16W',
 TOLERANCE='1%',
 MATERIAL='CHIP',
 PHYS_PAGE='81',
 XY='(-2300,2975)',
 ROT='0',
 VER='1',
 PACK_TYPE='0402LF',
 LOCATION='R4170',
 CDS_LIB='pure_quanta',
 CDS_PART_NAME='Q_RES_0402LF-33.2,1%,1/16W,CHIP,CS03322FB03',
 PART_NUMBER='CS03322FB03',
 VALUE='33.2',
 PRIM_FILE='./archive_libs/logical/q_res/chips/chips.prt';

PART_NAME
 R4171 'Q_RES_0402LF-33.2,1%,1/16W,CHIP,CS03322FB03':;

SECTION_NUMBER 1
 '@T6G_MB_LIB.T6G(SCH_1):PAGE80_I223@PURE_QUANTA.Q_RES(CHIPS)':
 C_PATH='@t6g_mb_lib.t6g(sch_1):page80_i223@pure_quanta.q_res(chips)',
 P_PATH='@t6g_mb_lib.t6g(sch_1):page81_i223@pure_quanta.q_res(chips)',
 PATH='I223',
 DRAWING='@T6G_MB_LIB.T6G(SCH_1):PAGE80',
 WATTAGE='1/16W',
 TOLERANCE='1%',
 MATERIAL='CHIP',
 PHYS_PAGE='81',
 XY='(-2300,2925)',
 ROT='0',
 VER='1',
 PACK_TYPE='0402LF',
 LOCATION='R4171',
 CDS_LIB='pure_quanta',
 CDS_PART_NAME='Q_RES_0402LF-33.2,1%,1/16W,CHIP,CS03322FB03',
 PART_NUMBER='CS03322FB03',
 VALUE='33.2',
 PRIM_FILE='./archive_libs/logical/q_res/chips/chips.prt';

PART_NAME
 R4172 'Q_RES_0402LF-33.2,1%,1/16W,CHIP,CS03322FB03':;

SECTION_NUMBER 1
 '@T6G_MB_LIB.T6G(SCH_1):PAGE80_I224@PURE_QUANTA.Q_RES(CHIPS)':
 C_PATH='@t6g_mb_lib.t6g(sch_1):page80_i224@pure_quanta.q_res(chips)',
 P_PATH='@t6g_mb_lib.t6g(sch_1):page81_i224@pure_quanta.q_res(chips)',
 PATH='I224',
 DRAWING='@T6G_MB_LIB.T6G(SCH_1):PAGE80',
 WATTAGE='1/16W',
 TOLERANCE='1%',
 MATERIAL='CHIP',
 PHYS_PAGE='81',
 XY='(-2300,2875)',
 ROT='0',
 VER='1',
 PACK_TYPE='0402LF',
 LOCATION='R4172',
 CDS_LIB='pure_quanta',
 CDS_PART_NAME='Q_RES_0402LF-33.2,1%,1/16W,CHIP,CS03322FB03',
 PART_NUMBER='CS03322FB03',
 VALUE='33.2',
 PRIM_FILE='./archive_libs/logical/q_res/chips/chips.prt';

PART_NAME
 R4173 'Q_RES_0402LF-100K,1%,1/16W,EMPTY,CS41002FB09':;

SECTION_NUMBER 1
 '@T6G_MB_LIB.T6G(SCH_1):PAGE256_I204@PURE_QUANTA.Q_RES(CHIPS)':
 C_PATH='@t6g_mb_lib.t6g(sch_1):page256_i204@pure_quanta.q_res(chips)',
 P_PATH='@t6g_mb_lib.t6g(sch_1):page130_i204@pure_quanta.q_res(chips)',
 PATH='I204',
 DRAWING='@T6G_MB_LIB.T6G(SCH_1):PAGE256',
 WATTAGE='1/16W',
 TOLERANCE='1%',
 MATERIAL='EMPTY',
 PHYS_PAGE='130',
 XY='(2950,-1625)',
 ROT='0',
 VER='2',
 PACK_TYPE='0402LF',
 LOCATION='R4173',
 CDS_LIB='pure_quanta',
 CDS_PART_NAME='Q_RES_0402LF-100K,1%,1/16W,EMPTY,CS41002FB09',
 PART_NUMBER='CS41002FB09',
 VALUE='100K',
 PRIM_FILE='./archive_libs/logical/q_res/chips/chips.prt';

PART_NAME
 R4178 'Q_RES_0402LF-33.2,1%,1/16W,CHIP,CS03322FB03':;

SECTION_NUMBER 1
 '@T6G_MB_LIB.T6G(SCH_1):PAGE359_I114@PURE_QUANTA.Q_RES(CHIPS)':
 C_PATH='@t6g_mb_lib.t6g(sch_1):page359_i114@pure_quanta.q_res(chips)',
 P_PATH='@t6g_mb_lib.t6g(sch_1):page235_i114@pure_quanta.q_res(chips)',
 PATH='I114',
 DRAWING='@T6G_MB_LIB.T6G(SCH_1):PAGE359',
 WATTAGE='1/16W',
 TOLERANCE='1%',
 MATERIAL='CHIP',
 PHYS_PAGE='235',
 XY='(275,-1500)',
 ROT='0',
 VER='1',
 PACK_TYPE='0402LF',
 LOCATION='R4178',
 CDS_LIB='pure_quanta',
 CDS_PART_NAME='Q_RES_0402LF-33.2,1%,1/16W,CHIP,CS03322FB03',
 PART_NUMBER='CS03322FB03',
 VALUE='33.2',
 PRIM_FILE='./archive_libs/logical/q_res/chips/chips.prt';

PART_NAME
 R4179 'Q_RES_0402LF-33.2,1%,1/16W,CHIP,CS03322FB03':;

SECTION_NUMBER 1
 '@T6G_MB_LIB.T6G(SCH_1):PAGE359_I109@PURE_QUANTA.Q_RES(CHIPS)':
 C_PATH='@t6g_mb_lib.t6g(sch_1):page359_i109@pure_quanta.q_res(chips)',
 P_PATH='@t6g_mb_lib.t6g(sch_1):page235_i109@pure_quanta.q_res(chips)',
 PATH='I109',
 DRAWING='@T6G_MB_LIB.T6G(SCH_1):PAGE359',
 WATTAGE='1/16W',
 TOLERANCE='1%',
 MATERIAL='CHIP',
 PHYS_PAGE='235',
 XY='(300,-25)',
 ROT='0',
 VER='1',
 PACK_TYPE='0402LF',
 LOCATION='R4179',
 CDS_LIB='pure_quanta',
 CDS_PART_NAME='Q_RES_0402LF-33.2,1%,1/16W,CHIP,CS03322FB03',
 PART_NUMBER='CS03322FB03',
 VALUE='33.2',
 PRIM_FILE='./archive_libs/logical/q_res/chips/chips.prt';

PART_NAME
 R4180 'Q_RES_0402LF-33.2,1%,1/16W,CHIP,CS03322FB03':;

SECTION_NUMBER 1
 '@T6G_MB_LIB.T6G(SCH_1):PAGE359_I77@PURE_QUANTA.Q_RES(CHIPS)':
 C_PATH='@t6g_mb_lib.t6g(sch_1):page359_i77@pure_quanta.q_res(chips)',
 P_PATH='@t6g_mb_lib.t6g(sch_1):page235_i77@pure_quanta.q_res(chips)',
 PATH='I77',
 DRAWING='@T6G_MB_LIB.T6G(SCH_1):PAGE359',
 WATTAGE='1/16W',
 TOLERANCE='1%',
 MATERIAL='CHIP',
 PHYS_PAGE='235',
 XY='(350,1450)',
 ROT='0',
 VER='1',
 PACK_TYPE='0402LF',
 LOCATION='R4180',
 CDS_LIB='pure_quanta',
 CDS_PART_NAME='Q_RES_0402LF-33.2,1%,1/16W,CHIP,CS03322FB03',
 PART_NUMBER='CS03322FB03',
 VALUE='33.2',
 PRIM_FILE='./archive_libs/logical/q_res/chips/chips.prt';

PART_NAME
 R4181 'Q_RES_0402LF-33.2,1%,1/16W,CHIP,CS03322FB03':;

SECTION_NUMBER 1
 '@T6G_MB_LIB.T6G(SCH_1):PAGE359_I116@PURE_QUANTA.Q_RES(CHIPS)':
 C_PATH='@t6g_mb_lib.t6g(sch_1):page359_i116@pure_quanta.q_res(chips)',
 P_PATH='@t6g_mb_lib.t6g(sch_1):page235_i116@pure_quanta.q_res(chips)',
 PATH='I116',
 DRAWING='@T6G_MB_LIB.T6G(SCH_1):PAGE359',
 WATTAGE='1/16W',
 TOLERANCE='1%',
 MATERIAL='CHIP',
 PHYS_PAGE='235',
 XY='(275,-1350)',
 ROT='0',
 VER='1',
 PACK_TYPE='0402LF',
 LOCATION='R4181',
 CDS_LIB='pure_quanta',
 CDS_PART_NAME='Q_RES_0402LF-33.2,1%,1/16W,CHIP,CS03322FB03',
 PART_NUMBER='CS03322FB03',
 VALUE='33.2',
 PRIM_FILE='./archive_libs/logical/q_res/chips/chips.prt';

PART_NAME
 R4182 'Q_RES_0402LF-33.2,1%,1/16W,CHIP,CS03322FB03':;

SECTION_NUMBER 1
 '@T6G_MB_LIB.T6G(SCH_1):PAGE359_I107@PURE_QUANTA.Q_RES(CHIPS)':
 C_PATH='@t6g_mb_lib.t6g(sch_1):page359_i107@pure_quanta.q_res(chips)',
 P_PATH='@t6g_mb_lib.t6g(sch_1):page235_i107@pure_quanta.q_res(chips)',
 PATH='I107',
 DRAWING='@T6G_MB_LIB.T6G(SCH_1):PAGE359',
 WATTAGE='1/16W',
 TOLERANCE='1%',
 MATERIAL='CHIP',
 PHYS_PAGE='235',
 XY='(300,125)',
 ROT='0',
 VER='1',
 PACK_TYPE='0402LF',
 LOCATION='R4182',
 CDS_LIB='pure_quanta',
 CDS_PART_NAME='Q_RES_0402LF-33.2,1%,1/16W,CHIP,CS03322FB03',
 PART_NUMBER='CS03322FB03',
 VALUE='33.2',
 PRIM_FILE='./archive_libs/logical/q_res/chips/chips.prt';

PART_NAME
 R4183 'Q_RES_0402LF-33.2,1%,1/16W,CHIP,CS03322FB03':;

SECTION_NUMBER 1
 '@T6G_MB_LIB.T6G(SCH_1):PAGE359_I78@PURE_QUANTA.Q_RES(CHIPS)':
 C_PATH='@t6g_mb_lib.t6g(sch_1):page359_i78@pure_quanta.q_res(chips)',
 P_PATH='@t6g_mb_lib.t6g(sch_1):page235_i78@pure_quanta.q_res(chips)',
 PATH='I78',
 DRAWING='@T6G_MB_LIB.T6G(SCH_1):PAGE359',
 WATTAGE='1/16W',
 TOLERANCE='1%',
 MATERIAL='CHIP',
 PHYS_PAGE='235',
 XY='(350,1600)',
 ROT='0',
 VER='1',
 PACK_TYPE='0402LF',
 LOCATION='R4183',
 CDS_LIB='pure_quanta',
 CDS_PART_NAME='Q_RES_0402LF-33.2,1%,1/16W,CHIP,CS03322FB03',
 PART_NUMBER='CS03322FB03',
 VALUE='33.2',
 PRIM_FILE='./archive_libs/logical/q_res/chips/chips.prt';

PART_NAME
 R4184 'Q_RES_0402LF-1K,1%,1/16W,EMPTY,CS21002FB06':;

SECTION_NUMBER 1
 '@T6G_MB_LIB.T6G(SCH_1):PAGE359_I142@PURE_QUANTA.Q_RES(CHIPS)':
 C_PATH='@t6g_mb_lib.t6g(sch_1):page359_i142@pure_quanta.q_res(chips)',
 P_PATH='@t6g_mb_lib.t6g(sch_1):page235_i142@pure_quanta.q_res(chips)',
 PATH='I142',
 DRAWING='@T6G_MB_LIB.T6G(SCH_1):PAGE359',
 WATTAGE='1/16W',
 TOLERANCE='1%',
 MATERIAL='EMPTY',
 PHYS_PAGE='235',
 XY='(3825,-2825)',
 ROT='0',
 VER='2',
 PACK_TYPE='0402LF',
 LOCATION='R4184',
 CDS_LIB='pure_quanta',
 CDS_PART_NAME='Q_RES_0402LF-1K,1%,1/16W,EMPTY,CS21002FB06',
 PART_NUMBER='CS21002FB06',
 VALUE='1K',
 PRIM_FILE='./archive_libs/logical/q_res/chips/chips.prt';

PART_NAME
 R4185 'Q_RES_0402LF-1K,1%,1/16W,CHIP,CS21002FB06':;

SECTION_NUMBER 1
 '@T6G_MB_LIB.T6G(SCH_1):PAGE359_I141@PURE_QUANTA.Q_RES(CHIPS)':
 C_PATH='@t6g_mb_lib.t6g(sch_1):page359_i141@pure_quanta.q_res(chips)',
 P_PATH='@t6g_mb_lib.t6g(sch_1):page235_i141@pure_quanta.q_res(chips)',
 PATH='I141',
 DRAWING='@T6G_MB_LIB.T6G(SCH_1):PAGE359',
 WATTAGE='1/16W',
 TOLERANCE='1%',
 MATERIAL='CHIP',
 PHYS_PAGE='235',
 XY='(3825,-3425)',
 ROT='0',
 VER='2',
 PACK_TYPE='0402LF',
 LOCATION='R4185',
 CDS_LIB='pure_quanta',
 CDS_PART_NAME='Q_RES_0402LF-1K,1%,1/16W,CHIP,CS21002FB06',
 PART_NUMBER='CS21002FB06',
 VALUE='1K',
 PRIM_FILE='./archive_libs/logical/q_res/chips/chips.prt';

PART_NAME
 R4186 'Q_RES_0402LF-1K,1%,1/16W,EMPTY,CS21002FB06':;

SECTION_NUMBER 1
 '@T6G_MB_LIB.T6G(SCH_1):PAGE359_I122@PURE_QUANTA.Q_RES(CHIPS)':
 C_PATH='@t6g_mb_lib.t6g(sch_1):page359_i122@pure_quanta.q_res(chips)',
 P_PATH='@t6g_mb_lib.t6g(sch_1):page235_i122@pure_quanta.q_res(chips)',
 PATH='I122',
 DRAWING='@T6G_MB_LIB.T6G(SCH_1):PAGE359',
 WATTAGE='1/16W',
 TOLERANCE='1%',
 MATERIAL='EMPTY',
 PHYS_PAGE='235',
 XY='(3875,-1350)',
 ROT='0',
 VER='2',
 PACK_TYPE='0402LF',
 LOCATION='R4186',
 CDS_LIB='pure_quanta',
 CDS_PART_NAME='Q_RES_0402LF-1K,1%,1/16W,EMPTY,CS21002FB06',
 PART_NUMBER='CS21002FB06',
 VALUE='1K',
 PRIM_FILE='./archive_libs/logical/q_res/chips/chips.prt';

PART_NAME
 R4187 'Q_RES_0402LF-1K,1%,1/16W,CHIP,CS21002FB06':;

SECTION_NUMBER 1
 '@T6G_MB_LIB.T6G(SCH_1):PAGE359_I121@PURE_QUANTA.Q_RES(CHIPS)':
 C_PATH='@t6g_mb_lib.t6g(sch_1):page359_i121@pure_quanta.q_res(chips)',
 P_PATH='@t6g_mb_lib.t6g(sch_1):page235_i121@pure_quanta.q_res(chips)',
 PATH='I121',
 DRAWING='@T6G_MB_LIB.T6G(SCH_1):PAGE359',
 WATTAGE='1/16W',
 TOLERANCE='1%',
 MATERIAL='CHIP',
 PHYS_PAGE='235',
 XY='(3875,-1950)',
 ROT='0',
 VER='2',
 PACK_TYPE='0402LF',
 LOCATION='R4187',
 CDS_LIB='pure_quanta',
 CDS_PART_NAME='Q_RES_0402LF-1K,1%,1/16W,CHIP,CS21002FB06',
 PART_NUMBER='CS21002FB06',
 VALUE='1K',
 PRIM_FILE='./archive_libs/logical/q_res/chips/chips.prt';

PART_NAME
 R4188 'Q_RES_0402LF-1K,1%,1/16W,EMPTY,CS21002FB06':;

SECTION_NUMBER 1
 '@T6G_MB_LIB.T6G(SCH_1):PAGE359_I101@PURE_QUANTA.Q_RES(CHIPS)':
 C_PATH='@t6g_mb_lib.t6g(sch_1):page359_i101@pure_quanta.q_res(chips)',
 P_PATH='@t6g_mb_lib.t6g(sch_1):page235_i101@pure_quanta.q_res(chips)',
 PATH='I101',
 DRAWING='@T6G_MB_LIB.T6G(SCH_1):PAGE359',
 WATTAGE='1/16W',
 TOLERANCE='1%',
 MATERIAL='EMPTY',
 PHYS_PAGE='235',
 XY='(3900,125)',
 ROT='0',
 VER='2',
 PACK_TYPE='0402LF',
 LOCATION='R4188',
 CDS_LIB='pure_quanta',
 CDS_PART_NAME='Q_RES_0402LF-1K,1%,1/16W,EMPTY,CS21002FB06',
 PART_NUMBER='CS21002FB06',
 VALUE='1K',
 PRIM_FILE='./archive_libs/logical/q_res/chips/chips.prt';

PART_NAME
 R4189 'Q_RES_0402LF-1K,1%,1/16W,CHIP,CS21002FB06':;

SECTION_NUMBER 1
 '@T6G_MB_LIB.T6G(SCH_1):PAGE359_I102@PURE_QUANTA.Q_RES(CHIPS)':
 C_PATH='@t6g_mb_lib.t6g(sch_1):page359_i102@pure_quanta.q_res(chips)',
 P_PATH='@t6g_mb_lib.t6g(sch_1):page235_i102@pure_quanta.q_res(chips)',
 PATH='I102',
 DRAWING='@T6G_MB_LIB.T6G(SCH_1):PAGE359',
 WATTAGE='1/16W',
 TOLERANCE='1%',
 MATERIAL='CHIP',
 PHYS_PAGE='235',
 XY='(3900,-475)',
 ROT='0',
 VER='2',
 PACK_TYPE='0402LF',
 LOCATION='R4189',
 CDS_LIB='pure_quanta',
 CDS_PART_NAME='Q_RES_0402LF-1K,1%,1/16W,CHIP,CS21002FB06',
 PART_NUMBER='CS21002FB06',
 VALUE='1K',
 PRIM_FILE='./archive_libs/logical/q_res/chips/chips.prt';

PART_NAME
 R4190 'Q_RES_0402LF-1K,1%,1/16W,EMPTY,CS21002FB06':;

SECTION_NUMBER 1
 '@T6G_MB_LIB.T6G(SCH_1):PAGE359_I91@PURE_QUANTA.Q_RES(CHIPS)':
 C_PATH='@t6g_mb_lib.t6g(sch_1):page359_i91@pure_quanta.q_res(chips)',
 P_PATH='@t6g_mb_lib.t6g(sch_1):page235_i91@pure_quanta.q_res(chips)',
 PATH='I91',
 DRAWING='@T6G_MB_LIB.T6G(SCH_1):PAGE359',
 WATTAGE='1/16W',
 TOLERANCE='1%',
 MATERIAL='EMPTY',
 PHYS_PAGE='235',
 XY='(3950,1600)',
 ROT='0',
 VER='2',
 PACK_TYPE='0402LF',
 LOCATION='R4190',
 CDS_LIB='pure_quanta',
 CDS_PART_NAME='Q_RES_0402LF-1K,1%,1/16W,EMPTY,CS21002FB06',
 PART_NUMBER='CS21002FB06',
 VALUE='1K',
 PRIM_FILE='./archive_libs/logical/q_res/chips/chips.prt';

PART_NAME
 R4191 'Q_RES_0402LF-1K,1%,1/16W,CHIP,CS21002FB06':;

SECTION_NUMBER 1
 '@T6G_MB_LIB.T6G(SCH_1):PAGE359_I89@PURE_QUANTA.Q_RES(CHIPS)':
 C_PATH='@t6g_mb_lib.t6g(sch_1):page359_i89@pure_quanta.q_res(chips)',
 P_PATH='@t6g_mb_lib.t6g(sch_1):page235_i89@pure_quanta.q_res(chips)',
 PATH='I89',
 DRAWING='@T6G_MB_LIB.T6G(SCH_1):PAGE359',
 WATTAGE='1/16W',
 TOLERANCE='1%',
 MATERIAL='CHIP',
 PHYS_PAGE='235',
 XY='(3950,1000)',
 ROT='0',
 VER='2',
 PACK_TYPE='0402LF',
 LOCATION='R4191',
 CDS_LIB='pure_quanta',
 CDS_PART_NAME='Q_RES_0402LF-1K,1%,1/16W,CHIP,CS21002FB06',
 PART_NUMBER='CS21002FB06',
 VALUE='1K',
 PRIM_FILE='./archive_libs/logical/q_res/chips/chips.prt';

PART_NAME
 R4192 'Q_RES_0402LF-1K,1%,1/16W,EMPTY,CS21002FB06':;

SECTION_NUMBER 1
 '@T6G_MB_LIB.T6G(SCH_1):PAGE359_I148@PURE_QUANTA.Q_RES(CHIPS)':
 C_PATH='@t6g_mb_lib.t6g(sch_1):page359_i148@pure_quanta.q_res(chips)',
 P_PATH='@t6g_mb_lib.t6g(sch_1):page235_i148@pure_quanta.q_res(chips)',
 PATH='I148',
 DRAWING='@T6G_MB_LIB.T6G(SCH_1):PAGE359',
 WATTAGE='1/16W',
 TOLERANCE='1%',
 MATERIAL='EMPTY',
 PHYS_PAGE='235',
 XY='(4075,-2825)',
 ROT='0',
 VER='2',
 PACK_TYPE='0402LF',
 LOCATION='R4192',
 CDS_LIB='pure_quanta',
 CDS_PART_NAME='Q_RES_0402LF-1K,1%,1/16W,EMPTY,CS21002FB06',
 PART_NUMBER='CS21002FB06',
 VALUE='1K',
 PRIM_FILE='./archive_libs/logical/q_res/chips/chips.prt';

PART_NAME
 R4193 'Q_RES_0402LF-1K,1%,1/16W,CHIP,CS21002FB06':;

SECTION_NUMBER 1
 '@T6G_MB_LIB.T6G(SCH_1):PAGE359_I145@PURE_QUANTA.Q_RES(CHIPS)':
 C_PATH='@t6g_mb_lib.t6g(sch_1):page359_i145@pure_quanta.q_res(chips)',
 P_PATH='@t6g_mb_lib.t6g(sch_1):page235_i145@pure_quanta.q_res(chips)',
 PATH='I145',
 DRAWING='@T6G_MB_LIB.T6G(SCH_1):PAGE359',
 WATTAGE='1/16W',
 TOLERANCE='1%',
 MATERIAL='CHIP',
 PHYS_PAGE='235',
 XY='(4075,-3425)',
 ROT='0',
 VER='2',
 PACK_TYPE='0402LF',
 LOCATION='R4193',
 CDS_LIB='pure_quanta',
 CDS_PART_NAME='Q_RES_0402LF-1K,1%,1/16W,CHIP,CS21002FB06',
 PART_NUMBER='CS21002FB06',
 VALUE='1K',
 PRIM_FILE='./archive_libs/logical/q_res/chips/chips.prt';

PART_NAME
 R4194 'Q_RES_0402LF-1K,1%,1/16W,EMPTY,CS21002FB06':;

SECTION_NUMBER 1
 '@T6G_MB_LIB.T6G(SCH_1):PAGE359_I128@PURE_QUANTA.Q_RES(CHIPS)':
 C_PATH='@t6g_mb_lib.t6g(sch_1):page359_i128@pure_quanta.q_res(chips)',
 P_PATH='@t6g_mb_lib.t6g(sch_1):page235_i128@pure_quanta.q_res(chips)',
 PATH='I128',
 DRAWING='@T6G_MB_LIB.T6G(SCH_1):PAGE359',
 WATTAGE='1/16W',
 TOLERANCE='1%',
 MATERIAL='EMPTY',
 PHYS_PAGE='235',
 XY='(4125,-1350)',
 ROT='0',
 VER='2',
 PACK_TYPE='0402LF',
 LOCATION='R4194',
 CDS_LIB='pure_quanta',
 CDS_PART_NAME='Q_RES_0402LF-1K,1%,1/16W,EMPTY,CS21002FB06',
 PART_NUMBER='CS21002FB06',
 VALUE='1K',
 PRIM_FILE='./archive_libs/logical/q_res/chips/chips.prt';

PART_NAME
 R4195 'Q_RES_0402LF-1K,1%,1/16W,CHIP,CS21002FB06':;

SECTION_NUMBER 1
 '@T6G_MB_LIB.T6G(SCH_1):PAGE359_I125@PURE_QUANTA.Q_RES(CHIPS)':
 C_PATH='@t6g_mb_lib.t6g(sch_1):page359_i125@pure_quanta.q_res(chips)',
 P_PATH='@t6g_mb_lib.t6g(sch_1):page235_i125@pure_quanta.q_res(chips)',
 PATH='I125',
 DRAWING='@T6G_MB_LIB.T6G(SCH_1):PAGE359',
 WATTAGE='1/16W',
 TOLERANCE='1%',
 MATERIAL='CHIP',
 PHYS_PAGE='235',
 XY='(4125,-1950)',
 ROT='0',
 VER='2',
 PACK_TYPE='0402LF',
 LOCATION='R4195',
 CDS_LIB='pure_quanta',
 CDS_PART_NAME='Q_RES_0402LF-1K,1%,1/16W,CHIP,CS21002FB06',
 PART_NUMBER='CS21002FB06',
 VALUE='1K',
 PRIM_FILE='./archive_libs/logical/q_res/chips/chips.prt';

PART_NAME
 R4196 'Q_RES_0402LF-1K,1%,1/16W,EMPTY,CS21002FB06':;

SECTION_NUMBER 1
 '@T6G_MB_LIB.T6G(SCH_1):PAGE359_I95@PURE_QUANTA.Q_RES(CHIPS)':
 C_PATH='@t6g_mb_lib.t6g(sch_1):page359_i95@pure_quanta.q_res(chips)',
 P_PATH='@t6g_mb_lib.t6g(sch_1):page235_i95@pure_quanta.q_res(chips)',
 PATH='I95',
 DRAWING='@T6G_MB_LIB.T6G(SCH_1):PAGE359',
 WATTAGE='1/16W',
 TOLERANCE='1%',
 MATERIAL='EMPTY',
 PHYS_PAGE='235',
 XY='(4150,125)',
 ROT='0',
 VER='2',
 PACK_TYPE='0402LF',
 LOCATION='R4196',
 CDS_LIB='pure_quanta',
 CDS_PART_NAME='Q_RES_0402LF-1K,1%,1/16W,EMPTY,CS21002FB06',
 PART_NUMBER='CS21002FB06',
 VALUE='1K',
 PRIM_FILE='./archive_libs/logical/q_res/chips/chips.prt';

PART_NAME
 R4197 'Q_RES_0402LF-1K,1%,1/16W,CHIP,CS21002FB06':;

SECTION_NUMBER 1
 '@T6G_MB_LIB.T6G(SCH_1):PAGE359_I98@PURE_QUANTA.Q_RES(CHIPS)':
 C_PATH='@t6g_mb_lib.t6g(sch_1):page359_i98@pure_quanta.q_res(chips)',
 P_PATH='@t6g_mb_lib.t6g(sch_1):page235_i98@pure_quanta.q_res(chips)',
 PATH='I98',
 DRAWING='@T6G_MB_LIB.T6G(SCH_1):PAGE359',
 WATTAGE='1/16W',
 TOLERANCE='1%',
 MATERIAL='CHIP',
 PHYS_PAGE='235',
 XY='(4150,-475)',
 ROT='0',
 VER='2',
 PACK_TYPE='0402LF',
 LOCATION='R4197',
 CDS_LIB='pure_quanta',
 CDS_PART_NAME='Q_RES_0402LF-1K,1%,1/16W,CHIP,CS21002FB06',
 PART_NUMBER='CS21002FB06',
 VALUE='1K',
 PRIM_FILE='./archive_libs/logical/q_res/chips/chips.prt';

PART_NAME
 R4198 'Q_RES_0402LF-1K,1%,1/16W,EMPTY,CS21002FB06':;

SECTION_NUMBER 1
 '@T6G_MB_LIB.T6G(SCH_1):PAGE359_I82@PURE_QUANTA.Q_RES(CHIPS)':
 C_PATH='@t6g_mb_lib.t6g(sch_1):page359_i82@pure_quanta.q_res(chips)',
 P_PATH='@t6g_mb_lib.t6g(sch_1):page235_i82@pure_quanta.q_res(chips)',
 PATH='I82',
 DRAWING='@T6G_MB_LIB.T6G(SCH_1):PAGE359',
 WATTAGE='1/16W',
 TOLERANCE='1%',
 MATERIAL='EMPTY',
 PHYS_PAGE='235',
 XY='(4200,1600)',
 ROT='0',
 VER='2',
 PACK_TYPE='0402LF',
 LOCATION='R4198',
 CDS_LIB='pure_quanta',
 CDS_PART_NAME='Q_RES_0402LF-1K,1%,1/16W,EMPTY,CS21002FB06',
 PART_NUMBER='CS21002FB06',
 VALUE='1K',
 PRIM_FILE='./archive_libs/logical/q_res/chips/chips.prt';

PART_NAME
 R4199 'Q_RES_0402LF-1K,1%,1/16W,CHIP,CS21002FB06':;

SECTION_NUMBER 1
 '@T6G_MB_LIB.T6G(SCH_1):PAGE359_I81@PURE_QUANTA.Q_RES(CHIPS)':
 C_PATH='@t6g_mb_lib.t6g(sch_1):page359_i81@pure_quanta.q_res(chips)',
 P_PATH='@t6g_mb_lib.t6g(sch_1):page235_i81@pure_quanta.q_res(chips)',
 PATH='I81',
 DRAWING='@T6G_MB_LIB.T6G(SCH_1):PAGE359',
 WATTAGE='1/16W',
 TOLERANCE='1%',
 MATERIAL='CHIP',
 PHYS_PAGE='235',
 XY='(4200,1000)',
 ROT='0',
 VER='2',
 PACK_TYPE='0402LF',
 LOCATION='R4199',
 CDS_LIB='pure_quanta',
 CDS_PART_NAME='Q_RES_0402LF-1K,1%,1/16W,CHIP,CS21002FB06',
 PART_NUMBER='CS21002FB06',
 VALUE='1K',
 PRIM_FILE='./archive_libs/logical/q_res/chips/chips.prt';

PART_NAME
 R4200 'Q_RES_0402LF-1K,1%,1/16W,EMPTY,CS21002FB06':;

SECTION_NUMBER 1
 '@T6G_MB_LIB.T6G(SCH_1):PAGE359_I149@PURE_QUANTA.Q_RES(CHIPS)':
 C_PATH='@t6g_mb_lib.t6g(sch_1):page359_i149@pure_quanta.q_res(chips)',
 P_PATH='@t6g_mb_lib.t6g(sch_1):page235_i149@pure_quanta.q_res(chips)',
 PATH='I149',
 DRAWING='@T6G_MB_LIB.T6G(SCH_1):PAGE359',
 WATTAGE='1/16W',
 TOLERANCE='1%',
 MATERIAL='EMPTY',
 PHYS_PAGE='235',
 XY='(4325,-2825)',
 ROT='0',
 VER='2',
 PACK_TYPE='0402LF',
 LOCATION='R4200',
 CDS_LIB='pure_quanta',
 CDS_PART_NAME='Q_RES_0402LF-1K,1%,1/16W,EMPTY,CS21002FB06',
 PART_NUMBER='CS21002FB06',
 VALUE='1K',
 PRIM_FILE='./archive_libs/logical/q_res/chips/chips.prt';

PART_NAME
 R4201 'Q_RES_0402LF-1K,1%,1/16W,CHIP,CS21002FB06':;

SECTION_NUMBER 1
 '@T6G_MB_LIB.T6G(SCH_1):PAGE359_I147@PURE_QUANTA.Q_RES(CHIPS)':
 C_PATH='@t6g_mb_lib.t6g(sch_1):page359_i147@pure_quanta.q_res(chips)',
 P_PATH='@t6g_mb_lib.t6g(sch_1):page235_i147@pure_quanta.q_res(chips)',
 PATH='I147',
 DRAWING='@T6G_MB_LIB.T6G(SCH_1):PAGE359',
 WATTAGE='1/16W',
 TOLERANCE='1%',
 MATERIAL='CHIP',
 PHYS_PAGE='235',
 XY='(4325,-3425)',
 ROT='0',
 VER='2',
 PACK_TYPE='0402LF',
 LOCATION='R4201',
 CDS_LIB='pure_quanta',
 CDS_PART_NAME='Q_RES_0402LF-1K,1%,1/16W,CHIP,CS21002FB06',
 PART_NUMBER='CS21002FB06',
 VALUE='1K',
 PRIM_FILE='./archive_libs/logical/q_res/chips/chips.prt';

PART_NAME
 R4202 'Q_RES_0402LF-1K,1%,1/16W,EMPTY,CS21002FB06':;

SECTION_NUMBER 1
 '@T6G_MB_LIB.T6G(SCH_1):PAGE359_I129@PURE_QUANTA.Q_RES(CHIPS)':
 C_PATH='@t6g_mb_lib.t6g(sch_1):page359_i129@pure_quanta.q_res(chips)',
 P_PATH='@t6g_mb_lib.t6g(sch_1):page235_i129@pure_quanta.q_res(chips)',
 PATH='I129',
 DRAWING='@T6G_MB_LIB.T6G(SCH_1):PAGE359',
 WATTAGE='1/16W',
 TOLERANCE='1%',
 MATERIAL='EMPTY',
 PHYS_PAGE='235',
 XY='(4375,-1350)',
 ROT='0',
 VER='2',
 PACK_TYPE='0402LF',
 LOCATION='R4202',
 CDS_LIB='pure_quanta',
 CDS_PART_NAME='Q_RES_0402LF-1K,1%,1/16W,EMPTY,CS21002FB06',
 PART_NUMBER='CS21002FB06',
 VALUE='1K',
 PRIM_FILE='./archive_libs/logical/q_res/chips/chips.prt';

PART_NAME
 R4203 'Q_RES_0402LF-1K,1%,1/16W,CHIP,CS21002FB06':;

SECTION_NUMBER 1
 '@T6G_MB_LIB.T6G(SCH_1):PAGE359_I127@PURE_QUANTA.Q_RES(CHIPS)':
 C_PATH='@t6g_mb_lib.t6g(sch_1):page359_i127@pure_quanta.q_res(chips)',
 P_PATH='@t6g_mb_lib.t6g(sch_1):page235_i127@pure_quanta.q_res(chips)',
 PATH='I127',
 DRAWING='@T6G_MB_LIB.T6G(SCH_1):PAGE359',
 WATTAGE='1/16W',
 TOLERANCE='1%',
 MATERIAL='CHIP',
 PHYS_PAGE='235',
 XY='(4375,-1950)',
 ROT='0',
 VER='2',
 PACK_TYPE='0402LF',
 LOCATION='R4203',
 CDS_LIB='pure_quanta',
 CDS_PART_NAME='Q_RES_0402LF-1K,1%,1/16W,CHIP,CS21002FB06',
 PART_NUMBER='CS21002FB06',
 VALUE='1K',
 PRIM_FILE='./archive_libs/logical/q_res/chips/chips.prt';

PART_NAME
 R4204 'Q_RES_0402LF-1K,1%,1/16W,EMPTY,CS21002FB06':;

SECTION_NUMBER 1
 '@T6G_MB_LIB.T6G(SCH_1):PAGE359_I94@PURE_QUANTA.Q_RES(CHIPS)':
 C_PATH='@t6g_mb_lib.t6g(sch_1):page359_i94@pure_quanta.q_res(chips)',
 P_PATH='@t6g_mb_lib.t6g(sch_1):page235_i94@pure_quanta.q_res(chips)',
 PATH='I94',
 DRAWING='@T6G_MB_LIB.T6G(SCH_1):PAGE359',
 WATTAGE='1/16W',
 TOLERANCE='1%',
 MATERIAL='EMPTY',
 PHYS_PAGE='235',
 XY='(4400,125)',
 ROT='0',
 VER='2',
 PACK_TYPE='0402LF',
 LOCATION='R4204',
 CDS_LIB='pure_quanta',
 CDS_PART_NAME='Q_RES_0402LF-1K,1%,1/16W,EMPTY,CS21002FB06',
 PART_NUMBER='CS21002FB06',
 VALUE='1K',
 PRIM_FILE='./archive_libs/logical/q_res/chips/chips.prt';

PART_NAME
 R4205 'Q_RES_0402LF-1K,1%,1/16W,CHIP,CS21002FB06':;

SECTION_NUMBER 1
 '@T6G_MB_LIB.T6G(SCH_1):PAGE359_I96@PURE_QUANTA.Q_RES(CHIPS)':
 C_PATH='@t6g_mb_lib.t6g(sch_1):page359_i96@pure_quanta.q_res(chips)',
 P_PATH='@t6g_mb_lib.t6g(sch_1):page235_i96@pure_quanta.q_res(chips)',
 PATH='I96',
 DRAWING='@T6G_MB_LIB.T6G(SCH_1):PAGE359',
 WATTAGE='1/16W',
 TOLERANCE='1%',
 MATERIAL='CHIP',
 PHYS_PAGE='235',
 XY='(4400,-475)',
 ROT='0',
 VER='2',
 PACK_TYPE='0402LF',
 LOCATION='R4205',
 CDS_LIB='pure_quanta',
 CDS_PART_NAME='Q_RES_0402LF-1K,1%,1/16W,CHIP,CS21002FB06',
 PART_NUMBER='CS21002FB06',
 VALUE='1K',
 PRIM_FILE='./archive_libs/logical/q_res/chips/chips.prt';

PART_NAME
 R4206 'Q_RES_0402LF-1K,1%,1/16W,EMPTY,CS21002FB06':;

SECTION_NUMBER 1
 '@T6G_MB_LIB.T6G(SCH_1):PAGE359_I86@PURE_QUANTA.Q_RES(CHIPS)':
 C_PATH='@t6g_mb_lib.t6g(sch_1):page359_i86@pure_quanta.q_res(chips)',
 P_PATH='@t6g_mb_lib.t6g(sch_1):page235_i86@pure_quanta.q_res(chips)',
 PATH='I86',
 DRAWING='@T6G_MB_LIB.T6G(SCH_1):PAGE359',
 WATTAGE='1/16W',
 TOLERANCE='1%',
 MATERIAL='EMPTY',
 PHYS_PAGE='235',
 XY='(4450,1600)',
 ROT='0',
 VER='2',
 PACK_TYPE='0402LF',
 LOCATION='R4206',
 CDS_LIB='pure_quanta',
 CDS_PART_NAME='Q_RES_0402LF-1K,1%,1/16W,EMPTY,CS21002FB06',
 PART_NUMBER='CS21002FB06',
 VALUE='1K',
 PRIM_FILE='./archive_libs/logical/q_res/chips/chips.prt';

PART_NAME
 R4207 'Q_RES_0402LF-1K,1%,1/16W,CHIP,CS21002FB06':;

SECTION_NUMBER 1
 '@T6G_MB_LIB.T6G(SCH_1):PAGE359_I85@PURE_QUANTA.Q_RES(CHIPS)':
 C_PATH='@t6g_mb_lib.t6g(sch_1):page359_i85@pure_quanta.q_res(chips)',
 P_PATH='@t6g_mb_lib.t6g(sch_1):page235_i85@pure_quanta.q_res(chips)',
 PATH='I85',
 DRAWING='@T6G_MB_LIB.T6G(SCH_1):PAGE359',
 WATTAGE='1/16W',
 TOLERANCE='1%',
 MATERIAL='CHIP',
 PHYS_PAGE='235',
 XY='(4450,1000)',
 ROT='0',
 VER='2',
 PACK_TYPE='0402LF',
 LOCATION='R4207',
 CDS_LIB='pure_quanta',
 CDS_PART_NAME='Q_RES_0402LF-1K,1%,1/16W,CHIP,CS21002FB06',
 PART_NUMBER='CS21002FB06',
 VALUE='1K',
 PRIM_FILE='./archive_libs/logical/q_res/chips/chips.prt';

PART_NAME
 R4208 'Q_RES_0402LF-200K,1%,1/16W,EMPTY,CS42002FB05':;

SECTION_NUMBER 1
 '@T6G_MB_LIB.T6G(SCH_1):PAGE359_I171@PURE_QUANTA.Q_RES(CHIPS)':
 C_PATH='@t6g_mb_lib.t6g(sch_1):page359_i171@pure_quanta.q_res(chips)',
 P_PATH='@t6g_mb_lib.t6g(sch_1):page235_i171@pure_quanta.q_res(chips)',
 PATH='I171',
 DRAWING='@T6G_MB_LIB.T6G(SCH_1):PAGE359',
 WATTAGE='1/16W',
 TOLERANCE='1%',
 MATERIAL='EMPTY',
 PHYS_PAGE='235',
 XY='(-350,-2625)',
 ROT='0',
 VER='2',
 PACK_TYPE='0402LF',
 LOCATION='R4208',
 CDS_LIB='pure_quanta',
 CDS_PART_NAME='Q_RES_0402LF-200K,1%,1/16W,EMPTY,CS42002FB05',
 PART_NUMBER='CS42002FB05',
 VALUE='200K',
 PRIM_FILE='./archive_libs/logical/q_res/chips/chips.prt';

PART_NAME
 R4209 'Q_RES_0402LF-200K,1%,1/16W,EMPTY,CS42002FB05':;

SECTION_NUMBER 1
 '@T6G_MB_LIB.T6G(SCH_1):PAGE359_I169@PURE_QUANTA.Q_RES(CHIPS)':
 C_PATH='@t6g_mb_lib.t6g(sch_1):page359_i169@pure_quanta.q_res(chips)',
 P_PATH='@t6g_mb_lib.t6g(sch_1):page235_i169@pure_quanta.q_res(chips)',
 PATH='I169',
 DRAWING='@T6G_MB_LIB.T6G(SCH_1):PAGE359',
 WATTAGE='1/16W',
 TOLERANCE='1%',
 MATERIAL='EMPTY',
 PHYS_PAGE='235',
 XY='(-250,325)',
 ROT='0',
 VER='2',
 PACK_TYPE='0402LF',
 LOCATION='R4209',
 CDS_LIB='pure_quanta',
 CDS_PART_NAME='Q_RES_0402LF-200K,1%,1/16W,EMPTY,CS42002FB05',
 PART_NUMBER='CS42002FB05',
 VALUE='200K',
 PRIM_FILE='./archive_libs/logical/q_res/chips/chips.prt';

PART_NAME
 R4210 'Q_RES_0402LF-200K,1%,1/16W,EMPTY,CS42002FB05':;

SECTION_NUMBER 1
 '@T6G_MB_LIB.T6G(SCH_1):PAGE359_I170@PURE_QUANTA.Q_RES(CHIPS)':
 C_PATH='@t6g_mb_lib.t6g(sch_1):page359_i170@pure_quanta.q_res(chips)',
 P_PATH='@t6g_mb_lib.t6g(sch_1):page235_i170@pure_quanta.q_res(chips)',
 PATH='I170',
 DRAWING='@T6G_MB_LIB.T6G(SCH_1):PAGE359',
 WATTAGE='1/16W',
 TOLERANCE='1%',
 MATERIAL='EMPTY',
 PHYS_PAGE='235',
 XY='(-250,-1175)',
 ROT='0',
 VER='2',
 PACK_TYPE='0402LF',
 LOCATION='R4210',
 CDS_LIB='pure_quanta',
 CDS_PART_NAME='Q_RES_0402LF-200K,1%,1/16W,EMPTY,CS42002FB05',
 PART_NUMBER='CS42002FB05',
 VALUE='200K',
 PRIM_FILE='./archive_libs/logical/q_res/chips/chips.prt';

PART_NAME
 R4211 'Q_RES_0402LF-200K,1%,1/16W,CHIP,CS42002FB05':;

SECTION_NUMBER 1
 '@T6G_MB_LIB.T6G(SCH_1):PAGE359_I168@PURE_QUANTA.Q_RES(CHIPS)':
 C_PATH='@t6g_mb_lib.t6g(sch_1):page359_i168@pure_quanta.q_res(chips)',
 P_PATH='@t6g_mb_lib.t6g(sch_1):page235_i168@pure_quanta.q_res(chips)',
 PATH='I168',
 DRAWING='@T6G_MB_LIB.T6G(SCH_1):PAGE359',
 WATTAGE='1/16W',
 TOLERANCE='1%',
 MATERIAL='CHIP',
 PHYS_PAGE='235',
 XY='(-200,1800)',
 ROT='0',
 VER='2',
 PACK_TYPE='0402LF',
 LOCATION='R4211',
 CDS_LIB='pure_quanta',
 CDS_PART_NAME='Q_RES_0402LF-200K,1%,1/16W,CHIP,CS42002FB05',
 PART_NUMBER='CS42002FB05',
 VALUE='200K',
 PRIM_FILE='./archive_libs/logical/q_res/chips/chips.prt';

PART_NAME
 R4212 'Q_RES_0402LF-0,5%,1/16W,CHIP,CS00002JB13':;

SECTION_NUMBER 1
 '@T6G_MB_LIB.T6G(SCH_1):PAGE359_I135@PURE_QUANTA.Q_RES(CHIPS)':
 C_PATH='@t6g_mb_lib.t6g(sch_1):page359_i135@pure_quanta.q_res(chips)',
 P_PATH='@t6g_mb_lib.t6g(sch_1):page235_i135@pure_quanta.q_res(chips)',
 PATH='I135',
 DRAWING='@T6G_MB_LIB.T6G(SCH_1):PAGE359',
 WATTAGE='1/16W',
 TOLERANCE='5%',
 MATERIAL='CHIP',
 PHYS_PAGE='235',
 XY='(225,-3125)',
 ROT='0',
 VER='1',
 PACK_TYPE='0402LF',
 LOCATION='R4212',
 CDS_LIB='pure_quanta',
 CDS_PART_NAME='Q_RES_0402LF-0,5%,1/16W,CHIP,CS00002JB13',
 PART_NUMBER='CS00002JB13',
 VALUE='0',
 PRIM_FILE='./archive_libs/logical/q_res/chips/chips.prt';

PART_NAME
 R4213 'Q_RES_0402LF-0,5%,1/16W,CHIP,CS00002JB13':;

SECTION_NUMBER 1
 '@T6G_MB_LIB.T6G(SCH_1):PAGE359_I115@PURE_QUANTA.Q_RES(CHIPS)':
 C_PATH='@t6g_mb_lib.t6g(sch_1):page359_i115@pure_quanta.q_res(chips)',
 P_PATH='@t6g_mb_lib.t6g(sch_1):page235_i115@pure_quanta.q_res(chips)',
 PATH='I115',
 DRAWING='@T6G_MB_LIB.T6G(SCH_1):PAGE359',
 WATTAGE='1/16W',
 TOLERANCE='5%',
 MATERIAL='CHIP',
 PHYS_PAGE='235',
 XY='(275,-1650)',
 ROT='0',
 VER='1',
 PACK_TYPE='0402LF',
 LOCATION='R4213',
 CDS_LIB='pure_quanta',
 CDS_PART_NAME='Q_RES_0402LF-0,5%,1/16W,CHIP,CS00002JB13',
 PART_NUMBER='CS00002JB13',
 VALUE='0',
 PRIM_FILE='./archive_libs/logical/q_res/chips/chips.prt';

PART_NAME
 R4214 'Q_RES_0402LF-0,5%,1/16W,CHIP,CS00002JB13':;

SECTION_NUMBER 1
 '@T6G_MB_LIB.T6G(SCH_1):PAGE359_I108@PURE_QUANTA.Q_RES(CHIPS)':
 C_PATH='@t6g_mb_lib.t6g(sch_1):page359_i108@pure_quanta.q_res(chips)',
 P_PATH='@t6g_mb_lib.t6g(sch_1):page235_i108@pure_quanta.q_res(chips)',
 PATH='I108',
 DRAWING='@T6G_MB_LIB.T6G(SCH_1):PAGE359',
 WATTAGE='1/16W',
 TOLERANCE='5%',
 MATERIAL='CHIP',
 PHYS_PAGE='235',
 XY='(300,-175)',
 ROT='0',
 VER='1',
 PACK_TYPE='0402LF',
 LOCATION='R4214',
 CDS_LIB='pure_quanta',
 CDS_PART_NAME='Q_RES_0402LF-0,5%,1/16W,CHIP,CS00002JB13',
 PART_NUMBER='CS00002JB13',
 VALUE='0',
 PRIM_FILE='./archive_libs/logical/q_res/chips/chips.prt';

PART_NAME
 R4215 'Q_RES_0402LF-0,5%,1/16W,CHIP,CS00002JB13':;

SECTION_NUMBER 1
 '@T6G_MB_LIB.T6G(SCH_1):PAGE359_I79@PURE_QUANTA.Q_RES(CHIPS)':
 C_PATH='@t6g_mb_lib.t6g(sch_1):page359_i79@pure_quanta.q_res(chips)',
 P_PATH='@t6g_mb_lib.t6g(sch_1):page235_i79@pure_quanta.q_res(chips)',
 PATH='I79',
 DRAWING='@T6G_MB_LIB.T6G(SCH_1):PAGE359',
 WATTAGE='1/16W',
 TOLERANCE='5%',
 MATERIAL='CHIP',
 PHYS_PAGE='235',
 XY='(350,1300)',
 ROT='0',
 VER='1',
 PACK_TYPE='0402LF',
 LOCATION='R4215',
 CDS_LIB='pure_quanta',
 CDS_PART_NAME='Q_RES_0402LF-0,5%,1/16W,CHIP,CS00002JB13',
 PART_NUMBER='CS00002JB13',
 VALUE='0',
 PRIM_FILE='./archive_libs/logical/q_res/chips/chips.prt';

PART_NAME
 R4264 'Q_RES_0402LF-4.7K,5%,1/16W,CHIP,CS24702JB10':;

SECTION_NUMBER 1
 '@T6G_MB_LIB.T6G(SCH_1):PAGE364_I47@PURE_QUANTA.Q_RES(CHIPS)':
 C_PATH='@t6g_mb_lib.t6g(sch_1):page364_i47@pure_quanta.q_res(chips)',
 P_PATH='@t6g_mb_lib.t6g(sch_1):page241_i47@pure_quanta.q_res(chips)',
 PATH='I47',
 DRAWING='@T6G_MB_LIB.T6G(SCH_1):PAGE364',
 WATTAGE='1/16W',
 TOLERANCE='5%',
 MATERIAL='CHIP',
 PHYS_PAGE='241',
 XY='(2150,525)',
 ROT='0',
 VER='2',
 PACK_TYPE='0402LF',
 LOCATION='R4264',
 CDS_LIB='pure_quanta',
 CDS_PART_NAME='Q_RES_0402LF-4.7K,5%,1/16W,CHIP,CS24702JB10',
 PART_NUMBER='CS24702JB10',
 VALUE='4.7K',
 PRIM_FILE='./archive_libs/logical/q_res/chips/chips.prt';

PART_NAME
 R4265 'Q_RES_0402LF-4.7K,5%,1/16W,EMPTY,CS24702JB10':;

SECTION_NUMBER 1
 '@T6G_MB_LIB.T6G(SCH_1):PAGE364_I43@PURE_QUANTA.Q_RES(CHIPS)':
 C_PATH='@t6g_mb_lib.t6g(sch_1):page364_i43@pure_quanta.q_res(chips)',
 P_PATH='@t6g_mb_lib.t6g(sch_1):page241_i43@pure_quanta.q_res(chips)',
 PATH='I43',
 DRAWING='@T6G_MB_LIB.T6G(SCH_1):PAGE364',
 WATTAGE='1/16W',
 TOLERANCE='5%',
 MATERIAL='EMPTY',
 PHYS_PAGE='241',
 XY='(2175,-25)',
 ROT='0',
 VER='2',
 PACK_TYPE='0402LF',
 LOCATION='R4265',
 CDS_LIB='pure_quanta',
 CDS_PART_NAME='Q_RES_0402LF-4.7K,5%,1/16W,EMPTY,CS24702JB10',
 PART_NUMBER='CS24702JB10',
 VALUE='4.7K',
 PRIM_FILE='./archive_libs/logical/q_res/chips/chips.prt';

PART_NAME
 R4266 'Q_RES_0402LF-33.2,1%,1/16W,CHIP,CS03322FB03':;

SECTION_NUMBER 1
 '@T6G_MB_LIB.T6G(SCH_1):PAGE364_I48@PURE_QUANTA.Q_RES(CHIPS)':
 C_PATH='@t6g_mb_lib.t6g(sch_1):page364_i48@pure_quanta.q_res(chips)',
 P_PATH='@t6g_mb_lib.t6g(sch_1):page241_i48@pure_quanta.q_res(chips)',
 PATH='I48',
 DRAWING='@T6G_MB_LIB.T6G(SCH_1):PAGE364',
 WATTAGE='1/16W',
 TOLERANCE='1%',
 MATERIAL='CHIP',
 PHYS_PAGE='241',
 XY='(2400,275)',
 ROT='0',
 VER='1',
 PACK_TYPE='0402LF',
 LOCATION='R4266',
 CDS_LIB='pure_quanta',
 CDS_PART_NAME='Q_RES_0402LF-33.2,1%,1/16W,CHIP,CS03322FB03',
 PART_NUMBER='CS03322FB03',
 VALUE='33.2',
 PRIM_FILE='./archive_libs/logical/q_res/chips/chips.prt';

PART_NAME
 R4268 'Q_RES_0402LF-0,5%,1/16W,CHIP,CS00002JB13':;

SECTION_NUMBER 1
 '@T6G_MB_LIB.T6G(SCH_1):PAGE364_I41@PURE_QUANTA.Q_RES(CHIPS)':
 C_PATH='@t6g_mb_lib.t6g(sch_1):page364_i41@pure_quanta.q_res(chips)',
 P_PATH='@t6g_mb_lib.t6g(sch_1):page241_i41@pure_quanta.q_res(chips)',
 PATH='I41',
 DRAWING='@T6G_MB_LIB.T6G(SCH_1):PAGE364',
 WATTAGE='1/16W',
 TOLERANCE='5%',
 MATERIAL='CHIP',
 PHYS_PAGE='241',
 XY='(-1125,275)',
 ROT='0',
 VER='1',
 PACK_TYPE='0402LF',
 LOCATION='R4268',
 CDS_LIB='pure_quanta',
 CDS_PART_NAME='Q_RES_0402LF-0,5%,1/16W,CHIP,CS00002JB13',
 PART_NUMBER='CS00002JB13',
 VALUE='0',
 PRIM_FILE='./archive_libs/logical/q_res/chips/chips.prt';

PART_NAME
 R4269 'Q_RES_0402LF-2.2K,5%,1/16W,EMPTY,CS22202JB07':;

SECTION_NUMBER 1
 '@T6G_MB_LIB.T6G(SCH_1):PAGE251_I41@PURE_QUANTA.Q_RES(CHIPS)':
 C_PATH='@t6g_mb_lib.t6g(sch_1):page251_i41@pure_quanta.q_res(chips)',
 P_PATH='@t6g_mb_lib.t6g(sch_1):page252_i41@pure_quanta.q_res(chips)',
 PATH='I41',
 DRAWING='@T6G_MB_LIB.T6G(SCH_1):PAGE251',
 WATTAGE='1/16W',
 TOLERANCE='5%',
 MATERIAL='EMPTY',
 PHYS_PAGE='252',
 XY='(-2550,1325)',
 ROT='0',
 VER='1',
 PACK_TYPE='0402LF',
 LOCATION='R4269',
 CDS_LIB='pure_quanta',
 CDS_PART_NAME='Q_RES_0402LF-2.2K,5%,1/16W,EMPTY,CS22202JB07',
 PART_NUMBER='CS22202JB07',
 VALUE='2.2K',
 PRIM_FILE='./archive_libs/logical/q_res/chips/chips.prt';

PART_NAME
 R4270 'Q_RES_0402LF-2.2K,5%,1/16W,EMPTY,CS22202JB07':;

SECTION_NUMBER 1
 '@T6G_MB_LIB.T6G(SCH_1):PAGE251_I40@PURE_QUANTA.Q_RES(CHIPS)':
 C_PATH='@t6g_mb_lib.t6g(sch_1):page251_i40@pure_quanta.q_res(chips)',
 P_PATH='@t6g_mb_lib.t6g(sch_1):page252_i40@pure_quanta.q_res(chips)',
 PATH='I40',
 DRAWING='@T6G_MB_LIB.T6G(SCH_1):PAGE251',
 WATTAGE='1/16W',
 TOLERANCE='5%',
 MATERIAL='EMPTY',
 PHYS_PAGE='252',
 XY='(-2550,1275)',
 ROT='0',
 VER='1',
 PACK_TYPE='0402LF',
 LOCATION='R4270',
 CDS_LIB='pure_quanta',
 CDS_PART_NAME='Q_RES_0402LF-2.2K,5%,1/16W,EMPTY,CS22202JB07',
 PART_NUMBER='CS22202JB07',
 VALUE='2.2K',
 PRIM_FILE='./archive_libs/logical/q_res/chips/chips.prt';

PART_NAME
 R4303 'Q_RES_0402LF-0,5%,1/16W,CHIP,CS00002JB13':;

SECTION_NUMBER 1
 '@T6G_MB_LIB.T6G(SCH_1):PAGE28_I191@PURE_QUANTA.Q_RES(CHIPS)':
 C_PATH='@t6g_mb_lib.t6g(sch_1):page28_i191@pure_quanta.q_res(chips)',
 P_PATH='@t6g_mb_lib.t6g(sch_1):page28_i191@pure_quanta.q_res(chips)',
 PATH='I191',
 DRAWING='@T6G_MB_LIB.T6G(SCH_1):PAGE28',
 WATTAGE='1/16W',
 TOLERANCE='5%',
 MATERIAL='CHIP',
 PHYS_PAGE='28',
 XY='(-2000,10925)',
 ROT='0',
 VER='1',
 PACK_TYPE='0402LF',
 LOCATION='R4303',
 CDS_LIB='pure_quanta',
 CDS_PART_NAME='Q_RES_0402LF-0,5%,1/16W,CHIP,CS00002JB13',
 PART_NUMBER='CS00002JB13',
 VALUE='0',
 PRIM_FILE='./archive_libs/logical/q_res/chips/chips.prt';

PART_NAME
 R4304 'Q_RES_0402LF-0,5%,1/16W,CHIP,CS00002JB13':;

SECTION_NUMBER 1
 '@T6G_MB_LIB.T6G(SCH_1):PAGE28_I192@PURE_QUANTA.Q_RES(CHIPS)':
 C_PATH='@t6g_mb_lib.t6g(sch_1):page28_i192@pure_quanta.q_res(chips)',
 P_PATH='@t6g_mb_lib.t6g(sch_1):page28_i192@pure_quanta.q_res(chips)',
 PATH='I192',
 DRAWING='@T6G_MB_LIB.T6G(SCH_1):PAGE28',
 WATTAGE='1/16W',
 TOLERANCE='5%',
 MATERIAL='CHIP',
 PHYS_PAGE='28',
 XY='(-2000,10875)',
 ROT='0',
 VER='1',
 PACK_TYPE='0402LF',
 LOCATION='R4304',
 CDS_LIB='pure_quanta',
 CDS_PART_NAME='Q_RES_0402LF-0,5%,1/16W,CHIP,CS00002JB13',
 PART_NUMBER='CS00002JB13',
 VALUE='0',
 PRIM_FILE='./archive_libs/logical/q_res/chips/chips.prt';

PART_NAME
 R4305 'Q_RES_0402LF-0,5%,1/16W,CHIP,CS00002JB13':;

SECTION_NUMBER 1
 '@T6G_MB_LIB.T6G(SCH_1):PAGE55_I327@PURE_QUANTA.Q_RES(CHIPS)':
 C_PATH='@t6g_mb_lib.t6g(sch_1):page55_i327@pure_quanta.q_res(chips)',
 P_PATH='@t6g_mb_lib.t6g(sch_1):page55_i327@pure_quanta.q_res(chips)',
 PATH='I327',
 DRAWING='@T6G_MB_LIB.T6G(SCH_1):PAGE55',
 WATTAGE='1/16W',
 TOLERANCE='5%',
 MATERIAL='CHIP',
 PHYS_PAGE='55',
 XY='(-2000,4025)',
 ROT='0',
 VER='1',
 PACK_TYPE='0402LF',
 LOCATION='R4305',
 CDS_LIB='pure_quanta',
 CDS_PART_NAME='Q_RES_0402LF-0,5%,1/16W,CHIP,CS00002JB13',
 PART_NUMBER='CS00002JB13',
 VALUE='0',
 PRIM_FILE='./archive_libs/logical/q_res/chips/chips.prt';

PART_NAME
 R4306 'Q_RES_0402LF-0,5%,1/16W,CHIP,CS00002JB13':;

SECTION_NUMBER 1
 '@T6G_MB_LIB.T6G(SCH_1):PAGE55_I326@PURE_QUANTA.Q_RES(CHIPS)':
 C_PATH='@t6g_mb_lib.t6g(sch_1):page55_i326@pure_quanta.q_res(chips)',
 P_PATH='@t6g_mb_lib.t6g(sch_1):page55_i326@pure_quanta.q_res(chips)',
 PATH='I326',
 DRAWING='@T6G_MB_LIB.T6G(SCH_1):PAGE55',
 WATTAGE='1/16W',
 TOLERANCE='5%',
 MATERIAL='CHIP',
 PHYS_PAGE='55',
 XY='(-2000,3975)',
 ROT='0',
 VER='1',
 PACK_TYPE='0402LF',
 LOCATION='R4306',
 CDS_LIB='pure_quanta',
 CDS_PART_NAME='Q_RES_0402LF-0,5%,1/16W,CHIP,CS00002JB13',
 PART_NUMBER='CS00002JB13',
 VALUE='0',
 PRIM_FILE='./archive_libs/logical/q_res/chips/chips.prt';

PART_NAME
 R4419 'Q_RES_0402LF-49.9,1%,1/16W,EMPTY,CS04992FB07':;

SECTION_NUMBER 1
 '@T6G_MB_LIB.T6G(SCH_1):PAGE358_I203@PURE_QUANTA.Q_RES(CHIPS)':
 C_PATH='@t6g_mb_lib.t6g(sch_1):page358_i203@pure_quanta.q_res(chips)',
 P_PATH='@t6g_mb_lib.t6g(sch_1):page234_i203@pure_quanta.q_res(chips)',
 PATH='I203',
 DRAWING='@T6G_MB_LIB.T6G(SCH_1):PAGE358',
 WATTAGE='1/16W',
 TOLERANCE='1%',
 MATERIAL='EMPTY',
 PHYS_PAGE='234',
 XY='(3450,3675)',
 ROT='0',
 VER='2',
 PACK_TYPE='0402LF',
 LOCATION='R4419',
 CDS_LIB='pure_quanta',
 CDS_PART_NAME='Q_RES_0402LF-49.9,1%,1/16W,EMPTY,CS04992FB07',
 PART_NUMBER='CS04992FB07',
 VALUE='49.9',
 PRIM_FILE='./archive_libs/logical/q_res/chips/chips.prt';

PART_NAME
 R4420 'Q_RES_0402LF-49.9,1%,1/16W,EMPTY,CS04992FB07':;

SECTION_NUMBER 1
 '@T6G_MB_LIB.T6G(SCH_1):PAGE358_I202@PURE_QUANTA.Q_RES(CHIPS)':
 C_PATH='@t6g_mb_lib.t6g(sch_1):page358_i202@pure_quanta.q_res(chips)',
 P_PATH='@t6g_mb_lib.t6g(sch_1):page234_i202@pure_quanta.q_res(chips)',
 PATH='I202',
 DRAWING='@T6G_MB_LIB.T6G(SCH_1):PAGE358',
 WATTAGE='1/16W',
 TOLERANCE='1%',
 MATERIAL='EMPTY',
 PHYS_PAGE='234',
 XY='(3625,3675)',
 ROT='0',
 VER='2',
 PACK_TYPE='0402LF',
 LOCATION='R4420',
 CDS_LIB='pure_quanta',
 CDS_PART_NAME='Q_RES_0402LF-49.9,1%,1/16W,EMPTY,CS04992FB07',
 PART_NUMBER='CS04992FB07',
 VALUE='49.9',
 PRIM_FILE='./archive_libs/logical/q_res/chips/chips.prt';

PART_NAME
 R4450 'Q_RES_0402LF-0,5%,1/16W,CHIP,CS00002JB13':
 ROOM='USB3_HUB1_CYP';

SECTION_NUMBER 1
 '@T6G_MB_LIB.T6G(SCH_1):PAGE153_I27@PURE_QUANTA.Q_RES(CHIPS)':
 C_PATH='@t6g_mb_lib.t6g(sch_1):page153_i27@pure_quanta.q_res(chips)',
 P_PATH='@t6g_mb_lib.t6g(sch_1):page176_i27@pure_quanta.q_res(chips)',
 PATH='I27',
 DRAWING='@T6G_MB_LIB.T6G(SCH_1):PAGE153',
 WATTAGE='1/16W',
 TOLERANCE='5%',
 MATERIAL='CHIP',
 PHYS_PAGE='176',
 XY='(-2825,6125)',
 ROT='0',
 VER='1',
 PACK_TYPE='0402LF',
 LOCATION='R4450',
 CDS_LIB='pure_quanta',
 CDS_PART_NAME='Q_RES_0402LF-0,5%,1/16W,CHIP,CS00002JB13',
 ROOM='USB3_HUB1_CYP',
 PART_NUMBER='CS00002JB13',
 VALUE='0',
 PRIM_FILE='./archive_libs/logical/q_res/chips/chips.prt';

PART_NAME
 R4451 'Q_RES_0402LF-33.2,1%,1/16W,CHIP,CS03322FB03':
 ROOM='USB3_HUB1_CYP';

SECTION_NUMBER 1
 '@T6G_MB_LIB.T6G(SCH_1):PAGE153_I20@PURE_QUANTA.Q_RES(CHIPS)':
 C_PATH='@t6g_mb_lib.t6g(sch_1):page153_i20@pure_quanta.q_res(chips)',
 P_PATH='@t6g_mb_lib.t6g(sch_1):page176_i20@pure_quanta.q_res(chips)',
 PATH='I20',
 DRAWING='@T6G_MB_LIB.T6G(SCH_1):PAGE153',
 WATTAGE='1/16W',
 TOLERANCE='1%',
 MATERIAL='CHIP',
 PHYS_PAGE='176',
 XY='(-7450,600)',
 ROT='0',
 VER='1',
 PACK_TYPE='0402LF',
 LOCATION='R4451',
 CDS_LIB='pure_quanta',
 CDS_PART_NAME='Q_RES_0402LF-33.2,1%,1/16W,CHIP,CS03322FB03',
 ROOM='USB3_HUB1_CYP',
 PART_NUMBER='CS03322FB03',
 VALUE='33.2',
 PRIM_FILE='./archive_libs/logical/q_res/chips/chips.prt';

PART_NAME
 R4452 'Q_RES_0402LF-10K,1%,1/16W,EMPTY,CS31002FB08':
 ROOM='USB3_HUB1_CYP';

SECTION_NUMBER 1
 '@T6G_MB_LIB.T6G(SCH_1):PAGE153_I93@PURE_QUANTA.Q_RES(CHIPS)':
 C_PATH='@t6g_mb_lib.t6g(sch_1):page153_i93@pure_quanta.q_res(chips)',
 P_PATH='@t6g_mb_lib.t6g(sch_1):page176_i93@pure_quanta.q_res(chips)',
 PATH='I93',
 DRAWING='@T6G_MB_LIB.T6G(SCH_1):PAGE153',
 WATTAGE='1/16W',
 TOLERANCE='1%',
 MATERIAL='EMPTY',
 PHYS_PAGE='176',
 XY='(-6875,850)',
 ROT='0',
 VER='2',
 PACK_TYPE='0402LF',
 LOCATION='R4452',
 CDS_LIB='pure_quanta',
 CDS_PART_NAME='Q_RES_0402LF-10K,1%,1/16W,EMPTY,CS31002FB08',
 ROOM='USB3_HUB1_CYP',
 PART_NUMBER='CS31002FB08',
 VALUE='10K',
 PRIM_FILE='./archive_libs/logical/q_res/chips/chips.prt';

PART_NAME
 R4453 'Q_RES_0402LF-47K,0.1%,1/16W,EMPTY,CS34702BB05':
 ROOM='USB3_HUB1_CYP';

SECTION_NUMBER 1
 '@T6G_MB_LIB.T6G(SCH_1):PAGE153_I23@PURE_QUANTA.Q_RES(CHIPS)':
 C_PATH='@t6g_mb_lib.t6g(sch_1):page153_i23@pure_quanta.q_res(chips)',
 P_PATH='@t6g_mb_lib.t6g(sch_1):page176_i23@pure_quanta.q_res(chips)',
 PATH='I23',
 DRAWING='@T6G_MB_LIB.T6G(SCH_1):PAGE153',
 WATTAGE='1/16W',
 TOLERANCE='0.1%',
 MATERIAL='EMPTY',
 PHYS_PAGE='176',
 XY='(-5875,375)',
 ROT='0',
 VER='2',
 PACK_TYPE='0402LF',
 LOCATION='R4453',
 CDS_LIB='pure_quanta',
 CDS_PART_NAME='Q_RES_0402LF-47K,0.1%,1/16W,EMPTY,CS34702BB05',
 ROOM='USB3_HUB1_CYP',
 PART_NUMBER='CS34702BB05',
 VALUE='47K',
 PRIM_FILE='./archive_libs/logical/q_res/chips/chips.prt';

PART_NAME
 R4475 'Q_RES_0603LF-1,1%,1/10W,CHIP,CS-1003F900':;

SECTION_NUMBER 1
 '@T6G_MB_LIB.T6G(SCH_1):PAGE160_I6@PURE_QUANTA.Q_RES(CHIPS)':
 C_PATH='@t6g_mb_lib.t6g(sch_1):page160_i6@pure_quanta.q_res(chips)',
 P_PATH='@t6g_mb_lib.t6g(sch_1):page182_i6@pure_quanta.q_res(chips)',
 PATH='I6',
 DRAWING='@T6G_MB_LIB.T6G(SCH_1):PAGE160',
 SEC_TYPE='0603LF',
 WATTAGE='1/10W',
 TOLERANCE='1%',
 MATERIAL='CHIP',
 PHYS_PAGE='182',
 XY='(-7875,5225)',
 ROT='0',
 VER='1',
 PACK_TYPE='0603LF',
 LOCATION='R4475',
 SEC='1',
 CDS_LIB='pure_quanta',
 CDS_PART_NAME='Q_RES_0603LF-1,1%,1/10W,CHIP,CS-1003F900',
 PART_NUMBER='CS-1003F900',
 VALUE='1',
 PRIM_FILE='./archive_libs/logical/q_res/chips/chips.prt';

PART_NAME
 R4476 'Q_RES_0402LF-10K,1%,1/16W,CHIP,CS31002FB08':;

SECTION_NUMBER 1
 '@T6G_MB_LIB.T6G(SCH_1):PAGE160_I73@PURE_QUANTA.Q_RES(CHIPS)':
 C_PATH='@t6g_mb_lib.t6g(sch_1):page160_i73@pure_quanta.q_res(chips)',
 P_PATH='@t6g_mb_lib.t6g(sch_1):page182_i73@pure_quanta.q_res(chips)',
 PATH='I73',
 DRAWING='@T6G_MB_LIB.T6G(SCH_1):PAGE160',
 WATTAGE='1/16W',
 TOLERANCE='1%',
 MATERIAL='CHIP',
 PHYS_PAGE='182',
 XY='(-7200,3700)',
 ROT='2',
 VER='2',
 PACK_TYPE='0402LF',
 LOCATION='R4476',
 CDS_LIB='pure_quanta',
 CDS_PART_NAME='Q_RES_0402LF-10K,1%,1/16W,CHIP,CS31002FB08',
 PART_NUMBER='CS31002FB08',
 VALUE='10K',
 PRIM_FILE='./archive_libs/logical/q_res/chips/chips.prt';

PART_NAME
 R4482 'Q_RES_0402LF-49.9,1%,1/16W,EMPTY,CS04992FB07':;

SECTION_NUMBER 1
 '@T6G_MB_LIB.T6G(SCH_1):PAGE358_I208@PURE_QUANTA.Q_RES(CHIPS)':
 C_PATH='@t6g_mb_lib.t6g(sch_1):page358_i208@pure_quanta.q_res(chips)',
 P_PATH='@t6g_mb_lib.t6g(sch_1):page234_i208@pure_quanta.q_res(chips)',
 PATH='I208',
 DRAWING='@T6G_MB_LIB.T6G(SCH_1):PAGE358',
 WATTAGE='1/16W',
 TOLERANCE='1%',
 MATERIAL='EMPTY',
 PHYS_PAGE='234',
 XY='(-2450,1025)',
 ROT='0',
 VER='2',
 PACK_TYPE='0402LF',
 LOCATION='R4482',
 CDS_LIB='pure_quanta',
 CDS_PART_NAME='Q_RES_0402LF-49.9,1%,1/16W,EMPTY,CS04992FB07',
 PART_NUMBER='CS04992FB07',
 VALUE='49.9',
 PRIM_FILE='./archive_libs/logical/q_res/chips/chips.prt';

PART_NAME
 R4483 'Q_RES_0402LF-49.9,1%,1/16W,EMPTY,CS04992FB07':;

SECTION_NUMBER 1
 '@T6G_MB_LIB.T6G(SCH_1):PAGE358_I206@PURE_QUANTA.Q_RES(CHIPS)':
 C_PATH='@t6g_mb_lib.t6g(sch_1):page358_i206@pure_quanta.q_res(chips)',
 P_PATH='@t6g_mb_lib.t6g(sch_1):page234_i206@pure_quanta.q_res(chips)',
 PATH='I206',
 DRAWING='@T6G_MB_LIB.T6G(SCH_1):PAGE358',
 WATTAGE='1/16W',
 TOLERANCE='1%',
 MATERIAL='EMPTY',
 PHYS_PAGE='234',
 XY='(-2275,1025)',
 ROT='0',
 VER='2',
 PACK_TYPE='0402LF',
 LOCATION='R4483',
 CDS_LIB='pure_quanta',
 CDS_PART_NAME='Q_RES_0402LF-49.9,1%,1/16W,EMPTY,CS04992FB07',
 PART_NUMBER='CS04992FB07',
 VALUE='49.9',
 PRIM_FILE='./archive_libs/logical/q_res/chips/chips.prt';

PART_NAME
 R4489 'Q_RES_0402LF-4.75K,1%,1/16W,CHIP,CS24752FB03':;

SECTION_NUMBER 1
 '@T6G_MB_LIB.T6G(SCH_1):PAGE160_I3@PURE_QUANTA.Q_RES(CHIPS)':
 C_PATH='@t6g_mb_lib.t6g(sch_1):page160_i3@pure_quanta.q_res(chips)',
 P_PATH='@t6g_mb_lib.t6g(sch_1):page182_i3@pure_quanta.q_res(chips)',
 PATH='I3',
 DRAWING='@T6G_MB_LIB.T6G(SCH_1):PAGE160',
 WATTAGE='1/16W',
 TOLERANCE='1%',
 MATERIAL='CHIP',
 PHYS_PAGE='182',
 XY='(-6250,1800)',
 ROT='0',
 VER='2',
 PACK_TYPE='0402LF',
 LOCATION='R4489',
 CDS_LIB='pure_quanta',
 CDS_PART_NAME='Q_RES_0402LF-4.75K,1%,1/16W,CHIP,CS24752FB03',
 PART_NUMBER='CS24752FB03',
 VALUE='4.75K',
 PRIM_FILE='./archive_libs/logical/q_res/chips/chips.prt';

PART_NAME
 R4490 'Q_RES_0402LF-4.75K,1%,1/16W,EMPTY,CS24752FB03':;

SECTION_NUMBER 1
 '@T6G_MB_LIB.T6G(SCH_1):PAGE160_I2@PURE_QUANTA.Q_RES(CHIPS)':
 C_PATH='@t6g_mb_lib.t6g(sch_1):page160_i2@pure_quanta.q_res(chips)',
 P_PATH='@t6g_mb_lib.t6g(sch_1):page182_i2@pure_quanta.q_res(chips)',
 PATH='I2',
 DRAWING='@T6G_MB_LIB.T6G(SCH_1):PAGE160',
 WATTAGE='1/16W',
 TOLERANCE='1%',
 MATERIAL='EMPTY',
 PHYS_PAGE='182',
 XY='(-6250,1375)',
 ROT='0',
 VER='2',
 PACK_TYPE='0402LF',
 LOCATION='R4490',
 CDS_LIB='pure_quanta',
 CDS_PART_NAME='Q_RES_0402LF-4.75K,1%,1/16W,EMPTY,CS24752FB03',
 PART_NUMBER='CS24752FB03',
 VALUE='4.75K',
 PRIM_FILE='./archive_libs/logical/q_res/chips/chips.prt';

PART_NAME
 R4491 'Q_RES_0402LF-10K,1%,1/16W,CHIP,CS31002FB08':;

SECTION_NUMBER 1
 '@T6G_MB_LIB.T6G(SCH_1):PAGE160_I31@PURE_QUANTA.Q_RES(CHIPS)':
 C_PATH='@t6g_mb_lib.t6g(sch_1):page160_i31@pure_quanta.q_res(chips)',
 P_PATH='@t6g_mb_lib.t6g(sch_1):page182_i31@pure_quanta.q_res(chips)',
 PATH='I31',
 DRAWING='@T6G_MB_LIB.T6G(SCH_1):PAGE160',
 WATTAGE='1/16W',
 TOLERANCE='1%',
 MATERIAL='CHIP',
 PHYS_PAGE='182',
 XY='(-4250,1800)',
 ROT='0',
 VER='2',
 PACK_TYPE='0402LF',
 LOCATION='R4491',
 CDS_LIB='pure_quanta',
 CDS_PART_NAME='Q_RES_0402LF-10K,1%,1/16W,CHIP,CS31002FB08',
 PART_NUMBER='CS31002FB08',
 VALUE='10K',
 PRIM_FILE='./archive_libs/logical/q_res/chips/chips.prt';

PART_NAME
 R4492 'Q_RES_0402LF-10K,1%,1/16W,CHIP,CS31002FB08':;

SECTION_NUMBER 1
 '@T6G_MB_LIB.T6G(SCH_1):PAGE160_I29@PURE_QUANTA.Q_RES(CHIPS)':
 C_PATH='@t6g_mb_lib.t6g(sch_1):page160_i29@pure_quanta.q_res(chips)',
 P_PATH='@t6g_mb_lib.t6g(sch_1):page182_i29@pure_quanta.q_res(chips)',
 PATH='I29',
 DRAWING='@T6G_MB_LIB.T6G(SCH_1):PAGE160',
 WATTAGE='1/16W',
 TOLERANCE='1%',
 MATERIAL='CHIP',
 PHYS_PAGE='182',
 XY='(-4250,1325)',
 ROT='0',
 VER='2',
 PACK_TYPE='0402LF',
 LOCATION='R4492',
 CDS_LIB='pure_quanta',
 CDS_PART_NAME='Q_RES_0402LF-10K,1%,1/16W,CHIP,CS31002FB08',
 PART_NUMBER='CS31002FB08',
 VALUE='10K',
 PRIM_FILE='./archive_libs/logical/q_res/chips/chips.prt';

PART_NAME
 R4493 'Q_RES_0603LF-1,1%,1/10W,CHIP,CS-1003F900':;

SECTION_NUMBER 1
 '@T6G_MB_LIB.T6G(SCH_1):PAGE160_I27@PURE_QUANTA.Q_RES(CHIPS)':
 C_PATH='@t6g_mb_lib.t6g(sch_1):page160_i27@pure_quanta.q_res(chips)',
 P_PATH='@t6g_mb_lib.t6g(sch_1):page182_i27@pure_quanta.q_res(chips)',
 PATH='I27',
 DRAWING='@T6G_MB_LIB.T6G(SCH_1):PAGE160',
 SEC_TYPE='0603LF',
 WATTAGE='1/10W',
 TOLERANCE='1%',
 MATERIAL='CHIP',
 PHYS_PAGE='182',
 XY='(-7925,6050)',
 ROT='0',
 VER='1',
 PACK_TYPE='0603LF',
 LOCATION='R4493',
 SEC='1',
 CDS_LIB='pure_quanta',
 CDS_PART_NAME='Q_RES_0603LF-1,1%,1/10W,CHIP,CS-1003F900',
 PART_NUMBER='CS-1003F900',
 VALUE='1',
 PRIM_FILE='./archive_libs/logical/q_res/chips/chips.prt';

PART_NAME
 R4501 'Q_RES_0402LF-0,5%,1/16W,CHIP,CS00002JB13':;

SECTION_NUMBER 1
 '@T6G_MB_LIB.T6G(SCH_1):PAGE232_I31@PURE_QUANTA.Q_RES(CHIPS)':
 C_PATH='@t6g_mb_lib.t6g(sch_1):page232_i31@pure_quanta.q_res(chips)',
 P_PATH='@t6g_mb_lib.t6g(sch_1):page233_i31@pure_quanta.q_res(chips)',
 PATH='I31',
 DRAWING='@T6G_MB_LIB.T6G(SCH_1):PAGE232',
 WATTAGE='1/16W',
 TOLERANCE='5%',
 MATERIAL='CHIP',
 PHYS_PAGE='233',
 XY='(-6375,4575)',
 ROT='0',
 VER='1',
 PACK_TYPE='0402LF',
 LOCATION='R4501',
 CDS_LIB='pure_quanta',
 CDS_PART_NAME='Q_RES_0402LF-0,5%,1/16W,CHIP,CS00002JB13',
 PART_NUMBER='CS00002JB13',
 VALUE='0',
 PRIM_FILE='./archive_libs/logical/q_res/chips/chips.prt';

PART_NAME
 R4506 'Q_RES_0402LF-33.2,1%,1/16W,CHIP,CS03322FB03':;

SECTION_NUMBER 1
 '@T6G_MB_LIB.T6G(SCH_1):PAGE348_I191@PURE_QUANTA.Q_RES(CHIPS)':
 C_PATH='@t6g_mb_lib.t6g(sch_1):page348_i191@pure_quanta.q_res(chips)',
 P_PATH='@t6g_mb_lib.t6g(sch_1):page150_i191@pure_quanta.q_res(chips)',
 PATH='I191',
 DRAWING='@T6G_MB_LIB.T6G(SCH_1):PAGE348',
 WATTAGE='1/16W',
 TOLERANCE='1%',
 MATERIAL='CHIP',
 PHYS_PAGE='150',
 XY='(-14925,8375)',
 ROT='0',
 VER='1',
 PACK_TYPE='0402LF',
 LOCATION='R4506',
 CDS_LIB='pure_quanta',
 CDS_PART_NAME='Q_RES_0402LF-33.2,1%,1/16W,CHIP,CS03322FB03',
 PART_NUMBER='CS03322FB03',
 VALUE='33.2',
 PRIM_FILE='./archive_libs/logical/q_res/chips/chips.prt';

PART_NAME
 R4507 'Q_RES_0402LF-33.2,1%,1/16W,CHIP,CS03322FB03':;

SECTION_NUMBER 1
 '@T6G_MB_LIB.T6G(SCH_1):PAGE348_I190@PURE_QUANTA.Q_RES(CHIPS)':
 C_PATH='@t6g_mb_lib.t6g(sch_1):page348_i190@pure_quanta.q_res(chips)',
 P_PATH='@t6g_mb_lib.t6g(sch_1):page150_i190@pure_quanta.q_res(chips)',
 PATH='I190',
 DRAWING='@T6G_MB_LIB.T6G(SCH_1):PAGE348',
 WATTAGE='1/16W',
 TOLERANCE='1%',
 MATERIAL='CHIP',
 PHYS_PAGE='150',
 XY='(-14925,8325)',
 ROT='0',
 VER='1',
 PACK_TYPE='0402LF',
 LOCATION='R4507',
 CDS_LIB='pure_quanta',
 CDS_PART_NAME='Q_RES_0402LF-33.2,1%,1/16W,CHIP,CS03322FB03',
 PART_NUMBER='CS03322FB03',
 VALUE='33.2',
 PRIM_FILE='./archive_libs/logical/q_res/chips/chips.prt';

PART_NAME
 R4508 'Q_RES_0402LF-33.2,1%,1/16W,CHIP,CS03322FB03':;

SECTION_NUMBER 1
 '@T6G_MB_LIB.T6G(SCH_1):PAGE348_I88@PURE_QUANTA.Q_RES(CHIPS)':
 C_PATH='@t6g_mb_lib.t6g(sch_1):page348_i88@pure_quanta.q_res(chips)',
 P_PATH='@t6g_mb_lib.t6g(sch_1):page150_i88@pure_quanta.q_res(chips)',
 PATH='I88',
 DRAWING='@T6G_MB_LIB.T6G(SCH_1):PAGE348',
 WATTAGE='1/16W',
 TOLERANCE='1%',
 MATERIAL='CHIP',
 PHYS_PAGE='150',
 XY='(-14925,7375)',
 ROT='0',
 VER='1',
 PACK_TYPE='0402LF',
 LOCATION='R4508',
 CDS_LIB='pure_quanta',
 CDS_PART_NAME='Q_RES_0402LF-33.2,1%,1/16W,CHIP,CS03322FB03',
 PART_NUMBER='CS03322FB03',
 VALUE='33.2',
 PRIM_FILE='./archive_libs/logical/q_res/chips/chips.prt';

PART_NAME
 R4509 'Q_RES_0402LF-33.2,1%,1/16W,CHIP,CS03322FB03':;

SECTION_NUMBER 1
 '@T6G_MB_LIB.T6G(SCH_1):PAGE348_I87@PURE_QUANTA.Q_RES(CHIPS)':
 C_PATH='@t6g_mb_lib.t6g(sch_1):page348_i87@pure_quanta.q_res(chips)',
 P_PATH='@t6g_mb_lib.t6g(sch_1):page150_i87@pure_quanta.q_res(chips)',
 PATH='I87',
 DRAWING='@T6G_MB_LIB.T6G(SCH_1):PAGE348',
 WATTAGE='1/16W',
 TOLERANCE='1%',
 MATERIAL='CHIP',
 PHYS_PAGE='150',
 XY='(-14925,7325)',
 ROT='0',
 VER='1',
 PACK_TYPE='0402LF',
 LOCATION='R4509',
 CDS_LIB='pure_quanta',
 CDS_PART_NAME='Q_RES_0402LF-33.2,1%,1/16W,CHIP,CS03322FB03',
 PART_NUMBER='CS03322FB03',
 VALUE='33.2',
 PRIM_FILE='./archive_libs/logical/q_res/chips/chips.prt';

PART_NAME
 R4514 'Q_RES_0402LF-4.7K,1%,1/16W,EMPTY,CS24702FB06':;

SECTION_NUMBER 1
 '@T6G_MB_LIB.T6G(SCH_1):PAGE232_I8@PURE_QUANTA.Q_RES(CHIPS)':
 C_PATH='@t6g_mb_lib.t6g(sch_1):page232_i8@pure_quanta.q_res(chips)',
 P_PATH='@t6g_mb_lib.t6g(sch_1):page233_i8@pure_quanta.q_res(chips)',
 PATH='I8',
 DRAWING='@T6G_MB_LIB.T6G(SCH_1):PAGE232',
 WATTAGE='1/16W',
 TOLERANCE='1%',
 MATERIAL='EMPTY',
 PHYS_PAGE='233',
 XY='(-6300,1175)',
 ROT='0',
 VER='2',
 PACK_TYPE='0402LF',
 LOCATION='R4514',
 CDS_LIB='pure_quanta',
 CDS_PART_NAME='Q_RES_0402LF-4.7K,1%,1/16W,EMPTY,CS24702FB06',
 PART_NUMBER='CS24702FB06',
 VALUE='4.7K',
 PRIM_FILE='./archive_libs/logical/q_res/chips/chips.prt';

PART_NAME
 R4515 'Q_RES_0402LF-100K,1%,1/16W,CHIP,CS41002FB09':;

SECTION_NUMBER 1
 '@T6G_MB_LIB.T6G(SCH_1):PAGE256_I200@PURE_QUANTA.Q_RES(CHIPS)':
 C_PATH='@t6g_mb_lib.t6g(sch_1):page256_i200@pure_quanta.q_res(chips)',
 P_PATH='@t6g_mb_lib.t6g(sch_1):page130_i200@pure_quanta.q_res(chips)',
 PATH='I200',
 DRAWING='@T6G_MB_LIB.T6G(SCH_1):PAGE256',
 WATTAGE='1/16W',
 TOLERANCE='1%',
 MATERIAL='CHIP',
 PHYS_PAGE='130',
 XY='(650,-1575)',
 ROT='0',
 VER='2',
 PACK_TYPE='0402LF',
 LOCATION='R4515',
 CDS_LIB='pure_quanta',
 CDS_PART_NAME='Q_RES_0402LF-100K,1%,1/16W,CHIP,CS41002FB09',
 PART_NUMBER='CS41002FB09',
 VALUE='100K',
 PRIM_FILE='./archive_libs/logical/q_res/chips/chips.prt';

PART_NAME
 R4518 'Q_RES_0402LF-10K,1%,1/16W,CHIP,CS31002FB08':;

SECTION_NUMBER 1
 '@T6G_MB_LIB.T6G(SCH_1):PAGE160_I52@PURE_QUANTA.Q_RES(CHIPS)':
 C_PATH='@t6g_mb_lib.t6g(sch_1):page160_i52@pure_quanta.q_res(chips)',
 P_PATH='@t6g_mb_lib.t6g(sch_1):page182_i52@pure_quanta.q_res(chips)',
 PATH='I52',
 DRAWING='@T6G_MB_LIB.T6G(SCH_1):PAGE160',
 WATTAGE='1/16W',
 TOLERANCE='1%',
 MATERIAL='CHIP',
 PHYS_PAGE='182',
 XY='(-3150,3075)',
 ROT='0',
 VER='2',
 PACK_TYPE='0402LF',
 LOCATION='R4518',
 CDS_LIB='pure_quanta',
 CDS_PART_NAME='Q_RES_0402LF-10K,1%,1/16W,CHIP,CS31002FB08',
 PART_NUMBER='CS31002FB08',
 VALUE='10K',
 PRIM_FILE='./archive_libs/logical/q_res/chips/chips.prt';

PART_NAME
 R4519 'Q_RES_0402LF-10K,1%,1/16W,CHIP,CS31002FB08':;

SECTION_NUMBER 1
 '@T6G_MB_LIB.T6G(SCH_1):PAGE160_I53@PURE_QUANTA.Q_RES(CHIPS)':
 C_PATH='@t6g_mb_lib.t6g(sch_1):page160_i53@pure_quanta.q_res(chips)',
 P_PATH='@t6g_mb_lib.t6g(sch_1):page182_i53@pure_quanta.q_res(chips)',
 PATH='I53',
 DRAWING='@T6G_MB_LIB.T6G(SCH_1):PAGE160',
 WATTAGE='1/16W',
 TOLERANCE='1%',
 MATERIAL='CHIP',
 PHYS_PAGE='182',
 XY='(-2925,3075)',
 ROT='0',
 VER='2',
 PACK_TYPE='0402LF',
 LOCATION='R4519',
 CDS_LIB='pure_quanta',
 CDS_PART_NAME='Q_RES_0402LF-10K,1%,1/16W,CHIP,CS31002FB08',
 PART_NUMBER='CS31002FB08',
 VALUE='10K',
 PRIM_FILE='./archive_libs/logical/q_res/chips/chips.prt';

PART_NAME
 R4520 'Q_RES_0402LF-10K,1%,1/16W,CHIP,CS31002FB08':;

SECTION_NUMBER 1
 '@T6G_MB_LIB.T6G(SCH_1):PAGE160_I55@PURE_QUANTA.Q_RES(CHIPS)':
 C_PATH='@t6g_mb_lib.t6g(sch_1):page160_i55@pure_quanta.q_res(chips)',
 P_PATH='@t6g_mb_lib.t6g(sch_1):page182_i55@pure_quanta.q_res(chips)',
 PATH='I55',
 DRAWING='@T6G_MB_LIB.T6G(SCH_1):PAGE160',
 WATTAGE='1/16W',
 TOLERANCE='1%',
 MATERIAL='CHIP',
 PHYS_PAGE='182',
 XY='(-2725,3100)',
 ROT='0',
 VER='2',
 PACK_TYPE='0402LF',
 LOCATION='R4520',
 CDS_LIB='pure_quanta',
 CDS_PART_NAME='Q_RES_0402LF-10K,1%,1/16W,CHIP,CS31002FB08',
 PART_NUMBER='CS31002FB08',
 VALUE='10K',
 PRIM_FILE='./archive_libs/logical/q_res/chips/chips.prt';

PART_NAME
 R4521 'Q_RES_0402LF-1K,1%,1/16W,CHIP,CS21002FB06':;

SECTION_NUMBER 1
 '@T6G_MB_LIB.T6G(SCH_1):PAGE232_I73@PURE_QUANTA.Q_RES(CHIPS)':
 C_PATH='@t6g_mb_lib.t6g(sch_1):page232_i73@pure_quanta.q_res(chips)',
 P_PATH='@t6g_mb_lib.t6g(sch_1):page233_i73@pure_quanta.q_res(chips)',
 PATH='I73',
 DRAWING='@T6G_MB_LIB.T6G(SCH_1):PAGE232',
 WATTAGE='1/16W',
 TOLERANCE='1%',
 MATERIAL='CHIP',
 PHYS_PAGE='233',
 XY='(-7975,3925)',
 ROT='0',
 VER='2',
 PACK_TYPE='0402LF',
 LOCATION='R4521',
 CDS_LIB='pure_quanta',
 CDS_PART_NAME='Q_RES_0402LF-1K,1%,1/16W,CHIP,CS21002FB06',
 PART_NUMBER='CS21002FB06',
 VALUE='1K',
 PRIM_FILE='./archive_libs/logical/q_res/chips/chips.prt';

PART_NAME
 R4532 'Q_RES_0402LF-10K,1%,1/16W,CHIP,CS31002FB08':
 ROOM='NIC_P12V_MPS_MAM_BOM2';

SECTION_NUMBER 1
 '@T6G_MB_LIB.T6G(SCH_1):PAGE339_I75@PURE_QUANTA.Q_RES(CHIPS)':
 C_PATH='@t6g_mb_lib.t6g(sch_1):page339_i75@pure_quanta.q_res(chips)',
 P_PATH='@t6g_mb_lib.t6g(sch_1):page135_i75@pure_quanta.q_res(chips)',
 PATH='I75',
 DRAWING='@T6G_MB_LIB.T6G(SCH_1):PAGE339',
 WATTAGE='1/16W',
 TOLERANCE='1%',
 MATERIAL='CHIP',
 PHYS_PAGE='135',
 XY='(-5925,10175)',
 ROT='0',
 VER='2',
 PACK_TYPE='0402LF',
 LOCATION='R4532',
 CDS_LIB='pure_quanta',
 CDS_PART_NAME='Q_RES_0402LF-10K,1%,1/16W,CHIP,CS31002FB08',
 ROOM='NIC_P12V_MPS_MAM_BOM2',
 PART_NUMBER='CS31002FB08',
 VALUE='10K',
 PRIM_FILE='./archive_libs/logical/q_res/chips/chips.prt';

PART_NAME
 R4535 'Q_RES_0402LF-0,5%,1/16W,CHIP,CS00002JB13':;

SECTION_NUMBER 1
 '@T6G_MB_LIB.T6G(SCH_1):PAGE28_I160@PURE_QUANTA.Q_RES(CHIPS)':
 C_PATH='@t6g_mb_lib.t6g(sch_1):page28_i160@pure_quanta.q_res(chips)',
 P_PATH='@t6g_mb_lib.t6g(sch_1):page28_i160@pure_quanta.q_res(chips)',
 PATH='I160',
 DRAWING='@T6G_MB_LIB.T6G(SCH_1):PAGE28',
 WATTAGE='1/16W',
 TOLERANCE='5%',
 MATERIAL='CHIP',
 PHYS_PAGE='28',
 XY='(-2025,11825)',
 ROT='0',
 VER='1',
 PACK_TYPE='0402LF',
 LOCATION='R4535',
 CDS_LIB='pure_quanta',
 CDS_PART_NAME='Q_RES_0402LF-0,5%,1/16W,CHIP,CS00002JB13',
 PART_NUMBER='CS00002JB13',
 VALUE='0',
 PRIM_FILE='./archive_libs/logical/q_res/chips/chips.prt';

PART_NAME
 R4536 'Q_RES_0402LF-0,5%,1/16W,CHIP,CS00002JB13':;

SECTION_NUMBER 1
 '@T6G_MB_LIB.T6G(SCH_1):PAGE28_I161@PURE_QUANTA.Q_RES(CHIPS)':
 C_PATH='@t6g_mb_lib.t6g(sch_1):page28_i161@pure_quanta.q_res(chips)',
 P_PATH='@t6g_mb_lib.t6g(sch_1):page28_i161@pure_quanta.q_res(chips)',
 PATH='I161',
 DRAWING='@T6G_MB_LIB.T6G(SCH_1):PAGE28',
 WATTAGE='1/16W',
 TOLERANCE='5%',
 MATERIAL='CHIP',
 PHYS_PAGE='28',
 XY='(-2025,11775)',
 ROT='0',
 VER='1',
 PACK_TYPE='0402LF',
 LOCATION='R4536',
 CDS_LIB='pure_quanta',
 CDS_PART_NAME='Q_RES_0402LF-0,5%,1/16W,CHIP,CS00002JB13',
 PART_NUMBER='CS00002JB13',
 VALUE='0',
 PRIM_FILE='./archive_libs/logical/q_res/chips/chips.prt';

PART_NAME
 R4537 'Q_RES_0402LF-0,5%,1/16W,CHIP,CS00002JB13':
 ROOM='PCIE REDRIVER BOM1';

SECTION_NUMBER 1
 '@T6G_MB_LIB.T6G(SCH_1):PAGE110_I67@PURE_QUANTA.Q_RES(CHIPS)':
 C_PATH='@t6g_mb_lib.t6g(sch_1):page110_i67@pure_quanta.q_res(chips)',
 P_PATH='@t6g_mb_lib.t6g(sch_1):page111_i67@pure_quanta.q_res(chips)',
 PATH='I67',
 DRAWING='@T6G_MB_LIB.T6G(SCH_1):PAGE110',
 WATTAGE='1/16W',
 TOLERANCE='5%',
 MATERIAL='CHIP',
 PHYS_PAGE='111',
 XY='(6250,5025)',
 ROT='0',
 VER='1',
 PACK_TYPE='0402LF',
 LOCATION='R4537',
 CDS_LIB='pure_quanta',
 CDS_PART_NAME='Q_RES_0402LF-0,5%,1/16W,CHIP,CS00002JB13',
 ROOM='PCIE REDRIVER BOM1',
 PART_NUMBER='CS00002JB13',
 VALUE='0',
 PRIM_FILE='./archive_libs/logical/q_res/chips/chips.prt';

PART_NAME
 R4543 'Q_RES_0402LF-1K,1%,1/16W,CHIP,CS21002FB06':;

SECTION_NUMBER 1
 '@T6G_MB_LIB.T6G(SCH_1):PAGE331_I85@PURE_QUANTA.Q_RES(CHIPS)':
 C_PATH='@t6g_mb_lib.t6g(sch_1):page331_i85@pure_quanta.q_res(chips)',
 P_PATH='@t6g_mb_lib.t6g(sch_1):page124_i85@pure_quanta.q_res(chips)',
 PATH='I85',
 DRAWING='@T6G_MB_LIB.T6G(SCH_1):PAGE331',
 WATTAGE='1/16W',
 TOLERANCE='1%',
 MATERIAL='CHIP',
 PHYS_PAGE='124',
 XY='(-2000,750)',
 ROT='0',
 VER='2',
 PACK_TYPE='0402LF',
 LOCATION='R4543',
 CDS_LIB='pure_quanta',
 CDS_PART_NAME='Q_RES_0402LF-1K,1%,1/16W,CHIP,CS21002FB06',
 PART_NUMBER='CS21002FB06',
 VALUE='1K',
 PRIM_FILE='./archive_libs/logical/q_res/chips/chips.prt';

PART_NAME
 R4544 'Q_RES_0402LF-100K,1%,1/16W,EMPTY,CS41002FB09':;

SECTION_NUMBER 1
 '@T6G_MB_LIB.T6G(SCH_1):PAGE331_I62@PURE_QUANTA.Q_RES(CHIPS)':
 C_PATH='@t6g_mb_lib.t6g(sch_1):page331_i62@pure_quanta.q_res(chips)',
 P_PATH='@t6g_mb_lib.t6g(sch_1):page124_i62@pure_quanta.q_res(chips)',
 PATH='I62',
 DRAWING='@T6G_MB_LIB.T6G(SCH_1):PAGE331',
 WATTAGE='1/16W',
 TOLERANCE='1%',
 MATERIAL='EMPTY',
 PHYS_PAGE='124',
 XY='(-1975,275)',
 ROT='0',
 VER='2',
 PACK_TYPE='0402LF',
 LOCATION='R4544',
 CDS_LIB='pure_quanta',
 CDS_PART_NAME='Q_RES_0402LF-100K,1%,1/16W,EMPTY,CS41002FB09',
 PART_NUMBER='CS41002FB09',
 VALUE='100K',
 PRIM_FILE='./archive_libs/logical/q_res/chips/chips.prt';

PART_NAME
 R4545 'Q_RES_0402LF-4.7K,5%,1/16W,CHIP,CS24702JB10':;

SECTION_NUMBER 1
 '@T6G_MB_LIB.T6G(SCH_1):PAGE331_I57@PURE_QUANTA.Q_RES(CHIPS)':
 C_PATH='@t6g_mb_lib.t6g(sch_1):page331_i57@pure_quanta.q_res(chips)',
 P_PATH='@t6g_mb_lib.t6g(sch_1):page124_i57@pure_quanta.q_res(chips)',
 PATH='I57',
 DRAWING='@T6G_MB_LIB.T6G(SCH_1):PAGE331',
 WATTAGE='1/16W',
 TOLERANCE='5%',
 MATERIAL='CHIP',
 PHYS_PAGE='124',
 XY='(-825,1125)',
 ROT='0',
 VER='2',
 PACK_TYPE='0402LF',
 LOCATION='R4545',
 CDS_LIB='pure_quanta',
 CDS_PART_NAME='Q_RES_0402LF-4.7K,5%,1/16W,CHIP,CS24702JB10',
 PART_NUMBER='CS24702JB10',
 VALUE='4.7K',
 PRIM_FILE='./archive_libs/logical/q_res/chips/chips.prt';

PART_NAME
 R4546 'Q_RES_0402LF-100K,1%,1/16W,EMPTY,CS41002FB09':;

SECTION_NUMBER 1
 '@T6G_MB_LIB.T6G(SCH_1):PAGE331_I110@PURE_QUANTA.Q_RES(CHIPS)':
 C_PATH='@t6g_mb_lib.t6g(sch_1):page331_i110@pure_quanta.q_res(chips)',
 P_PATH='@t6g_mb_lib.t6g(sch_1):page124_i110@pure_quanta.q_res(chips)',
 PATH='I110',
 DRAWING='@T6G_MB_LIB.T6G(SCH_1):PAGE331',
 WATTAGE='1/16W',
 TOLERANCE='1%',
 MATERIAL='EMPTY',
 PHYS_PAGE='124',
 XY='(325,1250)',
 ROT='2',
 VER='2',
 PACK_TYPE='0402LF',
 LOCATION='R4546',
 CDS_LIB='pure_quanta',
 CDS_PART_NAME='Q_RES_0402LF-100K,1%,1/16W,EMPTY,CS41002FB09',
 PART_NUMBER='CS41002FB09',
 VALUE='100K',
 PRIM_FILE='./archive_libs/logical/q_res/chips/chips.prt';

PART_NAME
 R4547 'Q_RES_0402LF-100K,1%,1/16W,EMPTY,CS41002FB09':;

SECTION_NUMBER 1
 '@T6G_MB_LIB.T6G(SCH_1):PAGE331_I89@PURE_QUANTA.Q_RES(CHIPS)':
 C_PATH='@t6g_mb_lib.t6g(sch_1):page331_i89@pure_quanta.q_res(chips)',
 P_PATH='@t6g_mb_lib.t6g(sch_1):page124_i89@pure_quanta.q_res(chips)',
 PATH='I89',
 DRAWING='@T6G_MB_LIB.T6G(SCH_1):PAGE331',
 WATTAGE='1/16W',
 TOLERANCE='1%',
 MATERIAL='EMPTY',
 PHYS_PAGE='124',
 XY='(2375,5550)',
 ROT='0',
 VER='2',
 PACK_TYPE='0402LF',
 LOCATION='R4547',
 CDS_LIB='pure_quanta',
 CDS_PART_NAME='Q_RES_0402LF-100K,1%,1/16W,EMPTY,CS41002FB09',
 PART_NUMBER='CS41002FB09',
 VALUE='100K',
 PRIM_FILE='./archive_libs/logical/q_res/chips/chips.prt';

PART_NAME
 R4548 'Q_RES_0402LF-100K,1%,1/16W,CHIP,CS41002FB09':;

SECTION_NUMBER 1
 '@T6G_MB_LIB.T6G(SCH_1):PAGE331_I87@PURE_QUANTA.Q_RES(CHIPS)':
 C_PATH='@t6g_mb_lib.t6g(sch_1):page331_i87@pure_quanta.q_res(chips)',
 P_PATH='@t6g_mb_lib.t6g(sch_1):page124_i87@pure_quanta.q_res(chips)',
 PATH='I87',
 DRAWING='@T6G_MB_LIB.T6G(SCH_1):PAGE331',
 WATTAGE='1/16W',
 TOLERANCE='1%',
 MATERIAL='CHIP',
 PHYS_PAGE='124',
 XY='(2400,5075)',
 ROT='0',
 VER='2',
 PACK_TYPE='0402LF',
 LOCATION='R4548',
 CDS_LIB='pure_quanta',
 CDS_PART_NAME='Q_RES_0402LF-100K,1%,1/16W,CHIP,CS41002FB09',
 PART_NUMBER='CS41002FB09',
 VALUE='100K',
 PRIM_FILE='./archive_libs/logical/q_res/chips/chips.prt';

PART_NAME
 R4549 'Q_RES_0402LF-4.7K,5%,1/16W,EMPTY,CS24702JB10':;

SECTION_NUMBER 1
 '@T6G_MB_LIB.T6G(SCH_1):PAGE331_I98@PURE_QUANTA.Q_RES(CHIPS)':
 C_PATH='@t6g_mb_lib.t6g(sch_1):page331_i98@pure_quanta.q_res(chips)',
 P_PATH='@t6g_mb_lib.t6g(sch_1):page124_i98@pure_quanta.q_res(chips)',
 PATH='I98',
 DRAWING='@T6G_MB_LIB.T6G(SCH_1):PAGE331',
 WATTAGE='1/16W',
 TOLERANCE='5%',
 MATERIAL='EMPTY',
 PHYS_PAGE='124',
 XY='(5125,5525)',
 ROT='0',
 VER='2',
 PACK_TYPE='0402LF',
 LOCATION='R4549',
 CDS_LIB='pure_quanta',
 CDS_PART_NAME='Q_RES_0402LF-4.7K,5%,1/16W,EMPTY,CS24702JB10',
 PART_NUMBER='CS24702JB10',
 VALUE='4.7K',
 PRIM_FILE='./archive_libs/logical/q_res/chips/chips.prt';

PART_NAME
 R4550 'Q_RES_0402LF-49.9,1%,1/16W,CHIP,CS04992FB07':;

SECTION_NUMBER 1
 '@T6G_MB_LIB.T6G(SCH_1):PAGE331_I97@PURE_QUANTA.Q_RES(CHIPS)':
 C_PATH='@t6g_mb_lib.t6g(sch_1):page331_i97@pure_quanta.q_res(chips)',
 P_PATH='@t6g_mb_lib.t6g(sch_1):page124_i97@pure_quanta.q_res(chips)',
 PATH='I97',
 DRAWING='@T6G_MB_LIB.T6G(SCH_1):PAGE331',
 WATTAGE='1/16W',
 TOLERANCE='1%',
 MATERIAL='CHIP',
 PHYS_PAGE='124',
 XY='(5375,5275)',
 ROT='0',
 VER='1',
 PACK_TYPE='0402LF',
 LOCATION='R4550',
 CDS_LIB='pure_quanta',
 CDS_PART_NAME='Q_RES_0402LF-49.9,1%,1/16W,CHIP,CS04992FB07',
 PART_NUMBER='CS04992FB07',
 VALUE='49.9',
 PRIM_FILE='./archive_libs/logical/q_res/chips/chips.prt';

PART_NAME
 R4551 'Q_RES_0402LF-54.9K,1%,1/16W,EMPTY,CS35492FB03':;

SECTION_NUMBER 1
 '@T6G_MB_LIB.T6G(SCH_1):PAGE364_I51@PURE_QUANTA.Q_RES(CHIPS)':
 C_PATH='@t6g_mb_lib.t6g(sch_1):page364_i51@pure_quanta.q_res(chips)',
 P_PATH='@t6g_mb_lib.t6g(sch_1):page241_i51@pure_quanta.q_res(chips)',
 PATH='I51',
 DRAWING='@T6G_MB_LIB.T6G(SCH_1):PAGE364',
 WATTAGE='1/16W',
 TOLERANCE='1%',
 MATERIAL='EMPTY',
 PHYS_PAGE='241',
 XY='(-1125,-1800)',
 ROT='0',
 VER='2',
 PACK_TYPE='0402LF',
 LOCATION='R4551',
 CDS_LIB='pure_quanta',
 CDS_PART_NAME='Q_RES_0402LF-54.9K,1%,1/16W,EMPTY,CS35492FB03',
 PART_NUMBER='CS35492FB03',
 VALUE='54.9K',
 PRIM_FILE='./archive_libs/logical/q_res/chips/chips.prt';

PART_NAME
 R4552 'Q_RES_0402LF-100K,1%,1/16W,CHIP,CS41002FB09':;

SECTION_NUMBER 1
 '@T6G_MB_LIB.T6G(SCH_1):PAGE364_I50@PURE_QUANTA.Q_RES(CHIPS)':
 C_PATH='@t6g_mb_lib.t6g(sch_1):page364_i50@pure_quanta.q_res(chips)',
 P_PATH='@t6g_mb_lib.t6g(sch_1):page241_i50@pure_quanta.q_res(chips)',
 PATH='I50',
 DRAWING='@T6G_MB_LIB.T6G(SCH_1):PAGE364',
 WATTAGE='1/16W',
 TOLERANCE='1%',
 MATERIAL='CHIP',
 PHYS_PAGE='241',
 XY='(-1100,-2275)',
 ROT='0',
 VER='2',
 PACK_TYPE='0402LF',
 LOCATION='R4552',
 CDS_LIB='pure_quanta',
 CDS_PART_NAME='Q_RES_0402LF-100K,1%,1/16W,CHIP,CS41002FB09',
 PART_NUMBER='CS41002FB09',
 VALUE='100K',
 PRIM_FILE='./archive_libs/logical/q_res/chips/chips.prt';

PART_NAME
 R4553 'Q_RES_0402LF-4.7K,5%,1/16W,CHIP,CS24702JB10':;

SECTION_NUMBER 1
 '@T6G_MB_LIB.T6G(SCH_1):PAGE364_I55@PURE_QUANTA.Q_RES(CHIPS)':
 C_PATH='@t6g_mb_lib.t6g(sch_1):page364_i55@pure_quanta.q_res(chips)',
 P_PATH='@t6g_mb_lib.t6g(sch_1):page241_i55@pure_quanta.q_res(chips)',
 PATH='I55',
 DRAWING='@T6G_MB_LIB.T6G(SCH_1):PAGE364',
 WATTAGE='1/16W',
 TOLERANCE='5%',
 MATERIAL='CHIP',
 PHYS_PAGE='241',
 XY='(50,-1425)',
 ROT='0',
 VER='2',
 PACK_TYPE='0402LF',
 LOCATION='R4553',
 CDS_LIB='pure_quanta',
 CDS_PART_NAME='Q_RES_0402LF-4.7K,5%,1/16W,CHIP,CS24702JB10',
 PART_NUMBER='CS24702JB10',
 VALUE='4.7K',
 PRIM_FILE='./archive_libs/logical/q_res/chips/chips.prt';

PART_NAME
 R4554 'Q_RES_0402LF-100K,1%,1/16W,CHIP,CS41002FB09':;

SECTION_NUMBER 1
 '@T6G_MB_LIB.T6G(SCH_1):PAGE364_I59@PURE_QUANTA.Q_RES(CHIPS)':
 C_PATH='@t6g_mb_lib.t6g(sch_1):page364_i59@pure_quanta.q_res(chips)',
 P_PATH='@t6g_mb_lib.t6g(sch_1):page241_i59@pure_quanta.q_res(chips)',
 PATH='I59',
 DRAWING='@T6G_MB_LIB.T6G(SCH_1):PAGE364',
 WATTAGE='1/16W',
 TOLERANCE='1%',
 MATERIAL='CHIP',
 PHYS_PAGE='241',
 XY='(1200,-1300)',
 ROT='0',
 VER='2',
 PACK_TYPE='0402LF',
 LOCATION='R4554',
 CDS_LIB='pure_quanta',
 CDS_PART_NAME='Q_RES_0402LF-100K,1%,1/16W,CHIP,CS41002FB09',
 PART_NUMBER='CS41002FB09',
 VALUE='100K',
 PRIM_FILE='./archive_libs/logical/q_res/chips/chips.prt';

PART_NAME
 R4555 'Q_RES_0402LF-4.7K,5%,1/16W,EMPTY,CS24702JB10':;

SECTION_NUMBER 1
 '@T6G_MB_LIB.T6G(SCH_1):PAGE331_I99@PURE_QUANTA.Q_RES(CHIPS)':
 C_PATH='@t6g_mb_lib.t6g(sch_1):page331_i99@pure_quanta.q_res(chips)',
 P_PATH='@t6g_mb_lib.t6g(sch_1):page124_i99@pure_quanta.q_res(chips)',
 PATH='I99',
 DRAWING='@T6G_MB_LIB.T6G(SCH_1):PAGE331',
 WATTAGE='1/16W',
 TOLERANCE='5%',
 MATERIAL='EMPTY',
 PHYS_PAGE='124',
 XY='(5175,5000)',
 ROT='0',
 VER='2',
 PACK_TYPE='0402LF',
 LOCATION='R4555',
 CDS_LIB='pure_quanta',
 CDS_PART_NAME='Q_RES_0402LF-4.7K,5%,1/16W,EMPTY,CS24702JB10',
 PART_NUMBER='CS24702JB10',
 VALUE='4.7K',
 PRIM_FILE='./archive_libs/logical/q_res/chips/chips.prt';

PART_NAME
 R4556 'Q_RES_0402LF-33.2,1%,1/16W,CHIP,CS03322FB03':;

SECTION_NUMBER 1
 '@T6G_MB_LIB.T6G(SCH_1):PAGE80_I226@PURE_QUANTA.Q_RES(CHIPS)':
 C_PATH='@t6g_mb_lib.t6g(sch_1):page80_i226@pure_quanta.q_res(chips)',
 P_PATH='@t6g_mb_lib.t6g(sch_1):page81_i226@pure_quanta.q_res(chips)',
 PATH='I226',
 DRAWING='@T6G_MB_LIB.T6G(SCH_1):PAGE80',
 WATTAGE='1/16W',
 TOLERANCE='1%',
 MATERIAL='CHIP',
 PHYS_PAGE='81',
 XY='(-2300,2825)',
 ROT='0',
 VER='1',
 PACK_TYPE='0402LF',
 LOCATION='R4556',
 CDS_LIB='pure_quanta',
 CDS_PART_NAME='Q_RES_0402LF-33.2,1%,1/16W,CHIP,CS03322FB03',
 PART_NUMBER='CS03322FB03',
 VALUE='33.2',
 PRIM_FILE='./archive_libs/logical/q_res/chips/chips.prt';

PART_NAME
 R4557 'Q_RES_0402LF-33.2,1%,1/16W,CHIP,CS03322FB03':;

SECTION_NUMBER 1
 '@T6G_MB_LIB.T6G(SCH_1):PAGE80_I301@PURE_QUANTA.Q_RES(CHIPS)':
 C_PATH='@t6g_mb_lib.t6g(sch_1):page80_i301@pure_quanta.q_res(chips)',
 P_PATH='@t6g_mb_lib.t6g(sch_1):page81_i301@pure_quanta.q_res(chips)',
 PATH='I301',
 DRAWING='@T6G_MB_LIB.T6G(SCH_1):PAGE80',
 WATTAGE='1/16W',
 TOLERANCE='1%',
 MATERIAL='CHIP',
 PHYS_PAGE='81',
 XY='(-6725,675)',
 ROT='0',
 VER='1',
 PACK_TYPE='0402LF',
 LOCATION='R4557',
 CDS_LIB='pure_quanta',
 CDS_PART_NAME='Q_RES_0402LF-33.2,1%,1/16W,CHIP,CS03322FB03',
 PART_NUMBER='CS03322FB03',
 VALUE='33.2',
 PRIM_FILE='./archive_libs/logical/q_res/chips/chips.prt';

PART_NAME
 R4558 'Q_RES_0402LF-33.2,1%,1/16W,CHIP,CS03322FB03':;

SECTION_NUMBER 1
 '@T6G_MB_LIB.T6G(SCH_1):PAGE80_I228@PURE_QUANTA.Q_RES(CHIPS)':
 C_PATH='@t6g_mb_lib.t6g(sch_1):page80_i228@pure_quanta.q_res(chips)',
 P_PATH='@t6g_mb_lib.t6g(sch_1):page81_i228@pure_quanta.q_res(chips)',
 PATH='I228',
 DRAWING='@T6G_MB_LIB.T6G(SCH_1):PAGE80',
 WATTAGE='1/16W',
 TOLERANCE='1%',
 MATERIAL='CHIP',
 PHYS_PAGE='81',
 XY='(-2300,2675)',
 ROT='0',
 VER='1',
 PACK_TYPE='0402LF',
 LOCATION='R4558',
 CDS_LIB='pure_quanta',
 CDS_PART_NAME='Q_RES_0402LF-33.2,1%,1/16W,CHIP,CS03322FB03',
 PART_NUMBER='CS03322FB03',
 VALUE='33.2',
 PRIM_FILE='./archive_libs/logical/q_res/chips/chips.prt';

PART_NAME
 R4559 'Q_RES_0402LF-100K,1%,1/16W,CHIP,CS41002FB09':;

SECTION_NUMBER 1
 '@T6G_MB_LIB.T6G(SCH_1):PAGE332_I54@PURE_QUANTA.Q_RES(CHIPS)':
 C_PATH='@t6g_mb_lib.t6g(sch_1):page332_i54@pure_quanta.q_res(chips)',
 P_PATH='@t6g_mb_lib.t6g(sch_1):page125_i54@pure_quanta.q_res(chips)',
 PATH='I54',
 DRAWING='@T6G_MB_LIB.T6G(SCH_1):PAGE332',
 WATTAGE='1/16W',
 TOLERANCE='1%',
 MATERIAL='CHIP',
 PHYS_PAGE='125',
 XY='(2500,-825)',
 ROT='0',
 VER='2',
 PACK_TYPE='0402LF',
 LOCATION='R4559',
 CDS_LIB='pure_quanta',
 CDS_PART_NAME='Q_RES_0402LF-100K,1%,1/16W,CHIP,CS41002FB09',
 PART_NUMBER='CS41002FB09',
 VALUE='100K',
 PRIM_FILE='./archive_libs/logical/q_res/chips/chips.prt';

PART_NAME
 R4560 'Q_RES_0402LF-4.7K,5%,1/16W,CHIP,CS24702JB10':;

SECTION_NUMBER 1
 '@T6G_MB_LIB.T6G(SCH_1):PAGE332_I62@PURE_QUANTA.Q_RES(CHIPS)':
 C_PATH='@t6g_mb_lib.t6g(sch_1):page332_i62@pure_quanta.q_res(chips)',
 P_PATH='@t6g_mb_lib.t6g(sch_1):page125_i62@pure_quanta.q_res(chips)',
 PATH='I62',
 DRAWING='@T6G_MB_LIB.T6G(SCH_1):PAGE332',
 WATTAGE='1/16W',
 TOLERANCE='5%',
 MATERIAL='CHIP',
 PHYS_PAGE='125',
 XY='(3650,25)',
 ROT='0',
 VER='2',
 PACK_TYPE='0402LF',
 LOCATION='R4560',
 CDS_LIB='pure_quanta',
 CDS_PART_NAME='Q_RES_0402LF-4.7K,5%,1/16W,CHIP,CS24702JB10',
 PART_NUMBER='CS24702JB10',
 VALUE='4.7K',
 PRIM_FILE='./archive_libs/logical/q_res/chips/chips.prt';

PART_NAME
 R4561 'Q_RES_0402LF-100K,1%,1/16W,CHIP,CS41002FB09':;

SECTION_NUMBER 1
 '@T6G_MB_LIB.T6G(SCH_1):PAGE332_I110@PURE_QUANTA.Q_RES(CHIPS)':
 C_PATH='@t6g_mb_lib.t6g(sch_1):page332_i110@pure_quanta.q_res(chips)',
 P_PATH='@t6g_mb_lib.t6g(sch_1):page125_i110@pure_quanta.q_res(chips)',
 PATH='I110',
 DRAWING='@T6G_MB_LIB.T6G(SCH_1):PAGE332',
 WATTAGE='1/16W',
 TOLERANCE='1%',
 MATERIAL='CHIP',
 PHYS_PAGE='125',
 XY='(4800,150)',
 ROT='0',
 VER='2',
 PACK_TYPE='0402LF',
 LOCATION='R4561',
 CDS_LIB='pure_quanta',
 CDS_PART_NAME='Q_RES_0402LF-100K,1%,1/16W,CHIP,CS41002FB09',
 PART_NUMBER='CS41002FB09',
 VALUE='100K',
 PRIM_FILE='./archive_libs/logical/q_res/chips/chips.prt';

PART_NAME
 R4562 'Q_RES_0402LF-100K,1%,1/16W,EMPTY,CS41002FB09':;

SECTION_NUMBER 1
 '@T6G_MB_LIB.T6G(SCH_1):PAGE332_I55@PURE_QUANTA.Q_RES(CHIPS)':
 C_PATH='@t6g_mb_lib.t6g(sch_1):page332_i55@pure_quanta.q_res(chips)',
 P_PATH='@t6g_mb_lib.t6g(sch_1):page125_i55@pure_quanta.q_res(chips)',
 PATH='I55',
 DRAWING='@T6G_MB_LIB.T6G(SCH_1):PAGE332',
 WATTAGE='1/16W',
 TOLERANCE='1%',
 MATERIAL='EMPTY',
 PHYS_PAGE='125',
 XY='(2475,-350)',
 ROT='0',
 VER='2',
 PACK_TYPE='0402LF',
 LOCATION='R4562',
 CDS_LIB='pure_quanta',
 CDS_PART_NAME='Q_RES_0402LF-100K,1%,1/16W,EMPTY,CS41002FB09',
 PART_NUMBER='CS41002FB09',
 VALUE='100K',
 PRIM_FILE='./archive_libs/logical/q_res/chips/chips.prt';

PART_NAME
 R4563 'Q_RES_0402LF-33.2,1%,1/16W,CHIP,CS03322FB03':;

SECTION_NUMBER 1
 '@T6G_MB_LIB.T6G(SCH_1):PAGE80_I243@PURE_QUANTA.Q_RES(CHIPS)':
 C_PATH='@t6g_mb_lib.t6g(sch_1):page80_i243@pure_quanta.q_res(chips)',
 P_PATH='@t6g_mb_lib.t6g(sch_1):page81_i243@pure_quanta.q_res(chips)',
 PATH='I243',
 DRAWING='@T6G_MB_LIB.T6G(SCH_1):PAGE80',
 WATTAGE='1/16W',
 TOLERANCE='1%',
 MATERIAL='CHIP',
 PHYS_PAGE='81',
 XY='(-2300,2275)',
 ROT='0',
 VER='1',
 PACK_TYPE='0402LF',
 LOCATION='R4563',
 CDS_LIB='pure_quanta',
 CDS_PART_NAME='Q_RES_0402LF-33.2,1%,1/16W,CHIP,CS03322FB03',
 PART_NUMBER='CS03322FB03',
 VALUE='33.2',
 PRIM_FILE='./archive_libs/logical/q_res/chips/chips.prt';

PART_NAME
 R4567 'Q_RES_0402LF-5.11K,1%,1/16W,CHIP,CS25112FB04':;

SECTION_NUMBER 1
 '@T6G_MB_LIB.T6G(SCH_1):PAGE369_I8@PURE_QUANTA.Q_RES(CHIPS)':
 C_PATH='@t6g_mb_lib.t6g(sch_1):page369_i8@pure_quanta.q_res(chips)',
 P_PATH='@t6g_mb_lib.t6g(sch_1):page257_i8@pure_quanta.q_res(chips)',
 PATH='I8',
 DRAWING='@T6G_MB_LIB.T6G(SCH_1):PAGE369',
 WATTAGE='1/16W',
 TOLERANCE='1%',
 MATERIAL='CHIP',
 PHYS_PAGE='257',
 XY='(-8375,1325)',
 ROT='0',
 VER='2',
 PACK_TYPE='0402LF',
 LOCATION='R4567',
 CDS_LIB='pure_quanta',
 CDS_PART_NAME='Q_RES_0402LF-5.11K,1%,1/16W,CHIP,CS25112FB04',
 PART_NUMBER='CS25112FB04',
 VALUE='5.11K',
 PRIM_FILE='./archive_libs/logical/q_res/chips/chips.prt';

PART_NAME
 R4568 'Q_RES_0402LF-4.7K,1%,1/16W,CHIP,CS24702FB06':;

SECTION_NUMBER 1
 '@T6G_MB_LIB.T6G(SCH_1):PAGE369_I7@PURE_QUANTA.Q_RES(CHIPS)':
 C_PATH='@t6g_mb_lib.t6g(sch_1):page369_i7@pure_quanta.q_res(chips)',
 P_PATH='@t6g_mb_lib.t6g(sch_1):page257_i7@pure_quanta.q_res(chips)',
 PATH='I7',
 DRAWING='@T6G_MB_LIB.T6G(SCH_1):PAGE369',
 WATTAGE='1/16W',
 TOLERANCE='1%',
 MATERIAL='CHIP',
 PHYS_PAGE='257',
 XY='(-8375,950)',
 ROT='0',
 VER='2',
 PACK_TYPE='0402LF',
 LOCATION='R4568',
 CDS_LIB='pure_quanta',
 CDS_PART_NAME='Q_RES_0402LF-4.7K,1%,1/16W,CHIP,CS24702FB06',
 PART_NUMBER='CS24702FB06',
 VALUE='4.7K',
 PRIM_FILE='./archive_libs/logical/q_res/chips/chips.prt';

PART_NAME
 R4569 'Q_RES_0402LF-0,5%,1/16W,EMPTY,CS00002JB13':;

SECTION_NUMBER 1
 '@T6G_MB_LIB.T6G(SCH_1):PAGE331_I107@PURE_QUANTA.Q_RES(CHIPS)':
 C_PATH='@t6g_mb_lib.t6g(sch_1):page331_i107@pure_quanta.q_res(chips)',
 P_PATH='@t6g_mb_lib.t6g(sch_1):page124_i107@pure_quanta.q_res(chips)',
 PATH='I107',
 DRAWING='@T6G_MB_LIB.T6G(SCH_1):PAGE331',
 WATTAGE='1/16W',
 TOLERANCE='5%',
 MATERIAL='EMPTY',
 PHYS_PAGE='124',
 XY='(-650,6050)',
 ROT='0',
 VER='1',
 PACK_TYPE='0402LF',
 LOCATION='R4569',
 CDS_LIB='pure_quanta',
 CDS_PART_NAME='Q_RES_0402LF-0,5%,1/16W,EMPTY,CS00002JB13',
 PART_NUMBER='CS00002JB13',
 VALUE='0',
 PRIM_FILE='./archive_libs/logical/q_res/chips/chips.prt';

PART_NAME
 R4570 'Q_RES_0402LF-0,5%,1/16W,EMPTY,CS00002JB13':;

SECTION_NUMBER 1
 '@T6G_MB_LIB.T6G(SCH_1):PAGE331_I109@PURE_QUANTA.Q_RES(CHIPS)':
 C_PATH='@t6g_mb_lib.t6g(sch_1):page331_i109@pure_quanta.q_res(chips)',
 P_PATH='@t6g_mb_lib.t6g(sch_1):page124_i109@pure_quanta.q_res(chips)',
 PATH='I109',
 DRAWING='@T6G_MB_LIB.T6G(SCH_1):PAGE331',
 WATTAGE='1/16W',
 TOLERANCE='5%',
 MATERIAL='EMPTY',
 PHYS_PAGE='124',
 XY='(-425,4575)',
 ROT='0',
 VER='1',
 PACK_TYPE='0402LF',
 LOCATION='R4570',
 CDS_LIB='pure_quanta',
 CDS_PART_NAME='Q_RES_0402LF-0,5%,1/16W,EMPTY,CS00002JB13',
 PART_NUMBER='CS00002JB13',
 VALUE='0',
 PRIM_FILE='./archive_libs/logical/q_res/chips/chips.prt';

PART_NAME
 R4571 'Q_RES_0402LF-0,5%,1/16W,EMPTY,CS00002JB13':;

SECTION_NUMBER 1
 '@T6G_MB_LIB.T6G(SCH_1):PAGE331_I108@PURE_QUANTA.Q_RES(CHIPS)':
 C_PATH='@t6g_mb_lib.t6g(sch_1):page331_i108@pure_quanta.q_res(chips)',
 P_PATH='@t6g_mb_lib.t6g(sch_1):page124_i108@pure_quanta.q_res(chips)',
 PATH='I108',
 DRAWING='@T6G_MB_LIB.T6G(SCH_1):PAGE331',
 WATTAGE='1/16W',
 TOLERANCE='5%',
 MATERIAL='EMPTY',
 PHYS_PAGE='124',
 XY='(-425,3125)',
 ROT='0',
 VER='1',
 PACK_TYPE='0402LF',
 LOCATION='R4571',
 CDS_LIB='pure_quanta',
 CDS_PART_NAME='Q_RES_0402LF-0,5%,1/16W,EMPTY,CS00002JB13',
 PART_NUMBER='CS00002JB13',
 VALUE='0',
 PRIM_FILE='./archive_libs/logical/q_res/chips/chips.prt';

PART_NAME
 R4572 'Q_RES_0402LF-0,5%,1/16W,EMPTY,CS00002JB13':;

SECTION_NUMBER 1
 '@T6G_MB_LIB.T6G(SCH_1):PAGE332_I41@PURE_QUANTA.Q_RES(CHIPS)':
 C_PATH='@t6g_mb_lib.t6g(sch_1):page332_i41@pure_quanta.q_res(chips)',
 P_PATH='@t6g_mb_lib.t6g(sch_1):page125_i41@pure_quanta.q_res(chips)',
 PATH='I41',
 DRAWING='@T6G_MB_LIB.T6G(SCH_1):PAGE332',
 WATTAGE='1/16W',
 TOLERANCE='5%',
 MATERIAL='EMPTY',
 PHYS_PAGE='125',
 XY='(-700,3025)',
 ROT='0',
 VER='1',
 PACK_TYPE='0402LF',
 LOCATION='R4572',
 CDS_LIB='pure_quanta',
 CDS_PART_NAME='Q_RES_0402LF-0,5%,1/16W,EMPTY,CS00002JB13',
 PART_NUMBER='CS00002JB13',
 VALUE='0',
 PRIM_FILE='./archive_libs/logical/q_res/chips/chips.prt';

PART_NAME
 R4573 'Q_RES_0402LF-0,5%,1/16W,EMPTY,CS00002JB13':;

SECTION_NUMBER 1
 '@T6G_MB_LIB.T6G(SCH_1):PAGE332_I33@PURE_QUANTA.Q_RES(CHIPS)':
 C_PATH='@t6g_mb_lib.t6g(sch_1):page332_i33@pure_quanta.q_res(chips)',
 P_PATH='@t6g_mb_lib.t6g(sch_1):page125_i33@pure_quanta.q_res(chips)',
 PATH='I33',
 DRAWING='@T6G_MB_LIB.T6G(SCH_1):PAGE332',
 WATTAGE='1/16W',
 TOLERANCE='5%',
 MATERIAL='EMPTY',
 PHYS_PAGE='125',
 XY='(-700,1575)',
 ROT='0',
 VER='1',
 PACK_TYPE='0402LF',
 LOCATION='R4573',
 CDS_LIB='pure_quanta',
 CDS_PART_NAME='Q_RES_0402LF-0,5%,1/16W,EMPTY,CS00002JB13',
 PART_NUMBER='CS00002JB13',
 VALUE='0',
 PRIM_FILE='./archive_libs/logical/q_res/chips/chips.prt';

PART_NAME
 R4574 'Q_RES_0402LF-0,5%,1/16W,EMPTY,CS00002JB13':;

SECTION_NUMBER 1
 '@T6G_MB_LIB.T6G(SCH_1):PAGE332_I31@PURE_QUANTA.Q_RES(CHIPS)':
 C_PATH='@t6g_mb_lib.t6g(sch_1):page332_i31@pure_quanta.q_res(chips)',
 P_PATH='@t6g_mb_lib.t6g(sch_1):page125_i31@pure_quanta.q_res(chips)',
 PATH='I31',
 DRAWING='@T6G_MB_LIB.T6G(SCH_1):PAGE332',
 WATTAGE='1/16W',
 TOLERANCE='5%',
 MATERIAL='EMPTY',
 PHYS_PAGE='125',
 XY='(-625,25)',
 ROT='0',
 VER='1',
 PACK_TYPE='0402LF',
 LOCATION='R4574',
 CDS_LIB='pure_quanta',
 CDS_PART_NAME='Q_RES_0402LF-0,5%,1/16W,EMPTY,CS00002JB13',
 PART_NUMBER='CS00002JB13',
 VALUE='0',
 PRIM_FILE='./archive_libs/logical/q_res/chips/chips.prt';

PART_NAME
 R4575 'Q_RES_0402LF-0,5%,1/16W,EMPTY,CS00002JB13':;

SECTION_NUMBER 1
 '@T6G_MB_LIB.T6G(SCH_1):PAGE332_I44@PURE_QUANTA.Q_RES(CHIPS)':
 C_PATH='@t6g_mb_lib.t6g(sch_1):page332_i44@pure_quanta.q_res(chips)',
 P_PATH='@t6g_mb_lib.t6g(sch_1):page125_i44@pure_quanta.q_res(chips)',
 PATH='I44',
 DRAWING='@T6G_MB_LIB.T6G(SCH_1):PAGE332',
 WATTAGE='1/16W',
 TOLERANCE='5%',
 MATERIAL='EMPTY',
 PHYS_PAGE='125',
 XY='(-575,4475)',
 ROT='0',
 VER='1',
 PACK_TYPE='0402LF',
 LOCATION='R4575',
 CDS_LIB='pure_quanta',
 CDS_PART_NAME='Q_RES_0402LF-0,5%,1/16W,EMPTY,CS00002JB13',
 PART_NUMBER='CS00002JB13',
 VALUE='0',
 PRIM_FILE='./archive_libs/logical/q_res/chips/chips.prt';

PART_NAME
 R4576 'Q_RES_0402LF-0,5%,1/16W,EMPTY,CS00002JB13':;

SECTION_NUMBER 1
 '@T6G_MB_LIB.T6G(SCH_1):PAGE332_I91@PURE_QUANTA.Q_RES(CHIPS)':
 C_PATH='@t6g_mb_lib.t6g(sch_1):page332_i91@pure_quanta.q_res(chips)',
 P_PATH='@t6g_mb_lib.t6g(sch_1):page125_i91@pure_quanta.q_res(chips)',
 PATH='I91',
 DRAWING='@T6G_MB_LIB.T6G(SCH_1):PAGE332',
 WATTAGE='1/16W',
 TOLERANCE='5%',
 MATERIAL='EMPTY',
 PHYS_PAGE='125',
 XY='(3925,1875)',
 ROT='0',
 VER='1',
 PACK_TYPE='0402LF',
 LOCATION='R4576',
 CDS_LIB='pure_quanta',
 CDS_PART_NAME='Q_RES_0402LF-0,5%,1/16W,EMPTY,CS00002JB13',
 PART_NUMBER='CS00002JB13',
 VALUE='0',
 PRIM_FILE='./archive_libs/logical/q_res/chips/chips.prt';

PART_NAME
 R4577 'Q_RES_0402LF-0,5%,1/16W,EMPTY,CS00002JB13':;

SECTION_NUMBER 1
 '@T6G_MB_LIB.T6G(SCH_1):PAGE332_I109@PURE_QUANTA.Q_RES(CHIPS)':
 C_PATH='@t6g_mb_lib.t6g(sch_1):page332_i109@pure_quanta.q_res(chips)',
 P_PATH='@t6g_mb_lib.t6g(sch_1):page125_i109@pure_quanta.q_res(chips)',
 PATH='I109',
 DRAWING='@T6G_MB_LIB.T6G(SCH_1):PAGE332',
 WATTAGE='1/16W',
 TOLERANCE='5%',
 MATERIAL='EMPTY',
 PHYS_PAGE='125',
 XY='(3950,4700)',
 ROT='0',
 VER='1',
 PACK_TYPE='0402LF',
 LOCATION='R4577',
 CDS_LIB='pure_quanta',
 CDS_PART_NAME='Q_RES_0402LF-0,5%,1/16W,EMPTY,CS00002JB13',
 PART_NUMBER='CS00002JB13',
 VALUE='0',
 PRIM_FILE='./archive_libs/logical/q_res/chips/chips.prt';

PART_NAME
 R4578 'Q_RES_0402LF-0,5%,1/16W,EMPTY,CS00002JB13':;

SECTION_NUMBER 1
 '@T6G_MB_LIB.T6G(SCH_1):PAGE332_I103@PURE_QUANTA.Q_RES(CHIPS)':
 C_PATH='@t6g_mb_lib.t6g(sch_1):page332_i103@pure_quanta.q_res(chips)',
 P_PATH='@t6g_mb_lib.t6g(sch_1):page125_i103@pure_quanta.q_res(chips)',
 PATH='I103',
 DRAWING='@T6G_MB_LIB.T6G(SCH_1):PAGE332',
 WATTAGE='1/16W',
 TOLERANCE='5%',
 MATERIAL='EMPTY',
 PHYS_PAGE='125',
 XY='(4000,3325)',
 ROT='0',
 VER='1',
 PACK_TYPE='0402LF',
 LOCATION='R4578',
 CDS_LIB='pure_quanta',
 CDS_PART_NAME='Q_RES_0402LF-0,5%,1/16W,EMPTY,CS00002JB13',
 PART_NUMBER='CS00002JB13',
 VALUE='0',
 PRIM_FILE='./archive_libs/logical/q_res/chips/chips.prt';

PART_NAME
 R4601 'Q_RES_0402LF-0,5%,1/16W,CHIP,CS00002JB13':;

SECTION_NUMBER 1
 '@T6G_MB_LIB.T6G(SCH_1):PAGE337_I29@PURE_QUANTA.Q_RES(CHIPS)':
 C_PATH='@t6g_mb_lib.t6g(sch_1):page337_i29@pure_quanta.q_res(chips)',
 P_PATH='@t6g_mb_lib.t6g(sch_1):page133_i29@pure_quanta.q_res(chips)',
 PATH='I29',
 DRAWING='@T6G_MB_LIB.T6G(SCH_1):PAGE337',
 WATTAGE='1/16W',
 TOLERANCE='5%',
 MATERIAL='CHIP',
 PHYS_PAGE='133',
 XY='(-4625,3275)',
 ROT='0',
 VER='1',
 PACK_TYPE='0402LF',
 LOCATION='R4601',
 CDS_LIB='pure_quanta',
 CDS_PART_NAME='Q_RES_0402LF-0,5%,1/16W,CHIP,CS00002JB13',
 PART_NUMBER='CS00002JB13',
 VALUE='0',
 PRIM_FILE='./archive_libs/logical/q_res/chips/chips.prt';

PART_NAME
 R4602 'Q_RES_0402LF-0,5%,1/16W,CHIP,CS00002JB13':;

SECTION_NUMBER 1
 '@T6G_MB_LIB.T6G(SCH_1):PAGE342_I36@PURE_QUANTA.Q_RES(CHIPS)':
 C_PATH='@t6g_mb_lib.t6g(sch_1):page342_i36@pure_quanta.q_res(chips)',
 P_PATH='@t6g_mb_lib.t6g(sch_1):page139_i36@pure_quanta.q_res(chips)',
 PATH='I36',
 DRAWING='@T6G_MB_LIB.T6G(SCH_1):PAGE342',
 WATTAGE='1/16W',
 TOLERANCE='5%',
 MATERIAL='CHIP',
 PHYS_PAGE='139',
 XY='(8575,-3425)',
 ROT='0',
 VER='1',
 PACK_TYPE='0402LF',
 LOCATION='R4602',
 CDS_LIB='pure_quanta',
 CDS_PART_NAME='Q_RES_0402LF-0,5%,1/16W,CHIP,CS00002JB13',
 PART_NUMBER='CS00002JB13',
 VALUE='0',
 PRIM_FILE='./archive_libs/logical/q_res/chips/chips.prt';

PART_NAME
 R4603 'Q_RES_0402LF-10K,1%,1/16W,CHIP,CS31002FB08':;

SECTION_NUMBER 1
 '@T6G_MB_LIB.T6G(SCH_1):PAGE249_I23@PURE_QUANTA.Q_RES(CHIPS)':
 C_PATH='@t6g_mb_lib.t6g(sch_1):page249_i23@pure_quanta.q_res(chips)',
 P_PATH='@t6g_mb_lib.t6g(sch_1):page248_i23@pure_quanta.q_res(chips)',
 PATH='I23',
 DRAWING='@T6G_MB_LIB.T6G(SCH_1):PAGE249',
 WATTAGE='1/16W',
 TOLERANCE='1%',
 MATERIAL='CHIP',
 PHYS_PAGE='248',
 XY='(-6700,3675)',
 ROT='0',
 VER='2',
 PACK_TYPE='0402LF',
 LOCATION='R4603',
 CDS_LIB='pure_quanta',
 CDS_PART_NAME='Q_RES_0402LF-10K,1%,1/16W,CHIP,CS31002FB08',
 PART_NUMBER='CS31002FB08',
 VALUE='10K',
 PRIM_FILE='./archive_libs/logical/q_res/chips/chips.prt';

PART_NAME
 R4604 'Q_RES_0402LF-4.7K,5%,1/16W,CHIP,CS24702JB10':;

SECTION_NUMBER 1
 '@T6G_MB_LIB.T6G(SCH_1):PAGE368_I5@PURE_QUANTA.Q_RES(CHIPS)':
 C_PATH='@t6g_mb_lib.t6g(sch_1):page368_i5@pure_quanta.q_res(chips)',
 P_PATH='@t6g_mb_lib.t6g(sch_1):page253_i5@pure_quanta.q_res(chips)',
 PATH='I5',
 DRAWING='@T6G_MB_LIB.T6G(SCH_1):PAGE368',
 WATTAGE='1/16W',
 TOLERANCE='5%',
 MATERIAL='CHIP',
 PHYS_PAGE='253',
 XY='(-5925,4500)',
 ROT='0',
 VER='2',
 PACK_TYPE='0402LF',
 LOCATION='R4604',
 CDS_LIB='pure_quanta',
 CDS_PART_NAME='Q_RES_0402LF-4.7K,5%,1/16W,CHIP,CS24702JB10',
 PART_NUMBER='CS24702JB10',
 VALUE='4.7K',
 PRIM_FILE='./archive_libs/logical/q_res/chips/chips.prt';

PART_NAME
 R4605 'Q_RES_0402LF-1K,1%,1/16W,CHIP,CS21002FB06':;

SECTION_NUMBER 1
 '@T6G_MB_LIB.T6G(SCH_1):PAGE368_I11@PURE_QUANTA.Q_RES(CHIPS)':
 C_PATH='@t6g_mb_lib.t6g(sch_1):page368_i11@pure_quanta.q_res(chips)',
 P_PATH='@t6g_mb_lib.t6g(sch_1):page253_i11@pure_quanta.q_res(chips)',
 PATH='I11',
 DRAWING='@T6G_MB_LIB.T6G(SCH_1):PAGE368',
 WATTAGE='1/16W',
 TOLERANCE='1%',
 MATERIAL='CHIP',
 PHYS_PAGE='253',
 XY='(-4775,4625)',
 ROT='0',
 VER='2',
 PACK_TYPE='0402LF',
 LOCATION='R4605',
 CDS_LIB='pure_quanta',
 CDS_PART_NAME='Q_RES_0402LF-1K,1%,1/16W,CHIP,CS21002FB06',
 PART_NUMBER='CS21002FB06',
 VALUE='1K',
 PRIM_FILE='./archive_libs/logical/q_res/chips/chips.prt';

PART_NAME
 R4608 'Q_RES_0402LF-33.2,1%,1/16W,CHIP,CS03322FB03':;

SECTION_NUMBER 1
 '@T6G_MB_LIB.T6G(SCH_1):PAGE80_I295@PURE_QUANTA.Q_RES(CHIPS)':
 C_PATH='@t6g_mb_lib.t6g(sch_1):page80_i295@pure_quanta.q_res(chips)',
 P_PATH='@t6g_mb_lib.t6g(sch_1):page81_i295@pure_quanta.q_res(chips)',
 PATH='I295',
 DRAWING='@T6G_MB_LIB.T6G(SCH_1):PAGE80',
 WATTAGE='1/16W',
 TOLERANCE='1%',
 MATERIAL='CHIP',
 PHYS_PAGE='81',
 XY='(-6725,2225)',
 ROT='0',
 VER='1',
 PACK_TYPE='0402LF',
 LOCATION='R4608',
 CDS_LIB='pure_quanta',
 CDS_PART_NAME='Q_RES_0402LF-33.2,1%,1/16W,CHIP,CS03322FB03',
 PART_NUMBER='CS03322FB03',
 VALUE='33.2',
 PRIM_FILE='./archive_libs/logical/q_res/chips/chips.prt';

PART_NAME
 R4620 'Q_RES_0402LF-1K,1%,1/16W,EMPTY,CS21002FB06':;

SECTION_NUMBER 1
 '@T6G_MB_LIB.T6G(SCH_1):PAGE372_I46@PURE_QUANTA.Q_RES(CHIPS)':
 C_PATH='@t6g_mb_lib.t6g(sch_1):page372_i46@pure_quanta.q_res(chips)',
 P_PATH='@t6g_mb_lib.t6g(sch_1):page268_i46@pure_quanta.q_res(chips)',
 PATH='I46',
 DRAWING='@T6G_MB_LIB.T6G(SCH_1):PAGE372',
 WATTAGE='1/16W',
 TOLERANCE='1%',
 MATERIAL='EMPTY',
 PHYS_PAGE='268',
 XY='(-1625,5725)',
 ROT='0',
 VER='2',
 PACK_TYPE='0402LF',
 LOCATION='R4620',
 CDS_LIB='pure_quanta',
 CDS_PART_NAME='Q_RES_0402LF-1K,1%,1/16W,EMPTY,CS21002FB06',
 PART_NUMBER='CS21002FB06',
 VALUE='1K',
 PRIM_FILE='./archive_libs/logical/q_res/chips/chips.prt';

PART_NAME
 R4638 'Q_RES_1206LF-243,1%,1/4W,CHIP,CS12436F201':;

SECTION_NUMBER 1
 '@T6G_MB_LIB.T6G(SCH_1):PAGE273_I45@PURE_QUANTA.Q_RES(CHIPS)':
 C_PATH='@t6g_mb_lib.t6g(sch_1):page273_i45@pure_quanta.q_res(chips)',
 P_PATH='@t6g_mb_lib.t6g(sch_1):page188_i45@pure_quanta.q_res(chips)',
 PATH='I45',
 DRAWING='@T6G_MB_LIB.T6G(SCH_1):PAGE273',
 WATTAGE='1/4W',
 TOLERANCE='1%',
 MATERIAL='CHIP',
 PHYS_PAGE='188',
 XY='(-2350,7275)',
 ROT='0',
 VER='2',
 PACK_TYPE='1206LF',
 LOCATION='R4638',
 CDS_LIB='pure_quanta',
 CDS_PART_NAME='Q_RES_1206LF-243,1%,1/4W,CHIP,CS12436F201',
 PART_NUMBER='CS12436F201',
 VALUE='243',
 PRIM_FILE='./archive_libs/logical/q_res/chips/chips.prt';

PART_NAME
 R4639 'Q_RES_1206LF-243,1%,1/4W,CHIP,CS12436F201':;

SECTION_NUMBER 1
 '@T6G_MB_LIB.T6G(SCH_1):PAGE273_I74@PURE_QUANTA.Q_RES(CHIPS)':
 C_PATH='@t6g_mb_lib.t6g(sch_1):page273_i74@pure_quanta.q_res(chips)',
 P_PATH='@t6g_mb_lib.t6g(sch_1):page188_i74@pure_quanta.q_res(chips)',
 PATH='I74',
 DRAWING='@T6G_MB_LIB.T6G(SCH_1):PAGE273',
 WATTAGE='1/4W',
 TOLERANCE='1%',
 MATERIAL='CHIP',
 PHYS_PAGE='188',
 XY='(-1750,7275)',
 ROT='0',
 VER='2',
 PACK_TYPE='1206LF',
 LOCATION='R4639',
 CDS_LIB='pure_quanta',
 CDS_PART_NAME='Q_RES_1206LF-243,1%,1/4W,CHIP,CS12436F201',
 PART_NUMBER='CS12436F201',
 VALUE='243',
 PRIM_FILE='./archive_libs/logical/q_res/chips/chips.prt';

PART_NAME
 R4640 'Q_RES_1206LF-243,1%,1/4W,CHIP,CS12436F201':;

SECTION_NUMBER 1
 '@T6G_MB_LIB.T6G(SCH_1):PAGE273_I75@PURE_QUANTA.Q_RES(CHIPS)':
 C_PATH='@t6g_mb_lib.t6g(sch_1):page273_i75@pure_quanta.q_res(chips)',
 P_PATH='@t6g_mb_lib.t6g(sch_1):page188_i75@pure_quanta.q_res(chips)',
 PATH='I75',
 DRAWING='@T6G_MB_LIB.T6G(SCH_1):PAGE273',
 WATTAGE='1/4W',
 TOLERANCE='1%',
 MATERIAL='CHIP',
 PHYS_PAGE='188',
 XY='(-1175,7275)',
 ROT='0',
 VER='2',
 PACK_TYPE='1206LF',
 LOCATION='R4640',
 CDS_LIB='pure_quanta',
 CDS_PART_NAME='Q_RES_1206LF-243,1%,1/4W,CHIP,CS12436F201',
 PART_NUMBER='CS12436F201',
 VALUE='243',
 PRIM_FILE='./archive_libs/logical/q_res/chips/chips.prt';

PART_NAME
 R4641 'Q_RES_1206LF-243,1%,1/4W,CHIP,CS12436F201':;

SECTION_NUMBER 1
 '@T6G_MB_LIB.T6G(SCH_1):PAGE273_I76@PURE_QUANTA.Q_RES(CHIPS)':
 C_PATH='@t6g_mb_lib.t6g(sch_1):page273_i76@pure_quanta.q_res(chips)',
 P_PATH='@t6g_mb_lib.t6g(sch_1):page188_i76@pure_quanta.q_res(chips)',
 PATH='I76',
 DRAWING='@T6G_MB_LIB.T6G(SCH_1):PAGE273',
 WATTAGE='1/4W',
 TOLERANCE='1%',
 MATERIAL='CHIP',
 PHYS_PAGE='188',
 XY='(-600,7275)',
 ROT='0',
 VER='2',
 PACK_TYPE='1206LF',
 LOCATION='R4641',
 CDS_LIB='pure_quanta',
 CDS_PART_NAME='Q_RES_1206LF-243,1%,1/4W,CHIP,CS12436F201',
 PART_NUMBER='CS12436F201',
 VALUE='243',
 PRIM_FILE='./archive_libs/logical/q_res/chips/chips.prt';

PART_NAME
 R4809 'Q_RES_0402LF-0,5%,1/16W,CHIP,CS00002JB13':;

SECTION_NUMBER 1
 '@T6G_MB_LIB.T6G(SCH_1):PAGE348_I220@PURE_QUANTA.Q_RES(CHIPS)':
 C_PATH='@t6g_mb_lib.t6g(sch_1):page348_i220@pure_quanta.q_res(chips)',
 P_PATH='@t6g_mb_lib.t6g(sch_1):page150_i220@pure_quanta.q_res(chips)',
 PATH='I220',
 DRAWING='@T6G_MB_LIB.T6G(SCH_1):PAGE348',
 WATTAGE='1/16W',
 TOLERANCE='5%',
 MATERIAL='CHIP',
 PHYS_PAGE='150',
 XY='(-16725,5525)',
 ROT='0',
 VER='2',
 PACK_TYPE='0402LF',
 LOCATION='R4809',
 CDS_LIB='pure_quanta',
 CDS_PART_NAME='Q_RES_0402LF-0,5%,1/16W,CHIP,CS00002JB13',
 PART_NUMBER='CS00002JB13',
 VALUE='0',
 PRIM_FILE='./archive_libs/logical/q_res/chips/chips.prt';

PART_NAME
 R4901 'Q_RES_0402LF-82K,1%,1/16W,CHIP,CS38202FB01':;

SECTION_NUMBER 1
 '@T6G_MB_LIB.T6G(SCH_1):PAGE372_I19@PURE_QUANTA.Q_RES(CHIPS)':
 C_PATH='@t6g_mb_lib.t6g(sch_1):page372_i19@pure_quanta.q_res(chips)',
 P_PATH='@t6g_mb_lib.t6g(sch_1):page268_i19@pure_quanta.q_res(chips)',
 PATH='I19',
 DRAWING='@T6G_MB_LIB.T6G(SCH_1):PAGE372',
 WATTAGE='1/16W',
 TOLERANCE='1%',
 MATERIAL='CHIP',
 PHYS_PAGE='268',
 XY='(-6825,1500)',
 ROT='0',
 VER='1',
 PACK_TYPE='0402LF',
 LOCATION='R4901',
 CDS_LIB='pure_quanta',
 CDS_PART_NAME='Q_RES_0402LF-82K,1%,1/16W,CHIP,CS38202FB01',
 PART_NUMBER='CS38202FB01',
 VALUE='82K',
 PRIM_FILE='./archive_libs/logical/q_res/chips/chips.prt';

PART_NAME
 R5004 'Q_RES_0402LF-10K,1%,1/16W,CHIP,CS31002FB08':;

SECTION_NUMBER 1
 '@T6G_MB_LIB.T6G(SCH_1):PAGE138_I27@PURE_QUANTA.Q_RES(CHIPS)':
 C_PATH='@t6g_mb_lib.t6g(sch_1):page138_i27@pure_quanta.q_res(chips)',
 P_PATH='@t6g_mb_lib.t6g(sch_1):page161_i27@pure_quanta.q_res(chips)',
 PATH='I27',
 DRAWING='@T6G_MB_LIB.T6G(SCH_1):PAGE138',
 WATTAGE='1/16W',
 TOLERANCE='1%',
 MATERIAL='CHIP',
 PHYS_PAGE='161',
 XY='(2800,3600)',
 ROT='0',
 VER='2',
 PACK_TYPE='0402LF',
 LOCATION='R5004',
 CDS_LIB='pure_quanta',
 CDS_PART_NAME='Q_RES_0402LF-10K,1%,1/16W,CHIP,CS31002FB08',
 PART_NUMBER='CS31002FB08',
 VALUE='10K',
 PRIM_FILE='./archive_libs/logical/q_res/chips/chips.prt';

PART_NAME
 R5006 'Q_RES_0402LF-1K,1%,1/16W,EMPTY,CS21002FB06':;

SECTION_NUMBER 1
 '@T6G_MB_LIB.T6G(SCH_1):PAGE136_I145@PURE_QUANTA.Q_RES(CHIPS)':
 C_PATH='@t6g_mb_lib.t6g(sch_1):page136_i145@pure_quanta.q_res(chips)',
 P_PATH='@t6g_mb_lib.t6g(sch_1):page159_i145@pure_quanta.q_res(chips)',
 PATH='I145',
 DRAWING='@T6G_MB_LIB.T6G(SCH_1):PAGE136',
 WATTAGE='1/16W',
 TOLERANCE='1%',
 MATERIAL='EMPTY',
 PHYS_PAGE='159',
 XY='(-3450,6100)',
 ROT='0',
 VER='2',
 PACK_TYPE='0402LF',
 LOCATION='R5006',
 CDS_LIB='pure_quanta',
 CDS_PART_NAME='Q_RES_0402LF-1K,1%,1/16W,EMPTY,CS21002FB06',
 PART_NUMBER='CS21002FB06',
 VALUE='1K',
 PRIM_FILE='./archive_libs/logical/q_res/chips/chips.prt';

PART_NAME
 R5007 'Q_RES_0402LF-1K,1%,1/16W,EMPTY,CS21002FB06':;

SECTION_NUMBER 1
 '@T6G_MB_LIB.T6G(SCH_1):PAGE136_I147@PURE_QUANTA.Q_RES(CHIPS)':
 C_PATH='@t6g_mb_lib.t6g(sch_1):page136_i147@pure_quanta.q_res(chips)',
 P_PATH='@t6g_mb_lib.t6g(sch_1):page159_i147@pure_quanta.q_res(chips)',
 PATH='I147',
 DRAWING='@T6G_MB_LIB.T6G(SCH_1):PAGE136',
 WATTAGE='1/16W',
 TOLERANCE='1%',
 MATERIAL='EMPTY',
 PHYS_PAGE='159',
 XY='(-3650,6100)',
 ROT='0',
 VER='2',
 PACK_TYPE='0402LF',
 LOCATION='R5007',
 CDS_LIB='pure_quanta',
 CDS_PART_NAME='Q_RES_0402LF-1K,1%,1/16W,EMPTY,CS21002FB06',
 PART_NUMBER='CS21002FB06',
 VALUE='1K',
 PRIM_FILE='./archive_libs/logical/q_res/chips/chips.prt';

PART_NAME
 R5008 'Q_RES_0402LF-1K,1%,1/16W,EMPTY,CS21002FB06':;

SECTION_NUMBER 1
 '@T6G_MB_LIB.T6G(SCH_1):PAGE136_I148@PURE_QUANTA.Q_RES(CHIPS)':
 C_PATH='@t6g_mb_lib.t6g(sch_1):page136_i148@pure_quanta.q_res(chips)',
 P_PATH='@t6g_mb_lib.t6g(sch_1):page159_i148@pure_quanta.q_res(chips)',
 PATH='I148',
 DRAWING='@T6G_MB_LIB.T6G(SCH_1):PAGE136',
 WATTAGE='1/16W',
 TOLERANCE='1%',
 MATERIAL='EMPTY',
 PHYS_PAGE='159',
 XY='(-3450,4700)',
 ROT='0',
 VER='2',
 PACK_TYPE='0402LF',
 LOCATION='R5008',
 CDS_LIB='pure_quanta',
 CDS_PART_NAME='Q_RES_0402LF-1K,1%,1/16W,EMPTY,CS21002FB06',
 PART_NUMBER='CS21002FB06',
 VALUE='1K',
 PRIM_FILE='./archive_libs/logical/q_res/chips/chips.prt';

PART_NAME
 R5009 'Q_RES_0402LF-1K,1%,1/16W,EMPTY,CS21002FB06':;

SECTION_NUMBER 1
 '@T6G_MB_LIB.T6G(SCH_1):PAGE136_I150@PURE_QUANTA.Q_RES(CHIPS)':
 C_PATH='@t6g_mb_lib.t6g(sch_1):page136_i150@pure_quanta.q_res(chips)',
 P_PATH='@t6g_mb_lib.t6g(sch_1):page159_i150@pure_quanta.q_res(chips)',
 PATH='I150',
 DRAWING='@T6G_MB_LIB.T6G(SCH_1):PAGE136',
 WATTAGE='1/16W',
 TOLERANCE='1%',
 MATERIAL='EMPTY',
 PHYS_PAGE='159',
 XY='(-3650,4700)',
 ROT='0',
 VER='2',
 PACK_TYPE='0402LF',
 LOCATION='R5009',
 CDS_LIB='pure_quanta',
 CDS_PART_NAME='Q_RES_0402LF-1K,1%,1/16W,EMPTY,CS21002FB06',
 PART_NUMBER='CS21002FB06',
 VALUE='1K',
 PRIM_FILE='./archive_libs/logical/q_res/chips/chips.prt';

PART_NAME
 R5010 'Q_RES_0402LF-1K,1%,1/16W,EMPTY,CS21002FB06':;

SECTION_NUMBER 1
 '@T6G_MB_LIB.T6G(SCH_1):PAGE136_I151@PURE_QUANTA.Q_RES(CHIPS)':
 C_PATH='@t6g_mb_lib.t6g(sch_1):page136_i151@pure_quanta.q_res(chips)',
 P_PATH='@t6g_mb_lib.t6g(sch_1):page159_i151@pure_quanta.q_res(chips)',
 PATH='I151',
 DRAWING='@T6G_MB_LIB.T6G(SCH_1):PAGE136',
 WATTAGE='1/16W',
 TOLERANCE='1%',
 MATERIAL='EMPTY',
 PHYS_PAGE='159',
 XY='(-3450,3175)',
 ROT='0',
 VER='2',
 PACK_TYPE='0402LF',
 LOCATION='R5010',
 CDS_LIB='pure_quanta',
 CDS_PART_NAME='Q_RES_0402LF-1K,1%,1/16W,EMPTY,CS21002FB06',
 PART_NUMBER='CS21002FB06',
 VALUE='1K',
 PRIM_FILE='./archive_libs/logical/q_res/chips/chips.prt';

PART_NAME
 R5011 'Q_RES_0402LF-1K,1%,1/16W,EMPTY,CS21002FB06':;

SECTION_NUMBER 1
 '@T6G_MB_LIB.T6G(SCH_1):PAGE136_I152@PURE_QUANTA.Q_RES(CHIPS)':
 C_PATH='@t6g_mb_lib.t6g(sch_1):page136_i152@pure_quanta.q_res(chips)',
 P_PATH='@t6g_mb_lib.t6g(sch_1):page159_i152@pure_quanta.q_res(chips)',
 PATH='I152',
 DRAWING='@T6G_MB_LIB.T6G(SCH_1):PAGE136',
 WATTAGE='1/16W',
 TOLERANCE='1%',
 MATERIAL='EMPTY',
 PHYS_PAGE='159',
 XY='(-3650,3175)',
 ROT='0',
 VER='2',
 PACK_TYPE='0402LF',
 LOCATION='R5011',
 CDS_LIB='pure_quanta',
 CDS_PART_NAME='Q_RES_0402LF-1K,1%,1/16W,EMPTY,CS21002FB06',
 PART_NUMBER='CS21002FB06',
 VALUE='1K',
 PRIM_FILE='./archive_libs/logical/q_res/chips/chips.prt';

PART_NAME
 R5012 'Q_RES_0402LF-1K,1%,1/16W,EMPTY,CS21002FB06':;

SECTION_NUMBER 1
 '@T6G_MB_LIB.T6G(SCH_1):PAGE136_I156@PURE_QUANTA.Q_RES(CHIPS)':
 C_PATH='@t6g_mb_lib.t6g(sch_1):page136_i156@pure_quanta.q_res(chips)',
 P_PATH='@t6g_mb_lib.t6g(sch_1):page159_i156@pure_quanta.q_res(chips)',
 PATH='I156',
 DRAWING='@T6G_MB_LIB.T6G(SCH_1):PAGE136',
 WATTAGE='1/16W',
 TOLERANCE='1%',
 MATERIAL='EMPTY',
 PHYS_PAGE='159',
 XY='(-3450,1725)',
 ROT='0',
 VER='2',
 PACK_TYPE='0402LF',
 LOCATION='R5012',
 CDS_LIB='pure_quanta',
 CDS_PART_NAME='Q_RES_0402LF-1K,1%,1/16W,EMPTY,CS21002FB06',
 PART_NUMBER='CS21002FB06',
 VALUE='1K',
 PRIM_FILE='./archive_libs/logical/q_res/chips/chips.prt';

PART_NAME
 R5013 'Q_RES_0402LF-1K,1%,1/16W,EMPTY,CS21002FB06':;

SECTION_NUMBER 1
 '@T6G_MB_LIB.T6G(SCH_1):PAGE136_I154@PURE_QUANTA.Q_RES(CHIPS)':
 C_PATH='@t6g_mb_lib.t6g(sch_1):page136_i154@pure_quanta.q_res(chips)',
 P_PATH='@t6g_mb_lib.t6g(sch_1):page159_i154@pure_quanta.q_res(chips)',
 PATH='I154',
 DRAWING='@T6G_MB_LIB.T6G(SCH_1):PAGE136',
 WATTAGE='1/16W',
 TOLERANCE='1%',
 MATERIAL='EMPTY',
 PHYS_PAGE='159',
 XY='(-3650,1725)',
 ROT='0',
 VER='2',
 PACK_TYPE='0402LF',
 LOCATION='R5013',
 CDS_LIB='pure_quanta',
 CDS_PART_NAME='Q_RES_0402LF-1K,1%,1/16W,EMPTY,CS21002FB06',
 PART_NUMBER='CS21002FB06',
 VALUE='1K',
 PRIM_FILE='./archive_libs/logical/q_res/chips/chips.prt';

PART_NAME
 R5014 'Q_RES_0402LF-1K,1%,1/16W,EMPTY,CS21002FB06':;

SECTION_NUMBER 1
 '@T6G_MB_LIB.T6G(SCH_1):PAGE136_I159@PURE_QUANTA.Q_RES(CHIPS)':
 C_PATH='@t6g_mb_lib.t6g(sch_1):page136_i159@pure_quanta.q_res(chips)',
 P_PATH='@t6g_mb_lib.t6g(sch_1):page159_i159@pure_quanta.q_res(chips)',
 PATH='I159',
 DRAWING='@T6G_MB_LIB.T6G(SCH_1):PAGE136',
 WATTAGE='1/16W',
 TOLERANCE='1%',
 MATERIAL='EMPTY',
 PHYS_PAGE='159',
 XY='(-5450,6175)',
 ROT='0',
 VER='2',
 PACK_TYPE='0402LF',
 LOCATION='R5014',
 CDS_LIB='pure_quanta',
 CDS_PART_NAME='Q_RES_0402LF-1K,1%,1/16W,EMPTY,CS21002FB06',
 PART_NUMBER='CS21002FB06',
 VALUE='1K',
 PRIM_FILE='./archive_libs/logical/q_res/chips/chips.prt';

PART_NAME
 R5015 'Q_RES_0402LF-1K,1%,1/16W,EMPTY,CS21002FB06':;

SECTION_NUMBER 1
 '@T6G_MB_LIB.T6G(SCH_1):PAGE136_I157@PURE_QUANTA.Q_RES(CHIPS)':
 C_PATH='@t6g_mb_lib.t6g(sch_1):page136_i157@pure_quanta.q_res(chips)',
 P_PATH='@t6g_mb_lib.t6g(sch_1):page159_i157@pure_quanta.q_res(chips)',
 PATH='I157',
 DRAWING='@T6G_MB_LIB.T6G(SCH_1):PAGE136',
 WATTAGE='1/16W',
 TOLERANCE='1%',
 MATERIAL='EMPTY',
 PHYS_PAGE='159',
 XY='(-5650,6175)',
 ROT='0',
 VER='2',
 PACK_TYPE='0402LF',
 LOCATION='R5015',
 CDS_LIB='pure_quanta',
 CDS_PART_NAME='Q_RES_0402LF-1K,1%,1/16W,EMPTY,CS21002FB06',
 PART_NUMBER='CS21002FB06',
 VALUE='1K',
 PRIM_FILE='./archive_libs/logical/q_res/chips/chips.prt';

PART_NAME
 R5016 'Q_RES_0402LF-1K,1%,1/16W,EMPTY,CS21002FB06':;

SECTION_NUMBER 1
 '@T6G_MB_LIB.T6G(SCH_1):PAGE136_I162@PURE_QUANTA.Q_RES(CHIPS)':
 C_PATH='@t6g_mb_lib.t6g(sch_1):page136_i162@pure_quanta.q_res(chips)',
 P_PATH='@t6g_mb_lib.t6g(sch_1):page159_i162@pure_quanta.q_res(chips)',
 PATH='I162',
 DRAWING='@T6G_MB_LIB.T6G(SCH_1):PAGE136',
 WATTAGE='1/16W',
 TOLERANCE='1%',
 MATERIAL='EMPTY',
 PHYS_PAGE='159',
 XY='(-5450,4700)',
 ROT='0',
 VER='2',
 PACK_TYPE='0402LF',
 LOCATION='R5016',
 CDS_LIB='pure_quanta',
 CDS_PART_NAME='Q_RES_0402LF-1K,1%,1/16W,EMPTY,CS21002FB06',
 PART_NUMBER='CS21002FB06',
 VALUE='1K',
 PRIM_FILE='./archive_libs/logical/q_res/chips/chips.prt';

PART_NAME
 R5017 'Q_RES_0402LF-1K,1%,1/16W,EMPTY,CS21002FB06':;

SECTION_NUMBER 1
 '@T6G_MB_LIB.T6G(SCH_1):PAGE136_I161@PURE_QUANTA.Q_RES(CHIPS)':
 C_PATH='@t6g_mb_lib.t6g(sch_1):page136_i161@pure_quanta.q_res(chips)',
 P_PATH='@t6g_mb_lib.t6g(sch_1):page159_i161@pure_quanta.q_res(chips)',
 PATH='I161',
 DRAWING='@T6G_MB_LIB.T6G(SCH_1):PAGE136',
 WATTAGE='1/16W',
 TOLERANCE='1%',
 MATERIAL='EMPTY',
 PHYS_PAGE='159',
 XY='(-5650,4700)',
 ROT='0',
 VER='2',
 PACK_TYPE='0402LF',
 LOCATION='R5017',
 CDS_LIB='pure_quanta',
 CDS_PART_NAME='Q_RES_0402LF-1K,1%,1/16W,EMPTY,CS21002FB06',
 PART_NUMBER='CS21002FB06',
 VALUE='1K',
 PRIM_FILE='./archive_libs/logical/q_res/chips/chips.prt';

PART_NAME
 R5018 'Q_RES_0402LF-1K,1%,1/16W,EMPTY,CS21002FB06':;

SECTION_NUMBER 1
 '@T6G_MB_LIB.T6G(SCH_1):PAGE136_I163@PURE_QUANTA.Q_RES(CHIPS)':
 C_PATH='@t6g_mb_lib.t6g(sch_1):page136_i163@pure_quanta.q_res(chips)',
 P_PATH='@t6g_mb_lib.t6g(sch_1):page159_i163@pure_quanta.q_res(chips)',
 PATH='I163',
 DRAWING='@T6G_MB_LIB.T6G(SCH_1):PAGE136',
 WATTAGE='1/16W',
 TOLERANCE='1%',
 MATERIAL='EMPTY',
 PHYS_PAGE='159',
 XY='(-5450,3175)',
 ROT='0',
 VER='2',
 PACK_TYPE='0402LF',
 LOCATION='R5018',
 CDS_LIB='pure_quanta',
 CDS_PART_NAME='Q_RES_0402LF-1K,1%,1/16W,EMPTY,CS21002FB06',
 PART_NUMBER='CS21002FB06',
 VALUE='1K',
 PRIM_FILE='./archive_libs/logical/q_res/chips/chips.prt';

PART_NAME
 R5019 'Q_RES_0402LF-1K,1%,1/16W,EMPTY,CS21002FB06':;

SECTION_NUMBER 1
 '@T6G_MB_LIB.T6G(SCH_1):PAGE136_I164@PURE_QUANTA.Q_RES(CHIPS)':
 C_PATH='@t6g_mb_lib.t6g(sch_1):page136_i164@pure_quanta.q_res(chips)',
 P_PATH='@t6g_mb_lib.t6g(sch_1):page159_i164@pure_quanta.q_res(chips)',
 PATH='I164',
 DRAWING='@T6G_MB_LIB.T6G(SCH_1):PAGE136',
 WATTAGE='1/16W',
 TOLERANCE='1%',
 MATERIAL='EMPTY',
 PHYS_PAGE='159',
 XY='(-5650,3175)',
 ROT='0',
 VER='2',
 PACK_TYPE='0402LF',
 LOCATION='R5019',
 CDS_LIB='pure_quanta',
 CDS_PART_NAME='Q_RES_0402LF-1K,1%,1/16W,EMPTY,CS21002FB06',
 PART_NUMBER='CS21002FB06',
 VALUE='1K',
 PRIM_FILE='./archive_libs/logical/q_res/chips/chips.prt';

PART_NAME
 R5020 'Q_RES_0402LF-1K,1%,1/16W,EMPTY,CS21002FB06':;

SECTION_NUMBER 1
 '@T6G_MB_LIB.T6G(SCH_1):PAGE136_I167@PURE_QUANTA.Q_RES(CHIPS)':
 C_PATH='@t6g_mb_lib.t6g(sch_1):page136_i167@pure_quanta.q_res(chips)',
 P_PATH='@t6g_mb_lib.t6g(sch_1):page159_i167@pure_quanta.q_res(chips)',
 PATH='I167',
 DRAWING='@T6G_MB_LIB.T6G(SCH_1):PAGE136',
 WATTAGE='1/16W',
 TOLERANCE='1%',
 MATERIAL='EMPTY',
 PHYS_PAGE='159',
 XY='(-5450,1725)',
 ROT='0',
 VER='2',
 PACK_TYPE='0402LF',
 LOCATION='R5020',
 CDS_LIB='pure_quanta',
 CDS_PART_NAME='Q_RES_0402LF-1K,1%,1/16W,EMPTY,CS21002FB06',
 PART_NUMBER='CS21002FB06',
 VALUE='1K',
 PRIM_FILE='./archive_libs/logical/q_res/chips/chips.prt';

PART_NAME
 R5021 'Q_RES_0402LF-1K,1%,1/16W,EMPTY,CS21002FB06':;

SECTION_NUMBER 1
 '@T6G_MB_LIB.T6G(SCH_1):PAGE136_I166@PURE_QUANTA.Q_RES(CHIPS)':
 C_PATH='@t6g_mb_lib.t6g(sch_1):page136_i166@pure_quanta.q_res(chips)',
 P_PATH='@t6g_mb_lib.t6g(sch_1):page159_i166@pure_quanta.q_res(chips)',
 PATH='I166',
 DRAWING='@T6G_MB_LIB.T6G(SCH_1):PAGE136',
 WATTAGE='1/16W',
 TOLERANCE='1%',
 MATERIAL='EMPTY',
 PHYS_PAGE='159',
 XY='(-5650,1725)',
 ROT='0',
 VER='2',
 PACK_TYPE='0402LF',
 LOCATION='R5021',
 CDS_LIB='pure_quanta',
 CDS_PART_NAME='Q_RES_0402LF-1K,1%,1/16W,EMPTY,CS21002FB06',
 PART_NUMBER='CS21002FB06',
 VALUE='1K',
 PRIM_FILE='./archive_libs/logical/q_res/chips/chips.prt';

PART_NAME
 R5026 'Q_RES_0402LF-4.7K,5%,1/16W,EMPTY,CS24702JB10':;

SECTION_NUMBER 1
 '@T6G_MB_LIB.T6G(SCH_1):PAGE28_I40@PURE_QUANTA.Q_RES(CHIPS)':
 C_PATH='@t6g_mb_lib.t6g(sch_1):page28_i40@pure_quanta.q_res(chips)',
 P_PATH='@t6g_mb_lib.t6g(sch_1):page28_i40@pure_quanta.q_res(chips)',
 PATH='I40',
 DRAWING='@T6G_MB_LIB.T6G(SCH_1):PAGE28',
 WATTAGE='1/16W',
 TOLERANCE='5%',
 MATERIAL='EMPTY',
 PHYS_PAGE='28',
 XY='(-7225,7225)',
 ROT='1',
 VER='1',
 PACK_TYPE='0402LF',
 LOCATION='R5026',
 CDS_LIB='pure_quanta',
 CDS_PART_NAME='Q_RES_0402LF-4.7K,5%,1/16W,EMPTY,CS24702JB10',
 PART_NUMBER='CS24702JB10',
 VALUE='4.7K',
 PRIM_FILE='./archive_libs/logical/q_res/chips/chips.prt';

PART_NAME
 R5027 'Q_RES_0402LF-4.7K,5%,1/16W,EMPTY,CS24702JB10':;

SECTION_NUMBER 1
 '@T6G_MB_LIB.T6G(SCH_1):PAGE28_I59@PURE_QUANTA.Q_RES(CHIPS)':
 C_PATH='@t6g_mb_lib.t6g(sch_1):page28_i59@pure_quanta.q_res(chips)',
 P_PATH='@t6g_mb_lib.t6g(sch_1):page28_i59@pure_quanta.q_res(chips)',
 PATH='I59',
 DRAWING='@T6G_MB_LIB.T6G(SCH_1):PAGE28',
 WATTAGE='1/16W',
 TOLERANCE='5%',
 MATERIAL='EMPTY',
 PHYS_PAGE='28',
 XY='(-7075,7225)',
 ROT='1',
 VER='1',
 PACK_TYPE='0402LF',
 LOCATION='R5027',
 CDS_LIB='pure_quanta',
 CDS_PART_NAME='Q_RES_0402LF-4.7K,5%,1/16W,EMPTY,CS24702JB10',
 PART_NUMBER='CS24702JB10',
 VALUE='4.7K',
 PRIM_FILE='./archive_libs/logical/q_res/chips/chips.prt';

PART_NAME
 R5028 'Q_RES_0402LF-4.7K,5%,1/16W,EMPTY,CS24702JB10':;

SECTION_NUMBER 1
 '@T6G_MB_LIB.T6G(SCH_1):PAGE28_I60@PURE_QUANTA.Q_RES(CHIPS)':
 C_PATH='@t6g_mb_lib.t6g(sch_1):page28_i60@pure_quanta.q_res(chips)',
 P_PATH='@t6g_mb_lib.t6g(sch_1):page28_i60@pure_quanta.q_res(chips)',
 PATH='I60',
 DRAWING='@T6G_MB_LIB.T6G(SCH_1):PAGE28',
 WATTAGE='1/16W',
 TOLERANCE='5%',
 MATERIAL='EMPTY',
 PHYS_PAGE='28',
 XY='(-6925,7225)',
 ROT='1',
 VER='1',
 PACK_TYPE='0402LF',
 LOCATION='R5028',
 CDS_LIB='pure_quanta',
 CDS_PART_NAME='Q_RES_0402LF-4.7K,5%,1/16W,EMPTY,CS24702JB10',
 PART_NUMBER='CS24702JB10',
 VALUE='4.7K',
 PRIM_FILE='./archive_libs/logical/q_res/chips/chips.prt';

PART_NAME
 R5029 'Q_RES_0402LF-4.7K,5%,1/16W,EMPTY,CS24702JB10':;

SECTION_NUMBER 1
 '@T6G_MB_LIB.T6G(SCH_1):PAGE28_I62@PURE_QUANTA.Q_RES(CHIPS)':
 C_PATH='@t6g_mb_lib.t6g(sch_1):page28_i62@pure_quanta.q_res(chips)',
 P_PATH='@t6g_mb_lib.t6g(sch_1):page28_i62@pure_quanta.q_res(chips)',
 PATH='I62',
 DRAWING='@T6G_MB_LIB.T6G(SCH_1):PAGE28',
 WATTAGE='1/16W',
 TOLERANCE='5%',
 MATERIAL='EMPTY',
 PHYS_PAGE='28',
 XY='(-6775,7225)',
 ROT='1',
 VER='1',
 PACK_TYPE='0402LF',
 LOCATION='R5029',
 CDS_LIB='pure_quanta',
 CDS_PART_NAME='Q_RES_0402LF-4.7K,5%,1/16W,EMPTY,CS24702JB10',
 PART_NUMBER='CS24702JB10',
 VALUE='4.7K',
 PRIM_FILE='./archive_libs/logical/q_res/chips/chips.prt';

PART_NAME
 R5030 'Q_RES_0402LF-4.7K,5%,1/16W,EMPTY,CS24702JB10':;

SECTION_NUMBER 1
 '@T6G_MB_LIB.T6G(SCH_1):PAGE55_I334@PURE_QUANTA.Q_RES(CHIPS)':
 C_PATH='@t6g_mb_lib.t6g(sch_1):page55_i334@pure_quanta.q_res(chips)',
 P_PATH='@t6g_mb_lib.t6g(sch_1):page55_i334@pure_quanta.q_res(chips)',
 PATH='I334',
 DRAWING='@T6G_MB_LIB.T6G(SCH_1):PAGE55',
 WATTAGE='1/16W',
 TOLERANCE='5%',
 MATERIAL='EMPTY',
 PHYS_PAGE='55',
 XY='(-8850,425)',
 ROT='1',
 VER='1',
 PACK_TYPE='0402LF',
 LOCATION='R5030',
 CDS_LIB='pure_quanta',
 CDS_PART_NAME='Q_RES_0402LF-4.7K,5%,1/16W,EMPTY,CS24702JB10',
 PART_NUMBER='CS24702JB10',
 VALUE='4.7K',
 PRIM_FILE='./archive_libs/logical/q_res/chips/chips.prt';

PART_NAME
 R5031 'Q_RES_0402LF-4.7K,5%,1/16W,EMPTY,CS24702JB10':;

SECTION_NUMBER 1
 '@T6G_MB_LIB.T6G(SCH_1):PAGE55_I331@PURE_QUANTA.Q_RES(CHIPS)':
 C_PATH='@t6g_mb_lib.t6g(sch_1):page55_i331@pure_quanta.q_res(chips)',
 P_PATH='@t6g_mb_lib.t6g(sch_1):page55_i331@pure_quanta.q_res(chips)',
 PATH='I331',
 DRAWING='@T6G_MB_LIB.T6G(SCH_1):PAGE55',
 WATTAGE='1/16W',
 TOLERANCE='5%',
 MATERIAL='EMPTY',
 PHYS_PAGE='55',
 XY='(-8975,425)',
 ROT='1',
 VER='1',
 PACK_TYPE='0402LF',
 LOCATION='R5031',
 CDS_LIB='pure_quanta',
 CDS_PART_NAME='Q_RES_0402LF-4.7K,5%,1/16W,EMPTY,CS24702JB10',
 PART_NUMBER='CS24702JB10',
 VALUE='4.7K',
 PRIM_FILE='./archive_libs/logical/q_res/chips/chips.prt';

PART_NAME
 R5032 'Q_RES_0402LF-4.7K,5%,1/16W,EMPTY,CS24702JB10':;

SECTION_NUMBER 1
 '@T6G_MB_LIB.T6G(SCH_1):PAGE55_I330@PURE_QUANTA.Q_RES(CHIPS)':
 C_PATH='@t6g_mb_lib.t6g(sch_1):page55_i330@pure_quanta.q_res(chips)',
 P_PATH='@t6g_mb_lib.t6g(sch_1):page55_i330@pure_quanta.q_res(chips)',
 PATH='I330',
 DRAWING='@T6G_MB_LIB.T6G(SCH_1):PAGE55',
 WATTAGE='1/16W',
 TOLERANCE='5%',
 MATERIAL='EMPTY',
 PHYS_PAGE='55',
 XY='(-9100,425)',
 ROT='1',
 VER='1',
 PACK_TYPE='0402LF',
 LOCATION='R5032',
 CDS_LIB='pure_quanta',
 CDS_PART_NAME='Q_RES_0402LF-4.7K,5%,1/16W,EMPTY,CS24702JB10',
 PART_NUMBER='CS24702JB10',
 VALUE='4.7K',
 PRIM_FILE='./archive_libs/logical/q_res/chips/chips.prt';

PART_NAME
 R5051 'Q_RES_0402LF-0,5%,1/16W,EMPTY,CS00002JB13':;

SECTION_NUMBER 1
 '@T6G_MB_LIB.T6G(SCH_1):PAGE156_I101@PURE_QUANTA.Q_RES(CHIPS)':
 C_PATH='@t6g_mb_lib.t6g(sch_1):page156_i101@pure_quanta.q_res(chips)',
 P_PATH='@t6g_mb_lib.t6g(sch_1):page187_i101@pure_quanta.q_res(chips)',
 PATH='I101',
 DRAWING='@T6G_MB_LIB.T6G(SCH_1):PAGE156',
 WATTAGE='1/16W',
 TOLERANCE='5%',
 MATERIAL='EMPTY',
 PHYS_PAGE='187',
 XY='(-6325,7000)',
 ROT='0',
 VER='1',
 PACK_TYPE='0402LF',
 LOCATION='R5051',
 CDS_LIB='pure_quanta',
 CDS_PART_NAME='Q_RES_0402LF-0,5%,1/16W,EMPTY,CS00002JB13',
 PART_NUMBER='CS00002JB13',
 VALUE='0',
 PRIM_FILE='./archive_libs/logical/q_res/chips/chips.prt';

PART_NAME
 R5052 'Q_RES_0402LF-0,5%,1/16W,CHIP,CS00002JB13':;

SECTION_NUMBER 1
 '@T6G_MB_LIB.T6G(SCH_1):PAGE156_I100@PURE_QUANTA.Q_RES(CHIPS)':
 C_PATH='@t6g_mb_lib.t6g(sch_1):page156_i100@pure_quanta.q_res(chips)',
 P_PATH='@t6g_mb_lib.t6g(sch_1):page187_i100@pure_quanta.q_res(chips)',
 PATH='I100',
 DRAWING='@T6G_MB_LIB.T6G(SCH_1):PAGE156',
 WATTAGE='1/16W',
 TOLERANCE='5%',
 MATERIAL='CHIP',
 PHYS_PAGE='187',
 XY='(-6550,7275)',
 ROT='0',
 VER='2',
 PACK_TYPE='0402LF',
 LOCATION='R5052',
 CDS_LIB='pure_quanta',
 CDS_PART_NAME='Q_RES_0402LF-0,5%,1/16W,CHIP,CS00002JB13',
 PART_NUMBER='CS00002JB13',
 VALUE='0',
 PRIM_FILE='./archive_libs/logical/q_res/chips/chips.prt';

PART_NAME
 R5053 'Q_RES_0402LF-1K,1%,1/16W,EMPTY,CS21002FB06':;

SECTION_NUMBER 1
 '@T6G_MB_LIB.T6G(SCH_1):PAGE156_I120@PURE_QUANTA.Q_RES(CHIPS)':
 C_PATH='@t6g_mb_lib.t6g(sch_1):page156_i120@pure_quanta.q_res(chips)',
 P_PATH='@t6g_mb_lib.t6g(sch_1):page187_i120@pure_quanta.q_res(chips)',
 PATH='I120',
 DRAWING='@T6G_MB_LIB.T6G(SCH_1):PAGE156',
 WATTAGE='1/16W',
 TOLERANCE='1%',
 MATERIAL='EMPTY',
 PHYS_PAGE='187',
 XY='(-3075,7000)',
 ROT='0',
 VER='1',
 PACK_TYPE='0402LF',
 LOCATION='R5053',
 CDS_LIB='pure_quanta',
 CDS_PART_NAME='Q_RES_0402LF-1K,1%,1/16W,EMPTY,CS21002FB06',
 PART_NUMBER='CS21002FB06',
 VALUE='1K',
 PRIM_FILE='./archive_libs/logical/q_res/chips/chips.prt';

PART_NAME
 R5054 'Q_RES_0402LF-0,5%,1/16W,CHIP,CS00002JB13':;

SECTION_NUMBER 1
 '@T6G_MB_LIB.T6G(SCH_1):PAGE156_I122@PURE_QUANTA.Q_RES(CHIPS)':
 C_PATH='@t6g_mb_lib.t6g(sch_1):page156_i122@pure_quanta.q_res(chips)',
 P_PATH='@t6g_mb_lib.t6g(sch_1):page187_i122@pure_quanta.q_res(chips)',
 PATH='I122',
 DRAWING='@T6G_MB_LIB.T6G(SCH_1):PAGE156',
 WATTAGE='1/16W',
 TOLERANCE='5%',
 MATERIAL='CHIP',
 PHYS_PAGE='187',
 XY='(-2750,7525)',
 ROT='0',
 VER='2',
 PACK_TYPE='0402LF',
 LOCATION='R5054',
 CDS_LIB='pure_quanta',
 CDS_PART_NAME='Q_RES_0402LF-0,5%,1/16W,CHIP,CS00002JB13',
 PART_NUMBER='CS00002JB13',
 VALUE='0',
 PRIM_FILE='./archive_libs/logical/q_res/chips/chips.prt';

PART_NAME
 R5055 'Q_RES_0402LF-10K,5%,1/16W,CHIP,CS31002JB08':;

SECTION_NUMBER 1
 '@T6G_MB_LIB.T6G(SCH_1):PAGE27_I427@PURE_QUANTA.Q_RES(CHIPS)':
 C_PATH='@t6g_mb_lib.t6g(sch_1):page27_i427@pure_quanta.q_res(chips)',
 P_PATH='@t6g_mb_lib.t6g(sch_1):page27_i427@pure_quanta.q_res(chips)',
 PATH='I427',
 DRAWING='@T6G_MB_LIB.T6G(SCH_1):PAGE27',
 BOM_COST='I/O CONNECTOR',
 WATTAGE='1/16W',
 TOLERANCE='5%',
 MATERIAL='CHIP',
 PHYS_PAGE='27',
 XY='(-5650,1350)',
 ROT='0',
 VER='2',
 PACK_TYPE='0402LF',
 LOCATION='R5055',
 CDS_LIB='pure_quanta',
 CDS_PART_NAME='Q_RES_0402LF-10K,5%,1/16W,CHIP,CS31002JB08',
 PART_NUMBER='CS31002JB08',
 VALUE='10K',
 PRIM_FILE='./archive_libs/logical/q_res/chips/chips.prt';

PART_NAME
 R5056 'Q_RES_0402LF-10K,5%,1/16W,EMPTY,CS31002JB08':;

SECTION_NUMBER 1
 '@T6G_MB_LIB.T6G(SCH_1):PAGE27_I428@PURE_QUANTA.Q_RES(CHIPS)':
 C_PATH='@t6g_mb_lib.t6g(sch_1):page27_i428@pure_quanta.q_res(chips)',
 P_PATH='@t6g_mb_lib.t6g(sch_1):page27_i428@pure_quanta.q_res(chips)',
 PATH='I428',
 DRAWING='@T6G_MB_LIB.T6G(SCH_1):PAGE27',
 BOM_COST='I/O CONNECTOR',
 WATTAGE='1/16W',
 TOLERANCE='5%',
 MATERIAL='EMPTY',
 PHYS_PAGE='27',
 XY='(-5650,900)',
 ROT='0',
 VER='2',
 PACK_TYPE='0402LF',
 LOCATION='R5056',
 CDS_LIB='pure_quanta',
 CDS_PART_NAME='Q_RES_0402LF-10K,5%,1/16W,EMPTY,CS31002JB08',
 PART_NUMBER='CS31002JB08',
 VALUE='10K',
 PRIM_FILE='./archive_libs/logical/q_res/chips/chips.prt';

PART_NAME
 R5071 'Q_RES_0402LF-100,1%,1/16W,CHIP,CS11002FB07':;

SECTION_NUMBER 1
 '@T6G_MB_LIB.T6G(SCH_1):PAGE144_I34@PURE_QUANTA.Q_RES(CHIPS)':
 C_PATH='@t6g_mb_lib.t6g(sch_1):page144_i34@pure_quanta.q_res(chips)',
 P_PATH='@t6g_mb_lib.t6g(sch_1):page167_i34@pure_quanta.q_res(chips)',
 PATH='I34',
 DRAWING='@T6G_MB_LIB.T6G(SCH_1):PAGE144',
 WATTAGE='1/16W',
 TOLERANCE='1%',
 MATERIAL='CHIP',
 PHYS_PAGE='167',
 XY='(-7950,4100)',
 ROT='2',
 VER='2',
 PACK_TYPE='0402LF',
 LOCATION='R5071',
 CDS_LIB='pure_quanta',
 CDS_PART_NAME='Q_RES_0402LF-100,1%,1/16W,CHIP,CS11002FB07',
 PART_NUMBER='CS11002FB07',
 VALUE='100',
 PRIM_FILE='./archive_libs/logical/q_res/chips/chips.prt';

PART_NAME
 R5099 'Q_RES_0402LF-0,5%,1/16W,CHIP,CS00002JB13':;

SECTION_NUMBER 1
 '@T6G_MB_LIB.T6G(SCH_1):PAGE80_I35@PURE_QUANTA.Q_RES(CHIPS)':
 C_PATH='@t6g_mb_lib.t6g(sch_1):page80_i35@pure_quanta.q_res(chips)',
 P_PATH='@t6g_mb_lib.t6g(sch_1):page81_i35@pure_quanta.q_res(chips)',
 PATH='I35',
 DRAWING='@T6G_MB_LIB.T6G(SCH_1):PAGE80',
 BOM_COST='MEM',
 WATTAGE='1/16W',
 TOLERANCE='5%',
 MATERIAL='CHIP',
 PHYS_PAGE='81',
 XY='(-6725,2025)',
 ROT='0',
 VER='1',
 PACK_TYPE='0402LF',
 LOCATION='R5099',
 CDS_LIB='pure_quanta',
 CDS_PART_NAME='Q_RES_0402LF-0,5%,1/16W,CHIP,CS00002JB13',
 PART_NUMBER='CS00002JB13',
 VALUE='0',
 PRIM_FILE='./archive_libs/logical/q_res/chips/chips.prt';

PART_NAME
 R5101 'Q_RES_0402LF-10K,5%,1/16W,CHIP,CS31002JB08':;

SECTION_NUMBER 1
 '@T6G_MB_LIB.T6G(SCH_1):PAGE156_I97@PURE_QUANTA.Q_RES(CHIPS)':
 C_PATH='@t6g_mb_lib.t6g(sch_1):page156_i97@pure_quanta.q_res(chips)',
 P_PATH='@t6g_mb_lib.t6g(sch_1):page187_i97@pure_quanta.q_res(chips)',
 PATH='I97',
 DRAWING='@T6G_MB_LIB.T6G(SCH_1):PAGE156',
 WATTAGE='1/16W',
 TOLERANCE='5%',
 MATERIAL='CHIP',
 PHYS_PAGE='187',
 XY='(-8175,7050)',
 ROT='0',
 VER='1',
 PACK_TYPE='0402LF',
 LOCATION='R5101',
 CDS_LIB='pure_quanta',
 CDS_PART_NAME='Q_RES_0402LF-10K,5%,1/16W,CHIP,CS31002JB08',
 PART_NUMBER='CS31002JB08',
 VALUE='10K',
 PRIM_FILE='./archive_libs/logical/q_res/chips/chips.prt';

PART_NAME
 R5102 'Q_RES_0402LF-49.9,1%,1/16W,CHIP,CS04992FB07':;

SECTION_NUMBER 1
 '@T6G_MB_LIB.T6G(SCH_1):PAGE28_I195@PURE_QUANTA.Q_RES(CHIPS)':
 C_PATH='@t6g_mb_lib.t6g(sch_1):page28_i195@pure_quanta.q_res(chips)',
 P_PATH='@t6g_mb_lib.t6g(sch_1):page28_i195@pure_quanta.q_res(chips)',
 PATH='I195',
 DRAWING='@T6G_MB_LIB.T6G(SCH_1):PAGE28',
 WATTAGE='1/16W',
 TOLERANCE='1%',
 MATERIAL='CHIP',
 PHYS_PAGE='28',
 XY='(-4950,8925)',
 ROT='2',
 VER='2',
 PACK_TYPE='0402LF',
 LOCATION='R5102',
 CDS_LIB='pure_quanta',
 CDS_PART_NAME='Q_RES_0402LF-49.9,1%,1/16W,CHIP,CS04992FB07',
 PART_NUMBER='CS04992FB07',
 VALUE='49.9',
 PRIM_FILE='./archive_libs/logical/q_res/chips/chips.prt';

PART_NAME
 R5103 'Q_RES_0402LF-49.9,1%,1/16W,CHIP,CS04992FB07':;

SECTION_NUMBER 1
 '@T6G_MB_LIB.T6G(SCH_1):PAGE55_I386@PURE_QUANTA.Q_RES(CHIPS)':
 C_PATH='@t6g_mb_lib.t6g(sch_1):page55_i386@pure_quanta.q_res(chips)',
 P_PATH='@t6g_mb_lib.t6g(sch_1):page55_i386@pure_quanta.q_res(chips)',
 PATH='I386',
 DRAWING='@T6G_MB_LIB.T6G(SCH_1):PAGE55',
 WATTAGE='1/16W',
 TOLERANCE='1%',
 MATERIAL='CHIP',
 PHYS_PAGE='55',
 XY='(-4900,1900)',
 ROT='2',
 VER='2',
 PACK_TYPE='0402LF',
 LOCATION='R5103',
 CDS_LIB='pure_quanta',
 CDS_PART_NAME='Q_RES_0402LF-49.9,1%,1/16W,CHIP,CS04992FB07',
 PART_NUMBER='CS04992FB07',
 VALUE='49.9',
 PRIM_FILE='./archive_libs/logical/q_res/chips/chips.prt';

PART_NAME
 R5234 'Q_RES_0402LF-0,5%,1/16W,CHIP,CS00002JB13':;

SECTION_NUMBER 1
 '@T6G_MB_LIB.T6G(SCH_1):PAGE358_I91@PURE_QUANTA.Q_RES(CHIPS)':
 C_PATH='@t6g_mb_lib.t6g(sch_1):page358_i91@pure_quanta.q_res(chips)',
 P_PATH='@t6g_mb_lib.t6g(sch_1):page234_i91@pure_quanta.q_res(chips)',
 PATH='I91',
 DRAWING='@T6G_MB_LIB.T6G(SCH_1):PAGE358',
 WATTAGE='1/16W',
 TOLERANCE='5%',
 MATERIAL='CHIP',
 PHYS_PAGE='234',
 XY='(1375,225)',
 ROT='0',
 VER='1',
 PACK_TYPE='0402LF',
 LOCATION='R5234',
 CDS_LIB='pure_quanta',
 CDS_PART_NAME='Q_RES_0402LF-0,5%,1/16W,CHIP,CS00002JB13',
 PART_NUMBER='CS00002JB13',
 VALUE='0',
 PRIM_FILE='./archive_libs/logical/q_res/chips/chips.prt';

PART_NAME
 R5236 'Q_RES_0402LF-0,5%,1/16W,CHIP,CS00002JB13':;

SECTION_NUMBER 1
 '@T6G_MB_LIB.T6G(SCH_1):PAGE358_I90@PURE_QUANTA.Q_RES(CHIPS)':
 C_PATH='@t6g_mb_lib.t6g(sch_1):page358_i90@pure_quanta.q_res(chips)',
 P_PATH='@t6g_mb_lib.t6g(sch_1):page234_i90@pure_quanta.q_res(chips)',
 PATH='I90',
 DRAWING='@T6G_MB_LIB.T6G(SCH_1):PAGE358',
 WATTAGE='1/16W',
 TOLERANCE='5%',
 MATERIAL='CHIP',
 PHYS_PAGE='234',
 XY='(1375,175)',
 ROT='0',
 VER='1',
 PACK_TYPE='0402LF',
 LOCATION='R5236',
 CDS_LIB='pure_quanta',
 CDS_PART_NAME='Q_RES_0402LF-0,5%,1/16W,CHIP,CS00002JB13',
 PART_NUMBER='CS00002JB13',
 VALUE='0',
 PRIM_FILE='./archive_libs/logical/q_res/chips/chips.prt';

PART_NAME
 R5238 'Q_RES_0402LF-3.9K,5%,1/16W,EMPTY,CS23902JB04':
 ROOM='USB2 BOM2';

SECTION_NUMBER 1
 '@T6G_MB_LIB.T6G(SCH_1):PAGE358_I83@PURE_QUANTA.Q_RES(CHIPS)':
 C_PATH='@t6g_mb_lib.t6g(sch_1):page358_i83@pure_quanta.q_res(chips)',
 P_PATH='@t6g_mb_lib.t6g(sch_1):page234_i83@pure_quanta.q_res(chips)',
 PATH='I83',
 DRAWING='@T6G_MB_LIB.T6G(SCH_1):PAGE358',
 WATTAGE='1/16W',
 TOLERANCE='5%',
 MATERIAL='EMPTY',
 PHYS_PAGE='234',
 XY='(-675,-250)',
 ROT='0',
 VER='2',
 PACK_TYPE='0402LF',
 LOCATION='R5238',
 CDS_LIB='pure_quanta',
 CDS_PART_NAME='Q_RES_0402LF-3.9K,5%,1/16W,EMPTY,CS23902JB04',
 ROOM='USB2 BOM2',
 PART_NUMBER='CS23902JB04',
 VALUE='3.9K',
 PRIM_FILE='./archive_libs/logical/q_res/chips/chips.prt';

PART_NAME
 R5377 'Q_RES_0402LF-0,5%,1/16W,CHIP,CS00002JB13':;

SECTION_NUMBER 1
 '@T6G_MB_LIB.T6G(SCH_1):PAGE345_I62@PURE_QUANTA.Q_RES(CHIPS)':
 C_PATH='@t6g_mb_lib.t6g(sch_1):page345_i62@pure_quanta.q_res(chips)',
 P_PATH='@t6g_mb_lib.t6g(sch_1):page144_i62@pure_quanta.q_res(chips)',
 PATH='I62',
 DRAWING='@T6G_MB_LIB.T6G(SCH_1):PAGE345',
 WATTAGE='1/16W',
 TOLERANCE='5%',
 MATERIAL='CHIP',
 PHYS_PAGE='144',
 XY='(10950,175)',
 ROT='0',
 VER='1',
 PACK_TYPE='0402LF',
 LOCATION='R5377',
 CDS_LIB='pure_quanta',
 CDS_PART_NAME='Q_RES_0402LF-0,5%,1/16W,CHIP,CS00002JB13',
 PART_NUMBER='CS00002JB13',
 VALUE='0',
 PRIM_FILE='./archive_libs/logical/q_res/chips/chips.prt';

PART_NAME
 R5487 'Q_RES_0402LF-0,5%,1/16W,EMPTY,CS00002JB13':
 ROOM='NIC_P3V3_BOM1';

SECTION_NUMBER 1
 '@T6G_MB_LIB.T6G(SCH_1):PAGE338_I126@PURE_QUANTA.Q_RES(CHIPS)':
 C_PATH='@t6g_mb_lib.t6g(sch_1):page338_i126@pure_quanta.q_res(chips)',
 P_PATH='@t6g_mb_lib.t6g(sch_1):page134_i126@pure_quanta.q_res(chips)',
 PATH='I126',
 DRAWING='@T6G_MB_LIB.T6G(SCH_1):PAGE338',
 WATTAGE='1/16W',
 TOLERANCE='5%',
 MATERIAL='EMPTY',
 PHYS_PAGE='134',
 XY='(3275,11825)',
 ROT='0',
 VER='1',
 PACK_TYPE='0402LF',
 LOCATION='R5487',
 CDS_LIB='pure_quanta',
 CDS_PART_NAME='Q_RES_0402LF-0,5%,1/16W,EMPTY,CS00002JB13',
 ROOM='NIC_P3V3_BOM1',
 PART_NUMBER='CS00002JB13',
 VALUE='0',
 PRIM_FILE='./archive_libs/logical/q_res/chips/chips.prt';

PART_NAME
 R6000 'Q_RES_0402LF-0,5%,1/16W,CHIP,CS00002JB13':;

SECTION_NUMBER 1
 '@T6G_MB_LIB.T6G(SCH_1):PAGE348_I123@PURE_QUANTA.Q_RES(CHIPS)':
 C_PATH='@t6g_mb_lib.t6g(sch_1):page348_i123@pure_quanta.q_res(chips)',
 P_PATH='@t6g_mb_lib.t6g(sch_1):page150_i123@pure_quanta.q_res(chips)',
 PATH='I123',
 DRAWING='@T6G_MB_LIB.T6G(SCH_1):PAGE348',
 BOM_COST='MEM',
 WATTAGE='1/16W',
 TOLERANCE='5%',
 MATERIAL='CHIP',
 PHYS_PAGE='150',
 XY='(-14425,9275)',
 ROT='2',
 VER='1',
 PACK_TYPE='0402LF',
 LOCATION='R6000',
 CDS_LIB='pure_quanta',
 CDS_PART_NAME='Q_RES_0402LF-0,5%,1/16W,CHIP,CS00002JB13',
 PART_NUMBER='CS00002JB13',
 VALUE='0',
 PRIM_FILE='./archive_libs/logical/q_res/chips/chips.prt';

PART_NAME
 R6001 'Q_RES_0402LF-0,5%,1/16W,CHIP,CS00002JB13':;

SECTION_NUMBER 1
 '@T6G_MB_LIB.T6G(SCH_1):PAGE348_I124@PURE_QUANTA.Q_RES(CHIPS)':
 C_PATH='@t6g_mb_lib.t6g(sch_1):page348_i124@pure_quanta.q_res(chips)',
 P_PATH='@t6g_mb_lib.t6g(sch_1):page150_i124@pure_quanta.q_res(chips)',
 PATH='I124',
 DRAWING='@T6G_MB_LIB.T6G(SCH_1):PAGE348',
 BOM_COST='MEM',
 WATTAGE='1/16W',
 TOLERANCE='5%',
 MATERIAL='CHIP',
 PHYS_PAGE='150',
 XY='(-14425,9225)',
 ROT='2',
 VER='1',
 PACK_TYPE='0402LF',
 LOCATION='R6001',
 CDS_LIB='pure_quanta',
 CDS_PART_NAME='Q_RES_0402LF-0,5%,1/16W,CHIP,CS00002JB13',
 PART_NUMBER='CS00002JB13',
 VALUE='0',
 PRIM_FILE='./archive_libs/logical/q_res/chips/chips.prt';

PART_NAME
 R6002 'Q_RES_0402LF-0,5%,1/16W,CHIP,CS00002JB13':;

SECTION_NUMBER 1
 '@T6G_MB_LIB.T6G(SCH_1):PAGE348_I122@PURE_QUANTA.Q_RES(CHIPS)':
 C_PATH='@t6g_mb_lib.t6g(sch_1):page348_i122@pure_quanta.q_res(chips)',
 P_PATH='@t6g_mb_lib.t6g(sch_1):page150_i122@pure_quanta.q_res(chips)',
 PATH='I122',
 DRAWING='@T6G_MB_LIB.T6G(SCH_1):PAGE348',
 BOM_COST='MEM',
 WATTAGE='1/16W',
 TOLERANCE='5%',
 MATERIAL='CHIP',
 PHYS_PAGE='150',
 XY='(-14425,9175)',
 ROT='2',
 VER='1',
 PACK_TYPE='0402LF',
 LOCATION='R6002',
 CDS_LIB='pure_quanta',
 CDS_PART_NAME='Q_RES_0402LF-0,5%,1/16W,CHIP,CS00002JB13',
 PART_NUMBER='CS00002JB13',
 VALUE='0',
 PRIM_FILE='./archive_libs/logical/q_res/chips/chips.prt';

PART_NAME
 R6003 'Q_RES_0402LF-0,5%,1/16W,CHIP,CS00002JB13':;

SECTION_NUMBER 1
 '@T6G_MB_LIB.T6G(SCH_1):PAGE348_I121@PURE_QUANTA.Q_RES(CHIPS)':
 C_PATH='@t6g_mb_lib.t6g(sch_1):page348_i121@pure_quanta.q_res(chips)',
 P_PATH='@t6g_mb_lib.t6g(sch_1):page150_i121@pure_quanta.q_res(chips)',
 PATH='I121',
 DRAWING='@T6G_MB_LIB.T6G(SCH_1):PAGE348',
 BOM_COST='MEM',
 WATTAGE='1/16W',
 TOLERANCE='5%',
 MATERIAL='CHIP',
 PHYS_PAGE='150',
 XY='(-14425,9125)',
 ROT='2',
 VER='1',
 PACK_TYPE='0402LF',
 LOCATION='R6003',
 CDS_LIB='pure_quanta',
 CDS_PART_NAME='Q_RES_0402LF-0,5%,1/16W,CHIP,CS00002JB13',
 PART_NUMBER='CS00002JB13',
 VALUE='0',
 PRIM_FILE='./archive_libs/logical/q_res/chips/chips.prt';

PART_NAME
 R6004 'Q_RES_0402LF-0,5%,1/16W,CHIP,CS00002JB13':;

SECTION_NUMBER 1
 '@T6G_MB_LIB.T6G(SCH_1):PAGE348_I120@PURE_QUANTA.Q_RES(CHIPS)':
 C_PATH='@t6g_mb_lib.t6g(sch_1):page348_i120@pure_quanta.q_res(chips)',
 P_PATH='@t6g_mb_lib.t6g(sch_1):page150_i120@pure_quanta.q_res(chips)',
 PATH='I120',
 DRAWING='@T6G_MB_LIB.T6G(SCH_1):PAGE348',
 BOM_COST='MEM',
 WATTAGE='1/16W',
 TOLERANCE='5%',
 MATERIAL='CHIP',
 PHYS_PAGE='150',
 XY='(-14425,9075)',
 ROT='2',
 VER='1',
 PACK_TYPE='0402LF',
 LOCATION='R6004',
 CDS_LIB='pure_quanta',
 CDS_PART_NAME='Q_RES_0402LF-0,5%,1/16W,CHIP,CS00002JB13',
 PART_NUMBER='CS00002JB13',
 VALUE='0',
 PRIM_FILE='./archive_libs/logical/q_res/chips/chips.prt';

PART_NAME
 R6005 'Q_RES_0402LF-0,5%,1/16W,CHIP,CS00002JB13':;

SECTION_NUMBER 1
 '@T6G_MB_LIB.T6G(SCH_1):PAGE348_I118@PURE_QUANTA.Q_RES(CHIPS)':
 C_PATH='@t6g_mb_lib.t6g(sch_1):page348_i118@pure_quanta.q_res(chips)',
 P_PATH='@t6g_mb_lib.t6g(sch_1):page150_i118@pure_quanta.q_res(chips)',
 PATH='I118',
 DRAWING='@T6G_MB_LIB.T6G(SCH_1):PAGE348',
 BOM_COST='MEM',
 WATTAGE='1/16W',
 TOLERANCE='5%',
 MATERIAL='CHIP',
 PHYS_PAGE='150',
 XY='(-14425,9025)',
 ROT='2',
 VER='1',
 PACK_TYPE='0402LF',
 LOCATION='R6005',
 CDS_LIB='pure_quanta',
 CDS_PART_NAME='Q_RES_0402LF-0,5%,1/16W,CHIP,CS00002JB13',
 PART_NUMBER='CS00002JB13',
 VALUE='0',
 PRIM_FILE='./archive_libs/logical/q_res/chips/chips.prt';

PART_NAME
 R6006 'Q_RES_0402LF-0,5%,1/16W,CHIP,CS00002JB13':;

SECTION_NUMBER 1
 '@T6G_MB_LIB.T6G(SCH_1):PAGE348_I117@PURE_QUANTA.Q_RES(CHIPS)':
 C_PATH='@t6g_mb_lib.t6g(sch_1):page348_i117@pure_quanta.q_res(chips)',
 P_PATH='@t6g_mb_lib.t6g(sch_1):page150_i117@pure_quanta.q_res(chips)',
 PATH='I117',
 DRAWING='@T6G_MB_LIB.T6G(SCH_1):PAGE348',
 BOM_COST='MEM',
 WATTAGE='1/16W',
 TOLERANCE='5%',
 MATERIAL='CHIP',
 PHYS_PAGE='150',
 XY='(-14425,8975)',
 ROT='2',
 VER='1',
 PACK_TYPE='0402LF',
 LOCATION='R6006',
 CDS_LIB='pure_quanta',
 CDS_PART_NAME='Q_RES_0402LF-0,5%,1/16W,CHIP,CS00002JB13',
 PART_NUMBER='CS00002JB13',
 VALUE='0',
 PRIM_FILE='./archive_libs/logical/q_res/chips/chips.prt';

PART_NAME
 R6007 'Q_RES_0402LF-0,5%,1/16W,CHIP,CS00002JB13':;

SECTION_NUMBER 1
 '@T6G_MB_LIB.T6G(SCH_1):PAGE348_I119@PURE_QUANTA.Q_RES(CHIPS)':
 C_PATH='@t6g_mb_lib.t6g(sch_1):page348_i119@pure_quanta.q_res(chips)',
 P_PATH='@t6g_mb_lib.t6g(sch_1):page150_i119@pure_quanta.q_res(chips)',
 PATH='I119',
 DRAWING='@T6G_MB_LIB.T6G(SCH_1):PAGE348',
 BOM_COST='MEM',
 WATTAGE='1/16W',
 TOLERANCE='5%',
 MATERIAL='CHIP',
 PHYS_PAGE='150',
 XY='(-14425,8925)',
 ROT='2',
 VER='1',
 PACK_TYPE='0402LF',
 LOCATION='R6007',
 CDS_LIB='pure_quanta',
 CDS_PART_NAME='Q_RES_0402LF-0,5%,1/16W,CHIP,CS00002JB13',
 PART_NUMBER='CS00002JB13',
 VALUE='0',
 PRIM_FILE='./archive_libs/logical/q_res/chips/chips.prt';

PART_NAME
 R6008 'Q_RES_0402LF-0,5%,1/16W,CHIP,CS00002JB13':;

SECTION_NUMBER 1
 '@T6G_MB_LIB.T6G(SCH_1):PAGE348_I135@PURE_QUANTA.Q_RES(CHIPS)':
 C_PATH='@t6g_mb_lib.t6g(sch_1):page348_i135@pure_quanta.q_res(chips)',
 P_PATH='@t6g_mb_lib.t6g(sch_1):page150_i135@pure_quanta.q_res(chips)',
 PATH='I135',
 DRAWING='@T6G_MB_LIB.T6G(SCH_1):PAGE348',
 BOM_COST='MEM',
 WATTAGE='1/16W',
 TOLERANCE='5%',
 MATERIAL='CHIP',
 PHYS_PAGE='150',
 XY='(-10300,7175)',
 ROT='2',
 VER='1',
 PACK_TYPE='0402LF',
 LOCATION='R6008',
 CDS_LIB='pure_quanta',
 CDS_PART_NAME='Q_RES_0402LF-0,5%,1/16W,CHIP,CS00002JB13',
 PART_NUMBER='CS00002JB13',
 VALUE='0',
 PRIM_FILE='./archive_libs/logical/q_res/chips/chips.prt';

PART_NAME
 R6009 'Q_RES_0402LF-0,5%,1/16W,CHIP,CS00002JB13':;

SECTION_NUMBER 1
 '@T6G_MB_LIB.T6G(SCH_1):PAGE348_I134@PURE_QUANTA.Q_RES(CHIPS)':
 C_PATH='@t6g_mb_lib.t6g(sch_1):page348_i134@pure_quanta.q_res(chips)',
 P_PATH='@t6g_mb_lib.t6g(sch_1):page150_i134@pure_quanta.q_res(chips)',
 PATH='I134',
 DRAWING='@T6G_MB_LIB.T6G(SCH_1):PAGE348',
 BOM_COST='MEM',
 WATTAGE='1/16W',
 TOLERANCE='5%',
 MATERIAL='CHIP',
 PHYS_PAGE='150',
 XY='(-10300,7125)',
 ROT='2',
 VER='1',
 PACK_TYPE='0402LF',
 LOCATION='R6009',
 CDS_LIB='pure_quanta',
 CDS_PART_NAME='Q_RES_0402LF-0,5%,1/16W,CHIP,CS00002JB13',
 PART_NUMBER='CS00002JB13',
 VALUE='0',
 PRIM_FILE='./archive_libs/logical/q_res/chips/chips.prt';

PART_NAME
 R6010 'Q_RES_0402LF-0,5%,1/16W,CHIP,CS00002JB13':;

SECTION_NUMBER 1
 '@T6G_MB_LIB.T6G(SCH_1):PAGE348_I133@PURE_QUANTA.Q_RES(CHIPS)':
 C_PATH='@t6g_mb_lib.t6g(sch_1):page348_i133@pure_quanta.q_res(chips)',
 P_PATH='@t6g_mb_lib.t6g(sch_1):page150_i133@pure_quanta.q_res(chips)',
 PATH='I133',
 DRAWING='@T6G_MB_LIB.T6G(SCH_1):PAGE348',
 BOM_COST='MEM',
 WATTAGE='1/16W',
 TOLERANCE='5%',
 MATERIAL='CHIP',
 PHYS_PAGE='150',
 XY='(-10300,7075)',
 ROT='2',
 VER='1',
 PACK_TYPE='0402LF',
 LOCATION='R6010',
 CDS_LIB='pure_quanta',
 CDS_PART_NAME='Q_RES_0402LF-0,5%,1/16W,CHIP,CS00002JB13',
 PART_NUMBER='CS00002JB13',
 VALUE='0',
 PRIM_FILE='./archive_libs/logical/q_res/chips/chips.prt';

PART_NAME
 R6011 'Q_RES_0402LF-0,5%,1/16W,CHIP,CS00002JB13':;

SECTION_NUMBER 1
 '@T6G_MB_LIB.T6G(SCH_1):PAGE348_I132@PURE_QUANTA.Q_RES(CHIPS)':
 C_PATH='@t6g_mb_lib.t6g(sch_1):page348_i132@pure_quanta.q_res(chips)',
 P_PATH='@t6g_mb_lib.t6g(sch_1):page150_i132@pure_quanta.q_res(chips)',
 PATH='I132',
 DRAWING='@T6G_MB_LIB.T6G(SCH_1):PAGE348',
 BOM_COST='MEM',
 WATTAGE='1/16W',
 TOLERANCE='5%',
 MATERIAL='CHIP',
 PHYS_PAGE='150',
 XY='(-10300,7025)',
 ROT='2',
 VER='1',
 PACK_TYPE='0402LF',
 LOCATION='R6011',
 CDS_LIB='pure_quanta',
 CDS_PART_NAME='Q_RES_0402LF-0,5%,1/16W,CHIP,CS00002JB13',
 PART_NUMBER='CS00002JB13',
 VALUE='0',
 PRIM_FILE='./archive_libs/logical/q_res/chips/chips.prt';

PART_NAME
 R6012 'Q_RES_0402LF-0,5%,1/16W,CHIP,CS00002JB13':;

SECTION_NUMBER 1
 '@T6G_MB_LIB.T6G(SCH_1):PAGE348_I131@PURE_QUANTA.Q_RES(CHIPS)':
 C_PATH='@t6g_mb_lib.t6g(sch_1):page348_i131@pure_quanta.q_res(chips)',
 P_PATH='@t6g_mb_lib.t6g(sch_1):page150_i131@pure_quanta.q_res(chips)',
 PATH='I131',
 DRAWING='@T6G_MB_LIB.T6G(SCH_1):PAGE348',
 BOM_COST='MEM',
 WATTAGE='1/16W',
 TOLERANCE='5%',
 MATERIAL='CHIP',
 PHYS_PAGE='150',
 XY='(-10300,6925)',
 ROT='2',
 VER='1',
 PACK_TYPE='0402LF',
 LOCATION='R6012',
 CDS_LIB='pure_quanta',
 CDS_PART_NAME='Q_RES_0402LF-0,5%,1/16W,CHIP,CS00002JB13',
 PART_NUMBER='CS00002JB13',
 VALUE='0',
 PRIM_FILE='./archive_libs/logical/q_res/chips/chips.prt';

PART_NAME
 R6013 'Q_RES_0402LF-0,5%,1/16W,CHIP,CS00002JB13':;

SECTION_NUMBER 1
 '@T6G_MB_LIB.T6G(SCH_1):PAGE348_I130@PURE_QUANTA.Q_RES(CHIPS)':
 C_PATH='@t6g_mb_lib.t6g(sch_1):page348_i130@pure_quanta.q_res(chips)',
 P_PATH='@t6g_mb_lib.t6g(sch_1):page150_i130@pure_quanta.q_res(chips)',
 PATH='I130',
 DRAWING='@T6G_MB_LIB.T6G(SCH_1):PAGE348',
 BOM_COST='MEM',
 WATTAGE='1/16W',
 TOLERANCE='5%',
 MATERIAL='CHIP',
 PHYS_PAGE='150',
 XY='(-10300,6875)',
 ROT='2',
 VER='1',
 PACK_TYPE='0402LF',
 LOCATION='R6013',
 CDS_LIB='pure_quanta',
 CDS_PART_NAME='Q_RES_0402LF-0,5%,1/16W,CHIP,CS00002JB13',
 PART_NUMBER='CS00002JB13',
 VALUE='0',
 PRIM_FILE='./archive_libs/logical/q_res/chips/chips.prt';

PART_NAME
 R6014 'Q_RES_0402LF-0,5%,1/16W,CHIP,CS00002JB13':;

SECTION_NUMBER 1
 '@T6G_MB_LIB.T6G(SCH_1):PAGE348_I128@PURE_QUANTA.Q_RES(CHIPS)':
 C_PATH='@t6g_mb_lib.t6g(sch_1):page348_i128@pure_quanta.q_res(chips)',
 P_PATH='@t6g_mb_lib.t6g(sch_1):page150_i128@pure_quanta.q_res(chips)',
 PATH='I128',
 DRAWING='@T6G_MB_LIB.T6G(SCH_1):PAGE348',
 BOM_COST='MEM',
 WATTAGE='1/16W',
 TOLERANCE='5%',
 MATERIAL='CHIP',
 PHYS_PAGE='150',
 XY='(-10300,6825)',
 ROT='2',
 VER='1',
 PACK_TYPE='0402LF',
 LOCATION='R6014',
 CDS_LIB='pure_quanta',
 CDS_PART_NAME='Q_RES_0402LF-0,5%,1/16W,CHIP,CS00002JB13',
 PART_NUMBER='CS00002JB13',
 VALUE='0',
 PRIM_FILE='./archive_libs/logical/q_res/chips/chips.prt';

PART_NAME
 R6015 'Q_RES_0402LF-0,5%,1/16W,CHIP,CS00002JB13':;

SECTION_NUMBER 1
 '@T6G_MB_LIB.T6G(SCH_1):PAGE348_I129@PURE_QUANTA.Q_RES(CHIPS)':
 C_PATH='@t6g_mb_lib.t6g(sch_1):page348_i129@pure_quanta.q_res(chips)',
 P_PATH='@t6g_mb_lib.t6g(sch_1):page150_i129@pure_quanta.q_res(chips)',
 PATH='I129',
 DRAWING='@T6G_MB_LIB.T6G(SCH_1):PAGE348',
 BOM_COST='MEM',
 WATTAGE='1/16W',
 TOLERANCE='5%',
 MATERIAL='CHIP',
 PHYS_PAGE='150',
 XY='(-10300,6775)',
 ROT='2',
 VER='1',
 PACK_TYPE='0402LF',
 LOCATION='R6015',
 CDS_LIB='pure_quanta',
 CDS_PART_NAME='Q_RES_0402LF-0,5%,1/16W,CHIP,CS00002JB13',
 PART_NUMBER='CS00002JB13',
 VALUE='0',
 PRIM_FILE='./archive_libs/logical/q_res/chips/chips.prt';

PART_NAME
 R6016 'Q_RES_0402LF-2K,5%,1/16W,EMPTY,TMP_QCS22002JB29':;

SECTION_NUMBER 1
 '@T6G_MB_LIB.T6G(SCH_1):PAGE349_I29@PURE_QUANTA.Q_RES(CHIPS)':
 C_PATH='@t6g_mb_lib.t6g(sch_1):page349_i29@pure_quanta.q_res(chips)',
 P_PATH='@t6g_mb_lib.t6g(sch_1):page151_i29@pure_quanta.q_res(chips)',
 PATH='I29',
 DRAWING='@T6G_MB_LIB.T6G(SCH_1):PAGE349',
 WATTAGE='1/16W',
 TOLERANCE='5%',
 MATERIAL='EMPTY',
 PHYS_PAGE='151',
 XY='(-2100,5800)',
 ROT='0',
 VER='1',
 PACK_TYPE='0402LF',
 LOCATION='R6016',
 CDS_LIB='pure_quanta',
 CDS_PART_NAME='Q_RES_0402LF-2K,5%,1/16W,EMPTY,TMP_QCS22002JB29',
 PART_NUMBER='TMP_QCS22002JB29',
 VALUE='2K',
 PRIM_FILE='./archive_libs/logical/q_res/chips/chips.prt';

PART_NAME
 R6017 'Q_RES_0402LF-2K,5%,1/16W,EMPTY,TMP_QCS22002JB29':;

SECTION_NUMBER 1
 '@T6G_MB_LIB.T6G(SCH_1):PAGE349_I28@PURE_QUANTA.Q_RES(CHIPS)':
 C_PATH='@t6g_mb_lib.t6g(sch_1):page349_i28@pure_quanta.q_res(chips)',
 P_PATH='@t6g_mb_lib.t6g(sch_1):page151_i28@pure_quanta.q_res(chips)',
 PATH='I28',
 DRAWING='@T6G_MB_LIB.T6G(SCH_1):PAGE349',
 WATTAGE='1/16W',
 TOLERANCE='5%',
 MATERIAL='EMPTY',
 PHYS_PAGE='151',
 XY='(-2100,5750)',
 ROT='0',
 VER='1',
 PACK_TYPE='0402LF',
 LOCATION='R6017',
 CDS_LIB='pure_quanta',
 CDS_PART_NAME='Q_RES_0402LF-2K,5%,1/16W,EMPTY,TMP_QCS22002JB29',
 PART_NUMBER='TMP_QCS22002JB29',
 VALUE='2K',
 PRIM_FILE='./archive_libs/logical/q_res/chips/chips.prt';

PART_NAME
 R6018 'Q_RES_0402LF-2K,5%,1/16W,EMPTY,TMP_QCS22002JB29':;

SECTION_NUMBER 1
 '@T6G_MB_LIB.T6G(SCH_1):PAGE349_I27@PURE_QUANTA.Q_RES(CHIPS)':
 C_PATH='@t6g_mb_lib.t6g(sch_1):page349_i27@pure_quanta.q_res(chips)',
 P_PATH='@t6g_mb_lib.t6g(sch_1):page151_i27@pure_quanta.q_res(chips)',
 PATH='I27',
 DRAWING='@T6G_MB_LIB.T6G(SCH_1):PAGE349',
 WATTAGE='1/16W',
 TOLERANCE='5%',
 MATERIAL='EMPTY',
 PHYS_PAGE='151',
 XY='(-2100,5700)',
 ROT='0',
 VER='1',
 PACK_TYPE='0402LF',
 LOCATION='R6018',
 CDS_LIB='pure_quanta',
 CDS_PART_NAME='Q_RES_0402LF-2K,5%,1/16W,EMPTY,TMP_QCS22002JB29',
 PART_NUMBER='TMP_QCS22002JB29',
 VALUE='2K',
 PRIM_FILE='./archive_libs/logical/q_res/chips/chips.prt';

PART_NAME
 R6019 'Q_RES_0402LF-2K,5%,1/16W,EMPTY,TMP_QCS22002JB29':;

SECTION_NUMBER 1
 '@T6G_MB_LIB.T6G(SCH_1):PAGE349_I25@PURE_QUANTA.Q_RES(CHIPS)':
 C_PATH='@t6g_mb_lib.t6g(sch_1):page349_i25@pure_quanta.q_res(chips)',
 P_PATH='@t6g_mb_lib.t6g(sch_1):page151_i25@pure_quanta.q_res(chips)',
 PATH='I25',
 DRAWING='@T6G_MB_LIB.T6G(SCH_1):PAGE349',
 WATTAGE='1/16W',
 TOLERANCE='5%',
 MATERIAL='EMPTY',
 PHYS_PAGE='151',
 XY='(-2100,5650)',
 ROT='0',
 VER='1',
 PACK_TYPE='0402LF',
 LOCATION='R6019',
 CDS_LIB='pure_quanta',
 CDS_PART_NAME='Q_RES_0402LF-2K,5%,1/16W,EMPTY,TMP_QCS22002JB29',
 PART_NUMBER='TMP_QCS22002JB29',
 VALUE='2K',
 PRIM_FILE='./archive_libs/logical/q_res/chips/chips.prt';

PART_NAME
 R6020 'Q_RES_0402LF-2K,5%,1/16W,EMPTY,TMP_QCS22002JB29':;

SECTION_NUMBER 1
 '@T6G_MB_LIB.T6G(SCH_1):PAGE349_I24@PURE_QUANTA.Q_RES(CHIPS)':
 C_PATH='@t6g_mb_lib.t6g(sch_1):page349_i24@pure_quanta.q_res(chips)',
 P_PATH='@t6g_mb_lib.t6g(sch_1):page151_i24@pure_quanta.q_res(chips)',
 PATH='I24',
 DRAWING='@T6G_MB_LIB.T6G(SCH_1):PAGE349',
 WATTAGE='1/16W',
 TOLERANCE='5%',
 MATERIAL='EMPTY',
 PHYS_PAGE='151',
 XY='(-2100,5600)',
 ROT='0',
 VER='1',
 PACK_TYPE='0402LF',
 LOCATION='R6020',
 CDS_LIB='pure_quanta',
 CDS_PART_NAME='Q_RES_0402LF-2K,5%,1/16W,EMPTY,TMP_QCS22002JB29',
 PART_NUMBER='TMP_QCS22002JB29',
 VALUE='2K',
 PRIM_FILE='./archive_libs/logical/q_res/chips/chips.prt';

PART_NAME
 R6021 'Q_RES_0402LF-2K,5%,1/16W,EMPTY,TMP_QCS22002JB29':;

SECTION_NUMBER 1
 '@T6G_MB_LIB.T6G(SCH_1):PAGE349_I22@PURE_QUANTA.Q_RES(CHIPS)':
 C_PATH='@t6g_mb_lib.t6g(sch_1):page349_i22@pure_quanta.q_res(chips)',
 P_PATH='@t6g_mb_lib.t6g(sch_1):page151_i22@pure_quanta.q_res(chips)',
 PATH='I22',
 DRAWING='@T6G_MB_LIB.T6G(SCH_1):PAGE349',
 WATTAGE='1/16W',
 TOLERANCE='5%',
 MATERIAL='EMPTY',
 PHYS_PAGE='151',
 XY='(-2100,5550)',
 ROT='0',
 VER='1',
 PACK_TYPE='0402LF',
 LOCATION='R6021',
 CDS_LIB='pure_quanta',
 CDS_PART_NAME='Q_RES_0402LF-2K,5%,1/16W,EMPTY,TMP_QCS22002JB29',
 PART_NUMBER='TMP_QCS22002JB29',
 VALUE='2K',
 PRIM_FILE='./archive_libs/logical/q_res/chips/chips.prt';

PART_NAME
 R6022 'Q_RES_0402LF-2K,5%,1/16W,EMPTY,TMP_QCS22002JB29':;

SECTION_NUMBER 1
 '@T6G_MB_LIB.T6G(SCH_1):PAGE349_I23@PURE_QUANTA.Q_RES(CHIPS)':
 C_PATH='@t6g_mb_lib.t6g(sch_1):page349_i23@pure_quanta.q_res(chips)',
 P_PATH='@t6g_mb_lib.t6g(sch_1):page151_i23@pure_quanta.q_res(chips)',
 PATH='I23',
 DRAWING='@T6G_MB_LIB.T6G(SCH_1):PAGE349',
 WATTAGE='1/16W',
 TOLERANCE='5%',
 MATERIAL='EMPTY',
 PHYS_PAGE='151',
 XY='(-2100,5500)',
 ROT='0',
 VER='1',
 PACK_TYPE='0402LF',
 LOCATION='R6022',
 CDS_LIB='pure_quanta',
 CDS_PART_NAME='Q_RES_0402LF-2K,5%,1/16W,EMPTY,TMP_QCS22002JB29',
 PART_NUMBER='TMP_QCS22002JB29',
 VALUE='2K',
 PRIM_FILE='./archive_libs/logical/q_res/chips/chips.prt';

PART_NAME
 R6023 'Q_RES_0402LF-2K,5%,1/16W,EMPTY,TMP_QCS22002JB29':;

SECTION_NUMBER 1
 '@T6G_MB_LIB.T6G(SCH_1):PAGE349_I21@PURE_QUANTA.Q_RES(CHIPS)':
 C_PATH='@t6g_mb_lib.t6g(sch_1):page349_i21@pure_quanta.q_res(chips)',
 P_PATH='@t6g_mb_lib.t6g(sch_1):page151_i21@pure_quanta.q_res(chips)',
 PATH='I21',
 DRAWING='@T6G_MB_LIB.T6G(SCH_1):PAGE349',
 WATTAGE='1/16W',
 TOLERANCE='5%',
 MATERIAL='EMPTY',
 PHYS_PAGE='151',
 XY='(-2100,5450)',
 ROT='0',
 VER='1',
 PACK_TYPE='0402LF',
 LOCATION='R6023',
 CDS_LIB='pure_quanta',
 CDS_PART_NAME='Q_RES_0402LF-2K,5%,1/16W,EMPTY,TMP_QCS22002JB29',
 PART_NUMBER='TMP_QCS22002JB29',
 VALUE='2K',
 PRIM_FILE='./archive_libs/logical/q_res/chips/chips.prt';

PART_NAME
 R6024 'Q_RES_0402LF-4.7K,5%,1/16W,EMPTY,CS24702JB10':;

SECTION_NUMBER 1
 '@T6G_MB_LIB.T6G(SCH_1):PAGE349_I20@PURE_QUANTA.Q_RES(CHIPS)':
 C_PATH='@t6g_mb_lib.t6g(sch_1):page349_i20@pure_quanta.q_res(chips)',
 P_PATH='@t6g_mb_lib.t6g(sch_1):page151_i20@pure_quanta.q_res(chips)',
 PATH='I20',
 DRAWING='@T6G_MB_LIB.T6G(SCH_1):PAGE349',
 WATTAGE='1/16W',
 TOLERANCE='5%',
 MATERIAL='EMPTY',
 PHYS_PAGE='151',
 XY='(-2100,5400)',
 ROT='0',
 VER='1',
 PACK_TYPE='0402LF',
 LOCATION='R6024',
 CDS_LIB='pure_quanta',
 CDS_PART_NAME='Q_RES_0402LF-4.7K,5%,1/16W,EMPTY,CS24702JB10',
 PART_NUMBER='CS24702JB10',
 VALUE='4.7K',
 PRIM_FILE='./archive_libs/logical/q_res/chips/chips.prt';

PART_NAME
 R6025 'Q_RES_0402LF-0,5%,1/16W,CHIP,CS00002JB13':;

SECTION_NUMBER 1
 '@T6G_MB_LIB.T6G(SCH_1):PAGE348_I43@PURE_QUANTA.Q_RES(CHIPS)':
 C_PATH='@t6g_mb_lib.t6g(sch_1):page348_i43@pure_quanta.q_res(chips)',
 P_PATH='@t6g_mb_lib.t6g(sch_1):page150_i43@pure_quanta.q_res(chips)',
 PATH='I43',
 DRAWING='@T6G_MB_LIB.T6G(SCH_1):PAGE348',
 BOM_COST='MEM',
 WATTAGE='1/16W',
 TOLERANCE='5%',
 MATERIAL='CHIP',
 PHYS_PAGE='150',
 XY='(-10300,6675)',
 ROT='2',
 VER='1',
 PACK_TYPE='0402LF',
 LOCATION='R6025',
 CDS_LIB='pure_quanta',
 CDS_PART_NAME='Q_RES_0402LF-0,5%,1/16W,CHIP,CS00002JB13',
 PART_NUMBER='CS00002JB13',
 VALUE='0',
 PRIM_FILE='./archive_libs/logical/q_res/chips/chips.prt';

PART_NAME
 R6026 'Q_RES_0402LF-0,5%,1/16W,CHIP,CS00002JB13':;

SECTION_NUMBER 1
 '@T6G_MB_LIB.T6G(SCH_1):PAGE348_I42@PURE_QUANTA.Q_RES(CHIPS)':
 C_PATH='@t6g_mb_lib.t6g(sch_1):page348_i42@pure_quanta.q_res(chips)',
 P_PATH='@t6g_mb_lib.t6g(sch_1):page150_i42@pure_quanta.q_res(chips)',
 PATH='I42',
 DRAWING='@T6G_MB_LIB.T6G(SCH_1):PAGE348',
 BOM_COST='MEM',
 WATTAGE='1/16W',
 TOLERANCE='5%',
 MATERIAL='CHIP',
 PHYS_PAGE='150',
 XY='(-10300,6625)',
 ROT='2',
 VER='1',
 PACK_TYPE='0402LF',
 LOCATION='R6026',
 CDS_LIB='pure_quanta',
 CDS_PART_NAME='Q_RES_0402LF-0,5%,1/16W,CHIP,CS00002JB13',
 PART_NUMBER='CS00002JB13',
 VALUE='0',
 PRIM_FILE='./archive_libs/logical/q_res/chips/chips.prt';

PART_NAME
 R6027 'Q_RES_0402LF-4.7K,5%,1/16W,EMPTY,CS24702JB10':;

SECTION_NUMBER 1
 '@T6G_MB_LIB.T6G(SCH_1):PAGE349_I32@PURE_QUANTA.Q_RES(CHIPS)':
 C_PATH='@t6g_mb_lib.t6g(sch_1):page349_i32@pure_quanta.q_res(chips)',
 P_PATH='@t6g_mb_lib.t6g(sch_1):page151_i32@pure_quanta.q_res(chips)',
 PATH='I32',
 DRAWING='@T6G_MB_LIB.T6G(SCH_1):PAGE349',
 WATTAGE='1/16W',
 TOLERANCE='5%',
 MATERIAL='EMPTY',
 PHYS_PAGE='151',
 XY='(-1600,4850)',
 ROT='0',
 VER='1',
 PACK_TYPE='0402LF',
 LOCATION='R6027',
 CDS_LIB='pure_quanta',
 CDS_PART_NAME='Q_RES_0402LF-4.7K,5%,1/16W,EMPTY,CS24702JB10',
 PART_NUMBER='CS24702JB10',
 VALUE='4.7K',
 PRIM_FILE='./archive_libs/logical/q_res/chips/chips.prt';

PART_NAME
 R6028 'Q_RES_0402LF-0,5%,1/16W,CHIP,CS00002JB13':;

SECTION_NUMBER 1
 '@T6G_MB_LIB.T6G(SCH_1):PAGE348_I174@PURE_QUANTA.Q_RES(CHIPS)':
 C_PATH='@t6g_mb_lib.t6g(sch_1):page348_i174@pure_quanta.q_res(chips)',
 P_PATH='@t6g_mb_lib.t6g(sch_1):page150_i174@pure_quanta.q_res(chips)',
 PATH='I174',
 DRAWING='@T6G_MB_LIB.T6G(SCH_1):PAGE348',
 WATTAGE='1/16W',
 TOLERANCE='5%',
 MATERIAL='CHIP',
 PHYS_PAGE='150',
 XY='(-8450,8475)',
 ROT='0',
 VER='2',
 PACK_TYPE='0402LF',
 LOCATION='R6028',
 CDS_LIB='pure_quanta',
 CDS_PART_NAME='Q_RES_0402LF-0,5%,1/16W,CHIP,CS00002JB13',
 PART_NUMBER='CS00002JB13',
 VALUE='0',
 PRIM_FILE='./archive_libs/logical/q_res/chips/chips.prt';

PART_NAME
 R6029 'Q_RES_0402LF-33,5%,1/16W,CHIP,CS03302JB10':;

SECTION_NUMBER 1
 '@T6G_MB_LIB.T6G(SCH_1):PAGE79_I65@PURE_QUANTA.Q_RES(CHIPS)':
 C_PATH='@t6g_mb_lib.t6g(sch_1):page79_i65@pure_quanta.q_res(chips)',
 P_PATH='@t6g_mb_lib.t6g(sch_1):page80_i65@pure_quanta.q_res(chips)',
 PATH='I65',
 DRAWING='@T6G_MB_LIB.T6G(SCH_1):PAGE79',
 BOM_COST='MEM',
 WATTAGE='1/16W',
 TOLERANCE='5%',
 MATERIAL='CHIP',
 PHYS_PAGE='80',
 XY='(-2775,2900)',
 ROT='2',
 VER='1',
 PACK_TYPE='0402LF',
 LOCATION='R6029',
 CDS_LIB='pure_quanta',
 CDS_PART_NAME='Q_RES_0402LF-33,5%,1/16W,CHIP,CS03302JB10',
 PART_NUMBER='CS03302JB10',
 VALUE='33',
 PRIM_FILE='./archive_libs/logical/q_res/chips/chips.prt';

PART_NAME
 R6030 'Q_RES_0402LF-33,5%,1/16W,CHIP,CS03302JB10':;

SECTION_NUMBER 1
 '@T6G_MB_LIB.T6G(SCH_1):PAGE79_I64@PURE_QUANTA.Q_RES(CHIPS)':
 C_PATH='@t6g_mb_lib.t6g(sch_1):page79_i64@pure_quanta.q_res(chips)',
 P_PATH='@t6g_mb_lib.t6g(sch_1):page80_i64@pure_quanta.q_res(chips)',
 PATH='I64',
 DRAWING='@T6G_MB_LIB.T6G(SCH_1):PAGE79',
 BOM_COST='MEM',
 WATTAGE='1/16W',
 TOLERANCE='5%',
 MATERIAL='CHIP',
 PHYS_PAGE='80',
 XY='(-2775,2850)',
 ROT='2',
 VER='1',
 PACK_TYPE='0402LF',
 LOCATION='R6030',
 CDS_LIB='pure_quanta',
 CDS_PART_NAME='Q_RES_0402LF-33,5%,1/16W,CHIP,CS03302JB10',
 PART_NUMBER='CS03302JB10',
 VALUE='33',
 PRIM_FILE='./archive_libs/logical/q_res/chips/chips.prt';

PART_NAME
 R6031 'Q_RES_0402LF-33,5%,1/16W,CHIP,CS03302JB10':;

SECTION_NUMBER 1
 '@T6G_MB_LIB.T6G(SCH_1):PAGE79_I55@PURE_QUANTA.Q_RES(CHIPS)':
 C_PATH='@t6g_mb_lib.t6g(sch_1):page79_i55@pure_quanta.q_res(chips)',
 P_PATH='@t6g_mb_lib.t6g(sch_1):page80_i55@pure_quanta.q_res(chips)',
 PATH='I55',
 DRAWING='@T6G_MB_LIB.T6G(SCH_1):PAGE79',
 BOM_COST='MEM',
 WATTAGE='1/16W',
 TOLERANCE='5%',
 MATERIAL='CHIP',
 PHYS_PAGE='80',
 XY='(-3825,1100)',
 ROT='2',
 VER='1',
 PACK_TYPE='0402LF',
 LOCATION='R6031',
 CDS_LIB='pure_quanta',
 CDS_PART_NAME='Q_RES_0402LF-33,5%,1/16W,CHIP,CS03302JB10',
 PART_NUMBER='CS03302JB10',
 VALUE='33',
 PRIM_FILE='./archive_libs/logical/q_res/chips/chips.prt';

PART_NAME
 R6032 'Q_RES_0402LF-0,5%,1/16W,CHIP,CS00002JB13':;

SECTION_NUMBER 1
 '@T6G_MB_LIB.T6G(SCH_1):PAGE348_I28@PURE_QUANTA.Q_RES(CHIPS)':
 C_PATH='@t6g_mb_lib.t6g(sch_1):page348_i28@pure_quanta.q_res(chips)',
 P_PATH='@t6g_mb_lib.t6g(sch_1):page150_i28@pure_quanta.q_res(chips)',
 PATH='I28',
 DRAWING='@T6G_MB_LIB.T6G(SCH_1):PAGE348',
 WATTAGE='1/16W',
 TOLERANCE='5%',
 MATERIAL='CHIP',
 PHYS_PAGE='150',
 XY='(-14950,6075)',
 ROT='0',
 VER='1',
 PACK_TYPE='0402LF',
 LOCATION='R6032',
 CDS_LIB='pure_quanta',
 CDS_PART_NAME='Q_RES_0402LF-0,5%,1/16W,CHIP,CS00002JB13',
 PART_NUMBER='CS00002JB13',
 VALUE='0',
 PRIM_FILE='./archive_libs/logical/q_res/chips/chips.prt';

PART_NAME
 R6033 'Q_RES_0402LF-0,5%,1/16W,CHIP,CS00002JB13':;

SECTION_NUMBER 1
 '@T6G_MB_LIB.T6G(SCH_1):PAGE348_I30@PURE_QUANTA.Q_RES(CHIPS)':
 C_PATH='@t6g_mb_lib.t6g(sch_1):page348_i30@pure_quanta.q_res(chips)',
 P_PATH='@t6g_mb_lib.t6g(sch_1):page150_i30@pure_quanta.q_res(chips)',
 PATH='I30',
 DRAWING='@T6G_MB_LIB.T6G(SCH_1):PAGE348',
 WATTAGE='1/16W',
 TOLERANCE='5%',
 MATERIAL='CHIP',
 PHYS_PAGE='150',
 XY='(-14950,6225)',
 ROT='0',
 VER='1',
 PACK_TYPE='0402LF',
 LOCATION='R6033',
 CDS_LIB='pure_quanta',
 CDS_PART_NAME='Q_RES_0402LF-0,5%,1/16W,CHIP,CS00002JB13',
 PART_NUMBER='CS00002JB13',
 VALUE='0',
 PRIM_FILE='./archive_libs/logical/q_res/chips/chips.prt';

PART_NAME
 R6034 'Q_RES_0402LF-1K,1%,1/16W,CHIP,CS21002FB06':;

SECTION_NUMBER 1
 '@T6G_MB_LIB.T6G(SCH_1):PAGE348_I18@PURE_QUANTA.Q_RES(CHIPS)':
 C_PATH='@t6g_mb_lib.t6g(sch_1):page348_i18@pure_quanta.q_res(chips)',
 P_PATH='@t6g_mb_lib.t6g(sch_1):page150_i18@pure_quanta.q_res(chips)',
 PATH='I18',
 DRAWING='@T6G_MB_LIB.T6G(SCH_1):PAGE348',
 WATTAGE='1/16W',
 TOLERANCE='1%',
 MATERIAL='CHIP',
 PHYS_PAGE='150',
 XY='(-15200,4700)',
 ROT='0',
 VER='2',
 PACK_TYPE='0402LF',
 LOCATION='R6034',
 CDS_LIB='pure_quanta',
 CDS_PART_NAME='Q_RES_0402LF-1K,1%,1/16W,CHIP,CS21002FB06',
 PART_NUMBER='CS21002FB06',
 VALUE='1K',
 PRIM_FILE='./archive_libs/logical/q_res/chips/chips.prt';

PART_NAME
 R6035 'Q_RES_0402LF-4.7K,5%,1/16W,EMPTY,CS24702JB10':;

SECTION_NUMBER 1
 '@T6G_MB_LIB.T6G(SCH_1):PAGE348_I17@PURE_QUANTA.Q_RES(CHIPS)':
 C_PATH='@t6g_mb_lib.t6g(sch_1):page348_i17@pure_quanta.q_res(chips)',
 P_PATH='@t6g_mb_lib.t6g(sch_1):page150_i17@pure_quanta.q_res(chips)',
 PATH='I17',
 DRAWING='@T6G_MB_LIB.T6G(SCH_1):PAGE348',
 WATTAGE='1/16W',
 TOLERANCE='5%',
 MATERIAL='EMPTY',
 PHYS_PAGE='150',
 XY='(-15200,4200)',
 ROT='0',
 VER='2',
 PACK_TYPE='0402LF',
 LOCATION='R6035',
 CDS_LIB='pure_quanta',
 CDS_PART_NAME='Q_RES_0402LF-4.7K,5%,1/16W,EMPTY,CS24702JB10',
 PART_NUMBER='CS24702JB10',
 VALUE='4.7K',
 PRIM_FILE='./archive_libs/logical/q_res/chips/chips.prt';

PART_NAME
 R6036 'Q_RES_0402LF-2K,1%,1/16W,EMPTY,CS22002FB07':;

SECTION_NUMBER 1
 '@T6G_MB_LIB.T6G(SCH_1):PAGE349_I131@PURE_QUANTA.Q_RES(CHIPS)':
 C_PATH='@t6g_mb_lib.t6g(sch_1):page349_i131@pure_quanta.q_res(chips)',
 P_PATH='@t6g_mb_lib.t6g(sch_1):page151_i131@pure_quanta.q_res(chips)',
 PATH='I131',
 DRAWING='@T6G_MB_LIB.T6G(SCH_1):PAGE349',
 WATTAGE='1/16W',
 TOLERANCE='1%',
 MATERIAL='EMPTY',
 PHYS_PAGE='151',
 XY='(4275,4525)',
 ROT='0',
 VER='1',
 PACK_TYPE='0402LF',
 LOCATION='R6036',
 CDS_LIB='pure_quanta',
 CDS_PART_NAME='Q_RES_0402LF-2K,1%,1/16W,EMPTY,CS22002FB07',
 PART_NUMBER='CS22002FB07',
 VALUE='2K',
 PRIM_FILE='./archive_libs/logical/q_res/chips/chips.prt';

PART_NAME
 R6037 'Q_RES_0402LF-2K,1%,1/16W,EMPTY,CS22002FB07':;

SECTION_NUMBER 1
 '@T6G_MB_LIB.T6G(SCH_1):PAGE349_I132@PURE_QUANTA.Q_RES(CHIPS)':
 C_PATH='@t6g_mb_lib.t6g(sch_1):page349_i132@pure_quanta.q_res(chips)',
 P_PATH='@t6g_mb_lib.t6g(sch_1):page151_i132@pure_quanta.q_res(chips)',
 PATH='I132',
 DRAWING='@T6G_MB_LIB.T6G(SCH_1):PAGE349',
 WATTAGE='1/16W',
 TOLERANCE='1%',
 MATERIAL='EMPTY',
 PHYS_PAGE='151',
 XY='(4275,4475)',
 ROT='0',
 VER='1',
 PACK_TYPE='0402LF',
 LOCATION='R6037',
 CDS_LIB='pure_quanta',
 CDS_PART_NAME='Q_RES_0402LF-2K,1%,1/16W,EMPTY,CS22002FB07',
 PART_NUMBER='CS22002FB07',
 VALUE='2K',
 PRIM_FILE='./archive_libs/logical/q_res/chips/chips.prt';

PART_NAME
 R6038 'Q_RES_0402LF-0,5%,1/16W,CHIP,CS00002JB13':;

SECTION_NUMBER 1
 '@T6G_MB_LIB.T6G(SCH_1):PAGE79_I21@PURE_QUANTA.Q_RES(CHIPS)':
 C_PATH='@t6g_mb_lib.t6g(sch_1):page79_i21@pure_quanta.q_res(chips)',
 P_PATH='@t6g_mb_lib.t6g(sch_1):page80_i21@pure_quanta.q_res(chips)',
 PATH='I21',
 DRAWING='@T6G_MB_LIB.T6G(SCH_1):PAGE79',
 BOM_COST='MEM',
 WATTAGE='1/16W',
 TOLERANCE='5%',
 MATERIAL='CHIP',
 PHYS_PAGE='80',
 XY='(-6850,3100)',
 ROT='2',
 VER='1',
 PACK_TYPE='0402LF',
 LOCATION='R6038',
 CDS_LIB='pure_quanta',
 CDS_PART_NAME='Q_RES_0402LF-0,5%,1/16W,CHIP,CS00002JB13',
 PART_NUMBER='CS00002JB13',
 VALUE='0',
 PRIM_FILE='./archive_libs/logical/q_res/chips/chips.prt';

PART_NAME
 R6039 'Q_RES_0402LF-0,5%,1/16W,CHIP,CS00002JB13':;

SECTION_NUMBER 1
 '@T6G_MB_LIB.T6G(SCH_1):PAGE79_I20@PURE_QUANTA.Q_RES(CHIPS)':
 C_PATH='@t6g_mb_lib.t6g(sch_1):page79_i20@pure_quanta.q_res(chips)',
 P_PATH='@t6g_mb_lib.t6g(sch_1):page80_i20@pure_quanta.q_res(chips)',
 PATH='I20',
 DRAWING='@T6G_MB_LIB.T6G(SCH_1):PAGE79',
 BOM_COST='MEM',
 WATTAGE='1/16W',
 TOLERANCE='5%',
 MATERIAL='CHIP',
 PHYS_PAGE='80',
 XY='(-6850,3050)',
 ROT='2',
 VER='1',
 PACK_TYPE='0402LF',
 LOCATION='R6039',
 CDS_LIB='pure_quanta',
 CDS_PART_NAME='Q_RES_0402LF-0,5%,1/16W,CHIP,CS00002JB13',
 PART_NUMBER='CS00002JB13',
 VALUE='0',
 PRIM_FILE='./archive_libs/logical/q_res/chips/chips.prt';

PART_NAME
 R6040 'Q_RES_0402LF-10K,5%,1/16W,CHIP,CS31002JB08':;

SECTION_NUMBER 1
 '@T6G_MB_LIB.T6G(SCH_1):PAGE144_I70@PURE_QUANTA.Q_RES(CHIPS)':
 C_PATH='@t6g_mb_lib.t6g(sch_1):page144_i70@pure_quanta.q_res(chips)',
 P_PATH='@t6g_mb_lib.t6g(sch_1):page167_i70@pure_quanta.q_res(chips)',
 PATH='I70',
 DRAWING='@T6G_MB_LIB.T6G(SCH_1):PAGE144',
 WATTAGE='1/16W',
 TOLERANCE='5%',
 MATERIAL='CHIP',
 PHYS_PAGE='167',
 XY='(-1000,1525)',
 ROT='2',
 VER='2',
 PACK_TYPE='0402LF',
 LOCATION='R6040',
 CDS_LIB='pure_quanta',
 CDS_PART_NAME='Q_RES_0402LF-10K,5%,1/16W,CHIP,CS31002JB08',
 PART_NUMBER='CS31002JB08',
 VALUE='10K',
 PRIM_FILE='./archive_libs/logical/q_res/chips/chips.prt';

PART_NAME
 R6041 'Q_RES_0402LF-100K,1%,1/16W,CHIP,CS41002FB09':;

SECTION_NUMBER 1
 '@T6G_MB_LIB.T6G(SCH_1):PAGE144_I69@PURE_QUANTA.Q_RES(CHIPS)':
 C_PATH='@t6g_mb_lib.t6g(sch_1):page144_i69@pure_quanta.q_res(chips)',
 P_PATH='@t6g_mb_lib.t6g(sch_1):page167_i69@pure_quanta.q_res(chips)',
 PATH='I69',
 DRAWING='@T6G_MB_LIB.T6G(SCH_1):PAGE144',
 WATTAGE='1/16W',
 TOLERANCE='1%',
 MATERIAL='CHIP',
 PHYS_PAGE='167',
 XY='(-1000,1150)',
 ROT='1',
 VER='1',
 PACK_TYPE='0402LF',
 LOCATION='R6041',
 CDS_LIB='pure_quanta',
 CDS_PART_NAME='Q_RES_0402LF-100K,1%,1/16W,CHIP,CS41002FB09',
 PART_NUMBER='CS41002FB09',
 VALUE='100K',
 PRIM_FILE='./archive_libs/logical/q_res/chips/chips.prt';

PART_NAME
 R6042 'Q_RES_0402LF-10K,5%,1/16W,CHIP,CS31002JB08':;

SECTION_NUMBER 1
 '@T6G_MB_LIB.T6G(SCH_1):PAGE144_I62@PURE_QUANTA.Q_RES(CHIPS)':
 C_PATH='@t6g_mb_lib.t6g(sch_1):page144_i62@pure_quanta.q_res(chips)',
 P_PATH='@t6g_mb_lib.t6g(sch_1):page167_i62@pure_quanta.q_res(chips)',
 PATH='I62',
 DRAWING='@T6G_MB_LIB.T6G(SCH_1):PAGE144',
 WATTAGE='1/16W',
 TOLERANCE='5%',
 MATERIAL='CHIP',
 PHYS_PAGE='167',
 XY='(-2425,1550)',
 ROT='2',
 VER='2',
 PACK_TYPE='0402LF',
 LOCATION='R6042',
 CDS_LIB='pure_quanta',
 CDS_PART_NAME='Q_RES_0402LF-10K,5%,1/16W,CHIP,CS31002JB08',
 PART_NUMBER='CS31002JB08',
 VALUE='10K',
 PRIM_FILE='./archive_libs/logical/q_res/chips/chips.prt';

PART_NAME
 R6043 'Q_RES_0402LF-100K,1%,1/16W,CHIP,CS41002FB09':;

SECTION_NUMBER 1
 '@T6G_MB_LIB.T6G(SCH_1):PAGE144_I61@PURE_QUANTA.Q_RES(CHIPS)':
 C_PATH='@t6g_mb_lib.t6g(sch_1):page144_i61@pure_quanta.q_res(chips)',
 P_PATH='@t6g_mb_lib.t6g(sch_1):page167_i61@pure_quanta.q_res(chips)',
 PATH='I61',
 DRAWING='@T6G_MB_LIB.T6G(SCH_1):PAGE144',
 WATTAGE='1/16W',
 TOLERANCE='1%',
 MATERIAL='CHIP',
 PHYS_PAGE='167',
 XY='(-2425,1175)',
 ROT='1',
 VER='1',
 PACK_TYPE='0402LF',
 LOCATION='R6043',
 CDS_LIB='pure_quanta',
 CDS_PART_NAME='Q_RES_0402LF-100K,1%,1/16W,CHIP,CS41002FB09',
 PART_NUMBER='CS41002FB09',
 VALUE='100K',
 PRIM_FILE='./archive_libs/logical/q_res/chips/chips.prt';

PART_NAME
 R6044 'Q_RES_0402LF-10K,5%,1/16W,CHIP,CS31002JB08':;

SECTION_NUMBER 1
 '@T6G_MB_LIB.T6G(SCH_1):PAGE144_I33@PURE_QUANTA.Q_RES(CHIPS)':
 C_PATH='@t6g_mb_lib.t6g(sch_1):page144_i33@pure_quanta.q_res(chips)',
 P_PATH='@t6g_mb_lib.t6g(sch_1):page167_i33@pure_quanta.q_res(chips)',
 PATH='I33',
 DRAWING='@T6G_MB_LIB.T6G(SCH_1):PAGE144',
 WATTAGE='1/16W',
 TOLERANCE='5%',
 MATERIAL='CHIP',
 PHYS_PAGE='167',
 XY='(-7950,3625)',
 ROT='2',
 VER='2',
 PACK_TYPE='0402LF',
 LOCATION='R6044',
 CDS_LIB='pure_quanta',
 CDS_PART_NAME='Q_RES_0402LF-10K,5%,1/16W,CHIP,CS31002JB08',
 PART_NUMBER='CS31002JB08',
 VALUE='10K',
 PRIM_FILE='./archive_libs/logical/q_res/chips/chips.prt';

PART_NAME
 R6045 'Q_RES_0402LF-4.7K,5%,1/16W,EMPTY,CS24702JB10':
 ROOM='NIC_P12V_MAM_TIC_BOM1';

SECTION_NUMBER 1
 '@T6G_MB_LIB.T6G(SCH_1):PAGE338_I130@PURE_QUANTA.Q_RES(CHIPS)':
 C_PATH='@t6g_mb_lib.t6g(sch_1):page338_i130@pure_quanta.q_res(chips)',
 P_PATH='@t6g_mb_lib.t6g(sch_1):page134_i130@pure_quanta.q_res(chips)',
 PATH='I130',
 DRAWING='@T6G_MB_LIB.T6G(SCH_1):PAGE338',
 WATTAGE='1/16W',
 TOLERANCE='5%',
 MATERIAL='EMPTY',
 PHYS_PAGE='134',
 XY='(3025,9900)',
 ROT='2',
 VER='2',
 PACK_TYPE='0402LF',
 LOCATION='R6045',
 CDS_LIB='pure_quanta',
 CDS_PART_NAME='Q_RES_0402LF-4.7K,5%,1/16W,EMPTY,CS24702JB10',
 ROOM='NIC_P12V_MAM_TIC_BOM1',
 PART_NUMBER='CS24702JB10',
 VALUE='4.7K',
 PRIM_FILE='./archive_libs/logical/q_res/chips/chips.prt';

PART_NAME
 R6046 'Q_RES_0402LF-100,1%,1/16W,CHIP,CS11002FB07':;

SECTION_NUMBER 1
 '@T6G_MB_LIB.T6G(SCH_1):PAGE80_I64@PURE_QUANTA.Q_RES(CHIPS)':
 C_PATH='@t6g_mb_lib.t6g(sch_1):page80_i64@pure_quanta.q_res(chips)',
 P_PATH='@t6g_mb_lib.t6g(sch_1):page81_i64@pure_quanta.q_res(chips)',
 PATH='I64',
 DRAWING='@T6G_MB_LIB.T6G(SCH_1):PAGE80',
 BOM_COST='MEM',
 WATTAGE='1/16W',
 TOLERANCE='1%',
 MATERIAL='CHIP',
 PHYS_PAGE='81',
 XY='(-6725,2975)',
 ROT='0',
 VER='1',
 PACK_TYPE='0402LF',
 LOCATION='R6046',
 CDS_LIB='pure_quanta',
 CDS_PART_NAME='Q_RES_0402LF-100,1%,1/16W,CHIP,CS11002FB07',
 PART_NUMBER='CS11002FB07',
 VALUE='100',
 PRIM_FILE='./archive_libs/logical/q_res/chips/chips.prt';

PART_NAME
 R6047 'Q_RES_0402LF-0,5%,1/16W,CHIP,CS00002JB13':;

SECTION_NUMBER 1
 '@T6G_MB_LIB.T6G(SCH_1):PAGE80_I34@PURE_QUANTA.Q_RES(CHIPS)':
 C_PATH='@t6g_mb_lib.t6g(sch_1):page80_i34@pure_quanta.q_res(chips)',
 P_PATH='@t6g_mb_lib.t6g(sch_1):page81_i34@pure_quanta.q_res(chips)',
 PATH='I34',
 DRAWING='@T6G_MB_LIB.T6G(SCH_1):PAGE80',
 BOM_COST='MEM',
 WATTAGE='1/16W',
 TOLERANCE='5%',
 MATERIAL='CHIP',
 PHYS_PAGE='81',
 XY='(-6725,1825)',
 ROT='0',
 VER='1',
 PACK_TYPE='0402LF',
 LOCATION='R6047',
 CDS_LIB='pure_quanta',
 CDS_PART_NAME='Q_RES_0402LF-0,5%,1/16W,CHIP,CS00002JB13',
 PART_NUMBER='CS00002JB13',
 VALUE='0',
 PRIM_FILE='./archive_libs/logical/q_res/chips/chips.prt';

PART_NAME
 R6048 'Q_RES_0402LF-0,5%,1/16W,CHIP,CS00002JB13':;

SECTION_NUMBER 1
 '@T6G_MB_LIB.T6G(SCH_1):PAGE80_I28@PURE_QUANTA.Q_RES(CHIPS)':
 C_PATH='@t6g_mb_lib.t6g(sch_1):page80_i28@pure_quanta.q_res(chips)',
 P_PATH='@t6g_mb_lib.t6g(sch_1):page81_i28@pure_quanta.q_res(chips)',
 PATH='I28',
 DRAWING='@T6G_MB_LIB.T6G(SCH_1):PAGE80',
 BOM_COST='MEM',
 WATTAGE='1/16W',
 TOLERANCE='5%',
 MATERIAL='CHIP',
 PHYS_PAGE='81',
 XY='(-6725,1425)',
 ROT='0',
 VER='1',
 PACK_TYPE='0402LF',
 LOCATION='R6048',
 CDS_LIB='pure_quanta',
 CDS_PART_NAME='Q_RES_0402LF-0,5%,1/16W,CHIP,CS00002JB13',
 PART_NUMBER='CS00002JB13',
 VALUE='0',
 PRIM_FILE='./archive_libs/logical/q_res/chips/chips.prt';

PART_NAME
 R6049 'Q_RES_0402LF-4.7K,5%,1/16W,CHIP,CS24702JB10':
 ROOM='E1S_P3V3_BOM1';

SECTION_NUMBER 1
 '@T6G_MB_LIB.T6G(SCH_1):PAGE324_I4@PURE_QUANTA.Q_RES(CHIPS)':
 C_PATH='@t6g_mb_lib.t6g(sch_1):page324_i4@pure_quanta.q_res(chips)',
 P_PATH='@t6g_mb_lib.t6g(sch_1):page146_i4@pure_quanta.q_res(chips)',
 PATH='I4',
 DRAWING='@T6G_MB_LIB.T6G(SCH_1):PAGE324',
 WATTAGE='1/16W',
 TOLERANCE='5%',
 MATERIAL='CHIP',
 PHYS_PAGE='146',
 XY='(-3300,-2975)',
 ROT='0',
 VER='2',
 PACK_TYPE='0402LF',
 LOCATION='R6049',
 CDS_LIB='pure_quanta',
 CDS_PART_NAME='Q_RES_0402LF-4.7K,5%,1/16W,CHIP,CS24702JB10',
 ROOM='E1S_P3V3_BOM1',
 PART_NUMBER='CS24702JB10',
 VALUE='4.7K',
 PRIM_FILE='./archive_libs/logical/q_res/chips/chips.prt';

PART_NAME
 R6050 'Q_RES_0402LF-100K,1%,1/16W,EMPTY,CS41002FB09':;

SECTION_NUMBER 1
 '@T6G_MB_LIB.T6G(SCH_1):PAGE273_I91@PURE_QUANTA.Q_RES(CHIPS)':
 C_PATH='@t6g_mb_lib.t6g(sch_1):page273_i91@pure_quanta.q_res(chips)',
 P_PATH='@t6g_mb_lib.t6g(sch_1):page188_i91@pure_quanta.q_res(chips)',
 PATH='I91',
 DRAWING='@T6G_MB_LIB.T6G(SCH_1):PAGE273',
 SEC_TYPE='0402LF',
 WATTAGE='1/16W',
 TOLERANCE='1%',
 MATERIAL='EMPTY',
 PHYS_PAGE='188',
 XY='(-3200,4575)',
 ROT='2',
 VER='2',
 PACK_TYPE='0402LF',
 LOCATION='R6050',
 SEC='1',
 CDS_LIB='pure_quanta',
 CDS_PART_NAME='Q_RES_0402LF-100K,1%,1/16W,EMPTY,CS41002FB09',
 PART_NUMBER='CS41002FB09',
 VALUE='100K',
 PRIM_FILE='./archive_libs/logical/q_res/chips/chips.prt';

PART_NAME
 R6051 'Q_RES_0402LF-0,5%,1/16W,CHIP,CS00002JB13':;

SECTION_NUMBER 1
 '@T6G_MB_LIB.T6G(SCH_1):PAGE81_I102@PURE_QUANTA.Q_RES(CHIPS)':
 C_PATH='@t6g_mb_lib.t6g(sch_1):page81_i102@pure_quanta.q_res(chips)',
 P_PATH='@t6g_mb_lib.t6g(sch_1):page82_i102@pure_quanta.q_res(chips)',
 PATH='I102',
 DRAWING='@T6G_MB_LIB.T6G(SCH_1):PAGE81',
 BOM_COST='MEM',
 WATTAGE='1/16W',
 TOLERANCE='5%',
 MATERIAL='CHIP',
 PHYS_PAGE='82',
 XY='(-3200,4575)',
 ROT='0',
 VER='1',
 PACK_TYPE='0402LF',
 LOCATION='R6051',
 CDS_LIB='pure_quanta',
 CDS_PART_NAME='Q_RES_0402LF-0,5%,1/16W,CHIP,CS00002JB13',
 PART_NUMBER='CS00002JB13',
 VALUE='0',
 PRIM_FILE='./archive_libs/logical/q_res/chips/chips.prt';

PART_NAME
 R6052 'Q_RES_0402LF-0,5%,1/16W,CHIP,CS00002JB13':;

SECTION_NUMBER 1
 '@T6G_MB_LIB.T6G(SCH_1):PAGE81_I99@PURE_QUANTA.Q_RES(CHIPS)':
 C_PATH='@t6g_mb_lib.t6g(sch_1):page81_i99@pure_quanta.q_res(chips)',
 P_PATH='@t6g_mb_lib.t6g(sch_1):page82_i99@pure_quanta.q_res(chips)',
 PATH='I99',
 DRAWING='@T6G_MB_LIB.T6G(SCH_1):PAGE81',
 BOM_COST='MEM',
 WATTAGE='1/16W',
 TOLERANCE='5%',
 MATERIAL='CHIP',
 PHYS_PAGE='82',
 XY='(-3200,4425)',
 ROT='0',
 VER='1',
 PACK_TYPE='0402LF',
 LOCATION='R6052',
 CDS_LIB='pure_quanta',
 CDS_PART_NAME='Q_RES_0402LF-0,5%,1/16W,CHIP,CS00002JB13',
 PART_NUMBER='CS00002JB13',
 VALUE='0',
 PRIM_FILE='./archive_libs/logical/q_res/chips/chips.prt';

PART_NAME
 R6053 'Q_RES_0402LF-0,5%,1/16W,CHIP,CS00002JB13':;

SECTION_NUMBER 1
 '@T6G_MB_LIB.T6G(SCH_1):PAGE81_I85@PURE_QUANTA.Q_RES(CHIPS)':
 C_PATH='@t6g_mb_lib.t6g(sch_1):page81_i85@pure_quanta.q_res(chips)',
 P_PATH='@t6g_mb_lib.t6g(sch_1):page82_i85@pure_quanta.q_res(chips)',
 PATH='I85',
 DRAWING='@T6G_MB_LIB.T6G(SCH_1):PAGE81',
 BOM_COST='MEM',
 WATTAGE='1/16W',
 TOLERANCE='5%',
 MATERIAL='CHIP',
 PHYS_PAGE='82',
 XY='(-3250,3825)',
 ROT='2',
 VER='1',
 PACK_TYPE='0402LF',
 LOCATION='R6053',
 CDS_LIB='pure_quanta',
 CDS_PART_NAME='Q_RES_0402LF-0,5%,1/16W,CHIP,CS00002JB13',
 PART_NUMBER='CS00002JB13',
 VALUE='0',
 PRIM_FILE='./archive_libs/logical/q_res/chips/chips.prt';

PART_NAME
 R6054 'Q_RES_0402LF-0,5%,1/16W,CHIP,CS00002JB13':;

SECTION_NUMBER 1
 '@T6G_MB_LIB.T6G(SCH_1):PAGE81_I83@PURE_QUANTA.Q_RES(CHIPS)':
 C_PATH='@t6g_mb_lib.t6g(sch_1):page81_i83@pure_quanta.q_res(chips)',
 P_PATH='@t6g_mb_lib.t6g(sch_1):page82_i83@pure_quanta.q_res(chips)',
 PATH='I83',
 DRAWING='@T6G_MB_LIB.T6G(SCH_1):PAGE81',
 BOM_COST='MEM',
 WATTAGE='1/16W',
 TOLERANCE='5%',
 MATERIAL='CHIP',
 PHYS_PAGE='82',
 XY='(-3250,3675)',
 ROT='2',
 VER='1',
 PACK_TYPE='0402LF',
 LOCATION='R6054',
 CDS_LIB='pure_quanta',
 CDS_PART_NAME='Q_RES_0402LF-0,5%,1/16W,CHIP,CS00002JB13',
 PART_NUMBER='CS00002JB13',
 VALUE='0',
 PRIM_FILE='./archive_libs/logical/q_res/chips/chips.prt';

PART_NAME
 R6055 'Q_RES_0402LF-0,5%,1/16W,CHIP,CS00002JB13':;

SECTION_NUMBER 1
 '@T6G_MB_LIB.T6G(SCH_1):PAGE80_I60@PURE_QUANTA.Q_RES(CHIPS)':
 C_PATH='@t6g_mb_lib.t6g(sch_1):page80_i60@pure_quanta.q_res(chips)',
 P_PATH='@t6g_mb_lib.t6g(sch_1):page81_i60@pure_quanta.q_res(chips)',
 PATH='I60',
 DRAWING='@T6G_MB_LIB.T6G(SCH_1):PAGE80',
 BOM_COST='MEM',
 WATTAGE='1/16W',
 TOLERANCE='5%',
 MATERIAL='CHIP',
 PHYS_PAGE='81',
 XY='(-6725,2425)',
 ROT='0',
 VER='1',
 PACK_TYPE='0402LF',
 LOCATION='R6055',
 CDS_LIB='pure_quanta',
 CDS_PART_NAME='Q_RES_0402LF-0,5%,1/16W,CHIP,CS00002JB13',
 PART_NUMBER='CS00002JB13',
 VALUE='0',
 PRIM_FILE='./archive_libs/logical/q_res/chips/chips.prt';

PART_NAME
 R6056 'Q_RES_0402LF-0,5%,1/16W,CHIP,CS00002JB13':;

SECTION_NUMBER 1
 '@T6G_MB_LIB.T6G(SCH_1):PAGE342_I72@PURE_QUANTA.Q_RES(CHIPS)':
 C_PATH='@t6g_mb_lib.t6g(sch_1):page342_i72@pure_quanta.q_res(chips)',
 P_PATH='@t6g_mb_lib.t6g(sch_1):page139_i72@pure_quanta.q_res(chips)',
 PATH='I72',
 DRAWING='@T6G_MB_LIB.T6G(SCH_1):PAGE342',
 BOM_COST='MEM',
 WATTAGE='1/16W',
 TOLERANCE='5%',
 MATERIAL='CHIP',
 PHYS_PAGE='139',
 XY='(6475,925)',
 ROT='0',
 VER='1',
 PACK_TYPE='0402LF',
 LOCATION='R6056',
 CDS_LIB='pure_quanta',
 CDS_PART_NAME='Q_RES_0402LF-0,5%,1/16W,CHIP,CS00002JB13',
 PART_NUMBER='CS00002JB13',
 VALUE='0',
 PRIM_FILE='./archive_libs/logical/q_res/chips/chips.prt';

PART_NAME
 R6057 'Q_RES_0402LF-0,5%,1/16W,CHIP,CS00002JB13':;

SECTION_NUMBER 1
 '@T6G_MB_LIB.T6G(SCH_1):PAGE342_I73@PURE_QUANTA.Q_RES(CHIPS)':
 C_PATH='@t6g_mb_lib.t6g(sch_1):page342_i73@pure_quanta.q_res(chips)',
 P_PATH='@t6g_mb_lib.t6g(sch_1):page139_i73@pure_quanta.q_res(chips)',
 PATH='I73',
 DRAWING='@T6G_MB_LIB.T6G(SCH_1):PAGE342',
 BOM_COST='MEM',
 WATTAGE='1/16W',
 TOLERANCE='5%',
 MATERIAL='CHIP',
 PHYS_PAGE='139',
 XY='(6475,875)',
 ROT='0',
 VER='1',
 PACK_TYPE='0402LF',
 LOCATION='R6057',
 CDS_LIB='pure_quanta',
 CDS_PART_NAME='Q_RES_0402LF-0,5%,1/16W,CHIP,CS00002JB13',
 PART_NUMBER='CS00002JB13',
 VALUE='0',
 PRIM_FILE='./archive_libs/logical/q_res/chips/chips.prt';

PART_NAME
 R6058 'Q_RES_0402LF-0,5%,1/16W,CHIP,CS00002JB13':;

SECTION_NUMBER 1
 '@T6G_MB_LIB.T6G(SCH_1):PAGE342_I74@PURE_QUANTA.Q_RES(CHIPS)':
 C_PATH='@t6g_mb_lib.t6g(sch_1):page342_i74@pure_quanta.q_res(chips)',
 P_PATH='@t6g_mb_lib.t6g(sch_1):page139_i74@pure_quanta.q_res(chips)',
 PATH='I74',
 DRAWING='@T6G_MB_LIB.T6G(SCH_1):PAGE342',
 BOM_COST='MEM',
 WATTAGE='1/16W',
 TOLERANCE='5%',
 MATERIAL='CHIP',
 PHYS_PAGE='139',
 XY='(6475,825)',
 ROT='0',
 VER='1',
 PACK_TYPE='0402LF',
 LOCATION='R6058',
 CDS_LIB='pure_quanta',
 CDS_PART_NAME='Q_RES_0402LF-0,5%,1/16W,CHIP,CS00002JB13',
 PART_NUMBER='CS00002JB13',
 VALUE='0',
 PRIM_FILE='./archive_libs/logical/q_res/chips/chips.prt';

PART_NAME
 R6059 'Q_RES_0402LF-0,5%,1/16W,CHIP,CS00002JB13':;

SECTION_NUMBER 1
 '@T6G_MB_LIB.T6G(SCH_1):PAGE342_I75@PURE_QUANTA.Q_RES(CHIPS)':
 C_PATH='@t6g_mb_lib.t6g(sch_1):page342_i75@pure_quanta.q_res(chips)',
 P_PATH='@t6g_mb_lib.t6g(sch_1):page139_i75@pure_quanta.q_res(chips)',
 PATH='I75',
 DRAWING='@T6G_MB_LIB.T6G(SCH_1):PAGE342',
 BOM_COST='MEM',
 WATTAGE='1/16W',
 TOLERANCE='5%',
 MATERIAL='CHIP',
 PHYS_PAGE='139',
 XY='(6475,775)',
 ROT='0',
 VER='1',
 PACK_TYPE='0402LF',
 LOCATION='R6059',
 CDS_LIB='pure_quanta',
 CDS_PART_NAME='Q_RES_0402LF-0,5%,1/16W,CHIP,CS00002JB13',
 PART_NUMBER='CS00002JB13',
 VALUE='0',
 PRIM_FILE='./archive_libs/logical/q_res/chips/chips.prt';

PART_NAME
 R6060 'Q_RES_0402LF-4.7K,5%,1/16W,EMPTY,CS24702JB10':
 ROOM='NIC_P12V_MAM_TIC_BOM1';

SECTION_NUMBER 1
 '@T6G_MB_LIB.T6G(SCH_1):PAGE343_I120@PURE_QUANTA.Q_RES(CHIPS)':
 C_PATH='@t6g_mb_lib.t6g(sch_1):page343_i120@pure_quanta.q_res(chips)',
 P_PATH='@t6g_mb_lib.t6g(sch_1):page140_i120@pure_quanta.q_res(chips)',
 PATH='I120',
 DRAWING='@T6G_MB_LIB.T6G(SCH_1):PAGE343',
 WATTAGE='1/16W',
 TOLERANCE='5%',
 MATERIAL='EMPTY',
 PHYS_PAGE='140',
 XY='(-3075,5550)',
 ROT='2',
 VER='2',
 PACK_TYPE='0402LF',
 LOCATION='R6060',
 CDS_LIB='pure_quanta',
 CDS_PART_NAME='Q_RES_0402LF-4.7K,5%,1/16W,EMPTY,CS24702JB10',
 ROOM='NIC_P12V_MAM_TIC_BOM1',
 PART_NUMBER='CS24702JB10',
 VALUE='4.7K',
 PRIM_FILE='./archive_libs/logical/q_res/chips/chips.prt';

PART_NAME
 R6061 'Q_RES_0402LF-4.7K,5%,1/16W,EMPTY,CS24702JB10':;

SECTION_NUMBER 1
 '@T6G_MB_LIB.T6G(SCH_1):PAGE82_I39@PURE_QUANTA.Q_RES(CHIPS)':
 C_PATH='@t6g_mb_lib.t6g(sch_1):page82_i39@pure_quanta.q_res(chips)',
 P_PATH='@t6g_mb_lib.t6g(sch_1):page83_i39@pure_quanta.q_res(chips)',
 PATH='I39',
 DRAWING='@T6G_MB_LIB.T6G(SCH_1):PAGE82',
 WATTAGE='1/16W',
 TOLERANCE='5%',
 MATERIAL='EMPTY',
 PHYS_PAGE='83',
 XY='(-7050,3825)',
 ROT='0',
 VER='1',
 PACK_TYPE='0402LF',
 LOCATION='R6061',
 CDS_LIB='pure_quanta',
 CDS_PART_NAME='Q_RES_0402LF-4.7K,5%,1/16W,EMPTY,CS24702JB10',
 PART_NUMBER='CS24702JB10',
 VALUE='4.7K',
 PRIM_FILE='./archive_libs/logical/q_res/chips/chips.prt';

PART_NAME
 R6062 'Q_RES_0402LF-4.7K,5%,1/16W,EMPTY,CS24702JB10':;

SECTION_NUMBER 1
 '@T6G_MB_LIB.T6G(SCH_1):PAGE82_I40@PURE_QUANTA.Q_RES(CHIPS)':
 C_PATH='@t6g_mb_lib.t6g(sch_1):page82_i40@pure_quanta.q_res(chips)',
 P_PATH='@t6g_mb_lib.t6g(sch_1):page83_i40@pure_quanta.q_res(chips)',
 PATH='I40',
 DRAWING='@T6G_MB_LIB.T6G(SCH_1):PAGE82',
 WATTAGE='1/16W',
 TOLERANCE='5%',
 MATERIAL='EMPTY',
 PHYS_PAGE='83',
 XY='(-7050,3775)',
 ROT='0',
 VER='1',
 PACK_TYPE='0402LF',
 LOCATION='R6062',
 CDS_LIB='pure_quanta',
 CDS_PART_NAME='Q_RES_0402LF-4.7K,5%,1/16W,EMPTY,CS24702JB10',
 PART_NUMBER='CS24702JB10',
 VALUE='4.7K',
 PRIM_FILE='./archive_libs/logical/q_res/chips/chips.prt';

PART_NAME
 R6063 'Q_RES_0402LF-33,5%,1/16W,CHIP,CS03302JB10':;

SECTION_NUMBER 1
 '@T6G_MB_LIB.T6G(SCH_1):PAGE132_I6@PURE_QUANTA.Q_RES(CHIPS)':
 C_PATH='@t6g_mb_lib.t6g(sch_1):page132_i6@pure_quanta.q_res(chips)',
 P_PATH='@t6g_mb_lib.t6g(sch_1):page155_i6@pure_quanta.q_res(chips)',
 PATH='I6',
 DRAWING='@T6G_MB_LIB.T6G(SCH_1):PAGE132',
 BOM_COST='PCH',
 WATTAGE='1/16W',
 TOLERANCE='5%',
 MATERIAL='CHIP',
 PHYS_PAGE='155',
 XY='(-5925,3275)',
 ROT='0',
 VER='1',
 PACK_TYPE='0402LF',
 LOCATION='R6063',
 CDS_LIB='pure_quanta',
 CDS_PART_NAME='Q_RES_0402LF-33,5%,1/16W,CHIP,CS03302JB10',
 PART_NUMBER='CS03302JB10',
 VALUE='33',
 PRIM_FILE='./archive_libs/logical/q_res/chips/chips.prt';

PART_NAME
 R6064 'Q_RES_0402LF-0,5%,1/16W,EMPTY,CS00002JB13':;

SECTION_NUMBER 1
 '@T6G_MB_LIB.T6G(SCH_1):PAGE348_I177@PURE_QUANTA.Q_RES(CHIPS)':
 C_PATH='@t6g_mb_lib.t6g(sch_1):page348_i177@pure_quanta.q_res(chips)',
 P_PATH='@t6g_mb_lib.t6g(sch_1):page150_i177@pure_quanta.q_res(chips)',
 PATH='I177',
 DRAWING='@T6G_MB_LIB.T6G(SCH_1):PAGE348',
 WATTAGE='1/16W',
 TOLERANCE='5%',
 MATERIAL='EMPTY',
 PHYS_PAGE='150',
 XY='(-9825,9125)',
 ROT='0',
 VER='1',
 PACK_TYPE='0402LF',
 LOCATION='R6064',
 CDS_LIB='pure_quanta',
 CDS_PART_NAME='Q_RES_0402LF-0,5%,1/16W,EMPTY,CS00002JB13',
 PART_NUMBER='CS00002JB13',
 VALUE='0',
 PRIM_FILE='./archive_libs/logical/q_res/chips/chips.prt';

PART_NAME
 R6065 'Q_RES_0402LF-0,5%,1/16W,EMPTY,CS00002JB13':;

SECTION_NUMBER 1
 '@T6G_MB_LIB.T6G(SCH_1):PAGE348_I178@PURE_QUANTA.Q_RES(CHIPS)':
 C_PATH='@t6g_mb_lib.t6g(sch_1):page348_i178@pure_quanta.q_res(chips)',
 P_PATH='@t6g_mb_lib.t6g(sch_1):page150_i178@pure_quanta.q_res(chips)',
 PATH='I178',
 DRAWING='@T6G_MB_LIB.T6G(SCH_1):PAGE348',
 WATTAGE='1/16W',
 TOLERANCE='5%',
 MATERIAL='EMPTY',
 PHYS_PAGE='150',
 XY='(-9825,9075)',
 ROT='0',
 VER='1',
 PACK_TYPE='0402LF',
 LOCATION='R6065',
 CDS_LIB='pure_quanta',
 CDS_PART_NAME='Q_RES_0402LF-0,5%,1/16W,EMPTY,CS00002JB13',
 PART_NUMBER='CS00002JB13',
 VALUE='0',
 PRIM_FILE='./archive_libs/logical/q_res/chips/chips.prt';

PART_NAME
 R6066 'Q_RES_0402LF-0,5%,1/16W,EMPTY,CS00002JB13':;

SECTION_NUMBER 1
 '@T6G_MB_LIB.T6G(SCH_1):PAGE349_I150@PURE_QUANTA.Q_RES(CHIPS)':
 C_PATH='@t6g_mb_lib.t6g(sch_1):page349_i150@pure_quanta.q_res(chips)',
 P_PATH='@t6g_mb_lib.t6g(sch_1):page151_i150@pure_quanta.q_res(chips)',
 PATH='I150',
 DRAWING='@T6G_MB_LIB.T6G(SCH_1):PAGE349',
 WATTAGE='1/16W',
 TOLERANCE='5%',
 MATERIAL='EMPTY',
 PHYS_PAGE='151',
 XY='(-1125,3475)',
 ROT='2',
 VER='1',
 PACK_TYPE='0402LF',
 LOCATION='R6066',
 CDS_LIB='pure_quanta',
 CDS_PART_NAME='Q_RES_0402LF-0,5%,1/16W,EMPTY,CS00002JB13',
 PART_NUMBER='CS00002JB13',
 VALUE='0',
 PRIM_FILE='./archive_libs/logical/q_res/chips/chips.prt';

PART_NAME
 R6067 'Q_RES_0402LF-0,5%,1/16W,CHIP,CS00002JB13':;

SECTION_NUMBER 1
 '@T6G_MB_LIB.T6G(SCH_1):PAGE349_I159@PURE_QUANTA.Q_RES(CHIPS)':
 C_PATH='@t6g_mb_lib.t6g(sch_1):page349_i159@pure_quanta.q_res(chips)',
 P_PATH='@t6g_mb_lib.t6g(sch_1):page151_i159@pure_quanta.q_res(chips)',
 PATH='I159',
 DRAWING='@T6G_MB_LIB.T6G(SCH_1):PAGE349',
 WATTAGE='1/16W',
 TOLERANCE='5%',
 MATERIAL='CHIP',
 PHYS_PAGE='151',
 XY='(-1125,3325)',
 ROT='2',
 VER='1',
 PACK_TYPE='0402LF',
 LOCATION='R6067',
 CDS_LIB='pure_quanta',
 CDS_PART_NAME='Q_RES_0402LF-0,5%,1/16W,CHIP,CS00002JB13',
 PART_NUMBER='CS00002JB13',
 VALUE='0',
 PRIM_FILE='./archive_libs/logical/q_res/chips/chips.prt';

PART_NAME
 R6068 'Q_RES_0402LF-0,5%,1/16W,EMPTY,CS00002JB13':;

SECTION_NUMBER 1
 '@T6G_MB_LIB.T6G(SCH_1):PAGE349_I151@PURE_QUANTA.Q_RES(CHIPS)':
 C_PATH='@t6g_mb_lib.t6g(sch_1):page349_i151@pure_quanta.q_res(chips)',
 P_PATH='@t6g_mb_lib.t6g(sch_1):page151_i151@pure_quanta.q_res(chips)',
 PATH='I151',
 DRAWING='@T6G_MB_LIB.T6G(SCH_1):PAGE349',
 WATTAGE='1/16W',
 TOLERANCE='5%',
 MATERIAL='EMPTY',
 PHYS_PAGE='151',
 XY='(-1125,2925)',
 ROT='2',
 VER='1',
 PACK_TYPE='0402LF',
 LOCATION='R6068',
 CDS_LIB='pure_quanta',
 CDS_PART_NAME='Q_RES_0402LF-0,5%,1/16W,EMPTY,CS00002JB13',
 PART_NUMBER='CS00002JB13',
 VALUE='0',
 PRIM_FILE='./archive_libs/logical/q_res/chips/chips.prt';

PART_NAME
 R6069 'Q_RES_0402LF-0,5%,1/16W,CHIP,CS00002JB13':;

SECTION_NUMBER 1
 '@T6G_MB_LIB.T6G(SCH_1):PAGE349_I158@PURE_QUANTA.Q_RES(CHIPS)':
 C_PATH='@t6g_mb_lib.t6g(sch_1):page349_i158@pure_quanta.q_res(chips)',
 P_PATH='@t6g_mb_lib.t6g(sch_1):page151_i158@pure_quanta.q_res(chips)',
 PATH='I158',
 DRAWING='@T6G_MB_LIB.T6G(SCH_1):PAGE349',
 WATTAGE='1/16W',
 TOLERANCE='5%',
 MATERIAL='CHIP',
 PHYS_PAGE='151',
 XY='(-1125,2750)',
 ROT='2',
 VER='1',
 PACK_TYPE='0402LF',
 LOCATION='R6069',
 CDS_LIB='pure_quanta',
 CDS_PART_NAME='Q_RES_0402LF-0,5%,1/16W,CHIP,CS00002JB13',
 PART_NUMBER='CS00002JB13',
 VALUE='0',
 PRIM_FILE='./archive_libs/logical/q_res/chips/chips.prt';

PART_NAME
 R6070 'Q_RES_0402LF-4.7K,5%,1/16W,EMPTY,CS24702JB10':;

SECTION_NUMBER 1
 '@T6G_MB_LIB.T6G(SCH_1):PAGE349_I161@PURE_QUANTA.Q_RES(CHIPS)':
 C_PATH='@t6g_mb_lib.t6g(sch_1):page349_i161@pure_quanta.q_res(chips)',
 P_PATH='@t6g_mb_lib.t6g(sch_1):page151_i161@pure_quanta.q_res(chips)',
 PATH='I161',
 DRAWING='@T6G_MB_LIB.T6G(SCH_1):PAGE349',
 WATTAGE='1/16W',
 TOLERANCE='5%',
 MATERIAL='EMPTY',
 PHYS_PAGE='151',
 XY='(-2100,5350)',
 ROT='0',
 VER='1',
 PACK_TYPE='0402LF',
 LOCATION='R6070',
 CDS_LIB='pure_quanta',
 CDS_PART_NAME='Q_RES_0402LF-4.7K,5%,1/16W,EMPTY,CS24702JB10',
 PART_NUMBER='CS24702JB10',
 VALUE='4.7K',
 PRIM_FILE='./archive_libs/logical/q_res/chips/chips.prt';

PART_NAME
 R6071 'Q_RES_0402LF-4.7K,5%,1/16W,EMPTY,CS24702JB10':;

SECTION_NUMBER 1
 '@T6G_MB_LIB.T6G(SCH_1):PAGE348_I214@PURE_QUANTA.Q_RES(CHIPS)':
 C_PATH='@t6g_mb_lib.t6g(sch_1):page348_i214@pure_quanta.q_res(chips)',
 P_PATH='@t6g_mb_lib.t6g(sch_1):page150_i214@pure_quanta.q_res(chips)',
 PATH='I214',
 DRAWING='@T6G_MB_LIB.T6G(SCH_1):PAGE348',
 WATTAGE='1/16W',
 TOLERANCE='5%',
 MATERIAL='EMPTY',
 PHYS_PAGE='150',
 XY='(-16775,6350)',
 ROT='2',
 VER='2',
 PACK_TYPE='0402LF',
 LOCATION='R6071',
 CDS_LIB='pure_quanta',
 CDS_PART_NAME='Q_RES_0402LF-4.7K,5%,1/16W,EMPTY,CS24702JB10',
 PART_NUMBER='CS24702JB10',
 VALUE='4.7K',
 PRIM_FILE='./archive_libs/logical/q_res/chips/chips.prt';

PART_NAME
 R6073 'Q_RES_0402LF-0,5%,1/16W,CHIP,CS00002JB13':;

SECTION_NUMBER 1
 '@T6G_MB_LIB.T6G(SCH_1):PAGE81_I146@PURE_QUANTA.Q_RES(CHIPS)':
 C_PATH='@t6g_mb_lib.t6g(sch_1):page81_i146@pure_quanta.q_res(chips)',
 P_PATH='@t6g_mb_lib.t6g(sch_1):page82_i146@pure_quanta.q_res(chips)',
 PATH='I146',
 DRAWING='@T6G_MB_LIB.T6G(SCH_1):PAGE81',
 BOM_COST='MEM',
 WATTAGE='1/16W',
 TOLERANCE='5%',
 MATERIAL='CHIP',
 PHYS_PAGE='82',
 XY='(-6450,5025)',
 ROT='0',
 VER='1',
 PACK_TYPE='0402LF',
 LOCATION='R6073',
 CDS_LIB='pure_quanta',
 CDS_PART_NAME='Q_RES_0402LF-0,5%,1/16W,CHIP,CS00002JB13',
 PART_NUMBER='CS00002JB13',
 VALUE='0',
 PRIM_FILE='./archive_libs/logical/q_res/chips/chips.prt';

PART_NAME
 R6074 'Q_RES_0402LF-0,5%,1/16W,CHIP,CS00002JB13':;

SECTION_NUMBER 1
 '@T6G_MB_LIB.T6G(SCH_1):PAGE84_I53@PURE_QUANTA.Q_RES(CHIPS)':
 C_PATH='@t6g_mb_lib.t6g(sch_1):page84_i53@pure_quanta.q_res(chips)',
 P_PATH='@t6g_mb_lib.t6g(sch_1):page85_i53@pure_quanta.q_res(chips)',
 PATH='I53',
 DRAWING='@T6G_MB_LIB.T6G(SCH_1):PAGE84',
 BOM_COST='MEM',
 WATTAGE='1/16W',
 TOLERANCE='5%',
 MATERIAL='CHIP',
 PHYS_PAGE='85',
 XY='(-7550,1550)',
 ROT='0',
 VER='1',
 PACK_TYPE='0402LF',
 LOCATION='R6074',
 CDS_LIB='pure_quanta',
 CDS_PART_NAME='Q_RES_0402LF-0,5%,1/16W,CHIP,CS00002JB13',
 PART_NUMBER='CS00002JB13',
 VALUE='0',
 PRIM_FILE='./archive_libs/logical/q_res/chips/chips.prt';

PART_NAME
 R6075 'Q_RES_0402LF-0,5%,1/16W,CHIP,CS00002JB13':;

SECTION_NUMBER 1
 '@T6G_MB_LIB.T6G(SCH_1):PAGE84_I57@PURE_QUANTA.Q_RES(CHIPS)':
 C_PATH='@t6g_mb_lib.t6g(sch_1):page84_i57@pure_quanta.q_res(chips)',
 P_PATH='@t6g_mb_lib.t6g(sch_1):page85_i57@pure_quanta.q_res(chips)',
 PATH='I57',
 DRAWING='@T6G_MB_LIB.T6G(SCH_1):PAGE84',
 BOM_COST='MEM',
 WATTAGE='1/16W',
 TOLERANCE='5%',
 MATERIAL='CHIP',
 PHYS_PAGE='85',
 XY='(-7550,1425)',
 ROT='0',
 VER='1',
 PACK_TYPE='0402LF',
 LOCATION='R6075',
 CDS_LIB='pure_quanta',
 CDS_PART_NAME='Q_RES_0402LF-0,5%,1/16W,CHIP,CS00002JB13',
 PART_NUMBER='CS00002JB13',
 VALUE='0',
 PRIM_FILE='./archive_libs/logical/q_res/chips/chips.prt';

PART_NAME
 R6076 'Q_RES_0402LF-33,5%,1/16W,CHIP,CS03302JB10':;

SECTION_NUMBER 1
 '@T6G_MB_LIB.T6G(SCH_1):PAGE349_I181@PURE_QUANTA.Q_RES(CHIPS)':
 C_PATH='@t6g_mb_lib.t6g(sch_1):page349_i181@pure_quanta.q_res(chips)',
 P_PATH='@t6g_mb_lib.t6g(sch_1):page151_i181@pure_quanta.q_res(chips)',
 PATH='I181',
 DRAWING='@T6G_MB_LIB.T6G(SCH_1):PAGE349',
 WATTAGE='1/16W',
 TOLERANCE='5%',
 MATERIAL='CHIP',
 PHYS_PAGE='151',
 XY='(-1125,1450)',
 ROT='0',
 VER='1',
 PACK_TYPE='0402LF',
 LOCATION='R6076',
 CDS_LIB='pure_quanta',
 CDS_PART_NAME='Q_RES_0402LF-33,5%,1/16W,CHIP,CS03302JB10',
 PART_NUMBER='CS03302JB10',
 VALUE='33',
 PRIM_FILE='./archive_libs/logical/q_res/chips/chips.prt';

PART_NAME
 R6077 'Q_RES_0402LF-33,5%,1/16W,CHIP,CS03302JB10':;

SECTION_NUMBER 1
 '@T6G_MB_LIB.T6G(SCH_1):PAGE349_I182@PURE_QUANTA.Q_RES(CHIPS)':
 C_PATH='@t6g_mb_lib.t6g(sch_1):page349_i182@pure_quanta.q_res(chips)',
 P_PATH='@t6g_mb_lib.t6g(sch_1):page151_i182@pure_quanta.q_res(chips)',
 PATH='I182',
 DRAWING='@T6G_MB_LIB.T6G(SCH_1):PAGE349',
 WATTAGE='1/16W',
 TOLERANCE='5%',
 MATERIAL='CHIP',
 PHYS_PAGE='151',
 XY='(-1125,1350)',
 ROT='0',
 VER='1',
 PACK_TYPE='0402LF',
 LOCATION='R6077',
 CDS_LIB='pure_quanta',
 CDS_PART_NAME='Q_RES_0402LF-33,5%,1/16W,CHIP,CS03302JB10',
 PART_NUMBER='CS03302JB10',
 VALUE='33',
 PRIM_FILE='./archive_libs/logical/q_res/chips/chips.prt';

PART_NAME
 R6078 'Q_RES_0402LF-0,5%,1/16W,CHIP,CS00002JB13':;

SECTION_NUMBER 1
 '@T6G_MB_LIB.T6G(SCH_1):PAGE84_I61@PURE_QUANTA.Q_RES(CHIPS)':
 C_PATH='@t6g_mb_lib.t6g(sch_1):page84_i61@pure_quanta.q_res(chips)',
 P_PATH='@t6g_mb_lib.t6g(sch_1):page85_i61@pure_quanta.q_res(chips)',
 PATH='I61',
 DRAWING='@T6G_MB_LIB.T6G(SCH_1):PAGE84',
 BOM_COST='MEM',
 WATTAGE='1/16W',
 TOLERANCE='5%',
 MATERIAL='CHIP',
 PHYS_PAGE='85',
 XY='(-7550,1300)',
 ROT='0',
 VER='1',
 PACK_TYPE='0402LF',
 LOCATION='R6078',
 CDS_LIB='pure_quanta',
 CDS_PART_NAME='Q_RES_0402LF-0,5%,1/16W,CHIP,CS00002JB13',
 PART_NUMBER='CS00002JB13',
 VALUE='0',
 PRIM_FILE='./archive_libs/logical/q_res/chips/chips.prt';

PART_NAME
 R6081 'Q_RES_0402LF-4.7K,5%,1/16W,CHIP,CS24702JB10':;

SECTION_NUMBER 1
 '@T6G_MB_LIB.T6G(SCH_1):PAGE28_I210@PURE_QUANTA.Q_RES(CHIPS)':
 C_PATH='@t6g_mb_lib.t6g(sch_1):page28_i210@pure_quanta.q_res(chips)',
 P_PATH='@t6g_mb_lib.t6g(sch_1):page28_i210@pure_quanta.q_res(chips)',
 PATH='I210',
 DRAWING='@T6G_MB_LIB.T6G(SCH_1):PAGE28',
 WATTAGE='1/16W',
 TOLERANCE='5%',
 MATERIAL='CHIP',
 PHYS_PAGE='28',
 XY='(-8275,11125)',
 ROT='0',
 VER='1',
 PACK_TYPE='0402LF',
 LOCATION='R6081',
 CDS_LIB='pure_quanta',
 CDS_PART_NAME='Q_RES_0402LF-4.7K,5%,1/16W,CHIP,CS24702JB10',
 PART_NUMBER='CS24702JB10',
 VALUE='4.7K',
 PRIM_FILE='./archive_libs/logical/q_res/chips/chips.prt';

PART_NAME
 R6082 'Q_RES_0402LF-4.7K,5%,1/16W,CHIP,CS24702JB10':;

SECTION_NUMBER 1
 '@T6G_MB_LIB.T6G(SCH_1):PAGE28_I212@PURE_QUANTA.Q_RES(CHIPS)':
 C_PATH='@t6g_mb_lib.t6g(sch_1):page28_i212@pure_quanta.q_res(chips)',
 P_PATH='@t6g_mb_lib.t6g(sch_1):page28_i212@pure_quanta.q_res(chips)',
 PATH='I212',
 DRAWING='@T6G_MB_LIB.T6G(SCH_1):PAGE28',
 WATTAGE='1/16W',
 TOLERANCE='5%',
 MATERIAL='CHIP',
 PHYS_PAGE='28',
 XY='(-8275,11075)',
 ROT='0',
 VER='1',
 PACK_TYPE='0402LF',
 LOCATION='R6082',
 CDS_LIB='pure_quanta',
 CDS_PART_NAME='Q_RES_0402LF-4.7K,5%,1/16W,CHIP,CS24702JB10',
 PART_NUMBER='CS24702JB10',
 VALUE='4.7K',
 PRIM_FILE='./archive_libs/logical/q_res/chips/chips.prt';

PART_NAME
 R6083 'Q_RES_0402LF-4.7K,5%,1/16W,CHIP,CS24702JB10':;

SECTION_NUMBER 1
 '@T6G_MB_LIB.T6G(SCH_1):PAGE28_I213@PURE_QUANTA.Q_RES(CHIPS)':
 C_PATH='@t6g_mb_lib.t6g(sch_1):page28_i213@pure_quanta.q_res(chips)',
 P_PATH='@t6g_mb_lib.t6g(sch_1):page28_i213@pure_quanta.q_res(chips)',
 PATH='I213',
 DRAWING='@T6G_MB_LIB.T6G(SCH_1):PAGE28',
 WATTAGE='1/16W',
 TOLERANCE='5%',
 MATERIAL='CHIP',
 PHYS_PAGE='28',
 XY='(-8275,11025)',
 ROT='0',
 VER='1',
 PACK_TYPE='0402LF',
 LOCATION='R6083',
 CDS_LIB='pure_quanta',
 CDS_PART_NAME='Q_RES_0402LF-4.7K,5%,1/16W,CHIP,CS24702JB10',
 PART_NUMBER='CS24702JB10',
 VALUE='4.7K',
 PRIM_FILE='./archive_libs/logical/q_res/chips/chips.prt';

PART_NAME
 R6084 'Q_RES_0402LF-4.7K,5%,1/16W,CHIP,CS24702JB10':;

SECTION_NUMBER 1
 '@T6G_MB_LIB.T6G(SCH_1):PAGE28_I214@PURE_QUANTA.Q_RES(CHIPS)':
 C_PATH='@t6g_mb_lib.t6g(sch_1):page28_i214@pure_quanta.q_res(chips)',
 P_PATH='@t6g_mb_lib.t6g(sch_1):page28_i214@pure_quanta.q_res(chips)',
 PATH='I214',
 DRAWING='@T6G_MB_LIB.T6G(SCH_1):PAGE28',
 WATTAGE='1/16W',
 TOLERANCE='5%',
 MATERIAL='CHIP',
 PHYS_PAGE='28',
 XY='(-8275,10975)',
 ROT='0',
 VER='1',
 PACK_TYPE='0402LF',
 LOCATION='R6084',
 CDS_LIB='pure_quanta',
 CDS_PART_NAME='Q_RES_0402LF-4.7K,5%,1/16W,CHIP,CS24702JB10',
 PART_NUMBER='CS24702JB10',
 VALUE='4.7K',
 PRIM_FILE='./archive_libs/logical/q_res/chips/chips.prt';

PART_NAME
 R6085 'Q_RES_0402LF-10K,1%,1/16W,CHIP,CS31002FB08':;

SECTION_NUMBER 1
 '@T6G_MB_LIB.T6G(SCH_1):PAGE80_I298@PURE_QUANTA.Q_RES(CHIPS)':
 C_PATH='@t6g_mb_lib.t6g(sch_1):page80_i298@pure_quanta.q_res(chips)',
 P_PATH='@t6g_mb_lib.t6g(sch_1):page81_i298@pure_quanta.q_res(chips)',
 PATH='I298',
 DRAWING='@T6G_MB_LIB.T6G(SCH_1):PAGE80',
 WATTAGE='1/16W',
 TOLERANCE='1%',
 MATERIAL='CHIP',
 PHYS_PAGE='81',
 XY='(-275,1125)',
 ROT='0',
 VER='2',
 PACK_TYPE='0402LF',
 LOCATION='R6085',
 CDS_LIB='pure_quanta',
 CDS_PART_NAME='Q_RES_0402LF-10K,1%,1/16W,CHIP,CS31002FB08',
 PART_NUMBER='CS31002FB08',
 VALUE='10K',
 PRIM_FILE='./archive_libs/logical/q_res/chips/chips.prt';

PART_NAME
 R6086 'Q_RES_0402LF-10K,1%,1/16W,EMPTY,CS31002FB08':;

SECTION_NUMBER 1
 '@T6G_MB_LIB.T6G(SCH_1):PAGE175_I129@PURE_QUANTA.Q_RES(CHIPS)':
 C_PATH='@t6g_mb_lib.t6g(sch_1):page175_i129@pure_quanta.q_res(chips)',
 P_PATH='@t6g_mb_lib.t6g(sch_1):page200_i129@pure_quanta.q_res(chips)',
 PATH='I129',
 DRAWING='@T6G_MB_LIB.T6G(SCH_1):PAGE175',
 WATTAGE='1/16W',
 TOLERANCE='1%',
 MATERIAL='EMPTY',
 PHYS_PAGE='200',
 XY='(-8225,1400)',
 ROT='0',
 VER='2',
 PACK_TYPE='0402LF',
 LOCATION='R6086',
 CDS_LIB='pure_quanta',
 CDS_PART_NAME='Q_RES_0402LF-10K,1%,1/16W,EMPTY,CS31002FB08',
 PART_NUMBER='CS31002FB08',
 VALUE='10K',
 PRIM_FILE='./archive_libs/logical/q_res/chips/chips.prt';

PART_NAME
 R6087 'Q_RES_0402LF-10K,1%,1/16W,EMPTY,CS31002FB08':;

SECTION_NUMBER 1
 '@T6G_MB_LIB.T6G(SCH_1):PAGE185_I135@PURE_QUANTA.Q_RES(CHIPS)':
 C_PATH='@t6g_mb_lib.t6g(sch_1):page185_i135@pure_quanta.q_res(chips)',
 P_PATH='@t6g_mb_lib.t6g(sch_1):page210_i135@pure_quanta.q_res(chips)',
 PATH='I135',
 DRAWING='@T6G_MB_LIB.T6G(SCH_1):PAGE185',
 WATTAGE='1/16W',
 TOLERANCE='1%',
 MATERIAL='EMPTY',
 PHYS_PAGE='210',
 XY='(-5075,2950)',
 ROT='0',
 VER='2',
 PACK_TYPE='0402LF',
 LOCATION='R6087',
 CDS_LIB='pure_quanta',
 CDS_PART_NAME='Q_RES_0402LF-10K,1%,1/16W,EMPTY,CS31002FB08',
 PART_NUMBER='CS31002FB08',
 VALUE='10K',
 PRIM_FILE='./archive_libs/logical/q_res/chips/chips.prt';

PART_NAME
 R6088 'Q_RES_0402LF-10K,1%,1/16W,EMPTY,CS31002FB08':;

SECTION_NUMBER 1
 '@T6G_MB_LIB.T6G(SCH_1):PAGE192_I130@PURE_QUANTA.Q_RES(CHIPS)':
 C_PATH='@t6g_mb_lib.t6g(sch_1):page192_i130@pure_quanta.q_res(chips)',
 P_PATH='@t6g_mb_lib.t6g(sch_1):page217_i130@pure_quanta.q_res(chips)',
 PATH='I130',
 DRAWING='@T6G_MB_LIB.T6G(SCH_1):PAGE192',
 WATTAGE='1/16W',
 TOLERANCE='1%',
 MATERIAL='EMPTY',
 PHYS_PAGE='217',
 XY='(-4550,2325)',
 ROT='0',
 VER='2',
 PACK_TYPE='0402LF',
 LOCATION='R6088',
 CDS_LIB='pure_quanta',
 CDS_PART_NAME='Q_RES_0402LF-10K,1%,1/16W,EMPTY,CS31002FB08',
 PART_NUMBER='CS31002FB08',
 VALUE='10K',
 PRIM_FILE='./archive_libs/logical/q_res/chips/chips.prt';

PART_NAME
 R6089 'Q_RES_0402LF-10K,1%,1/16W,EMPTY,CS31002FB08':;

SECTION_NUMBER 1
 '@T6G_MB_LIB.T6G(SCH_1):PAGE168_I136@PURE_QUANTA.Q_RES(CHIPS)':
 C_PATH='@t6g_mb_lib.t6g(sch_1):page168_i136@pure_quanta.q_res(chips)',
 P_PATH='@t6g_mb_lib.t6g(sch_1):page193_i136@pure_quanta.q_res(chips)',
 PATH='I136',
 DRAWING='@T6G_MB_LIB.T6G(SCH_1):PAGE168',
 WATTAGE='1/16W',
 TOLERANCE='1%',
 MATERIAL='EMPTY',
 PHYS_PAGE='193',
 XY='(-7950,1575)',
 ROT='0',
 VER='2',
 PACK_TYPE='0402LF',
 LOCATION='R6089',
 CDS_LIB='pure_quanta',
 CDS_PART_NAME='Q_RES_0402LF-10K,1%,1/16W,EMPTY,CS31002FB08',
 PART_NUMBER='CS31002FB08',
 VALUE='10K',
 PRIM_FILE='./archive_libs/logical/q_res/chips/chips.prt';

PART_NAME
 R6090 'Q_RES_0402LF-4.7K,5%,1/16W,CHIP,CS24702JB10':;

SECTION_NUMBER 1
 '@T6G_MB_LIB.T6G(SCH_1):PAGE84_I77@PURE_QUANTA.Q_RES(CHIPS)':
 C_PATH='@t6g_mb_lib.t6g(sch_1):page84_i77@pure_quanta.q_res(chips)',
 P_PATH='@t6g_mb_lib.t6g(sch_1):page85_i77@pure_quanta.q_res(chips)',
 PATH='I77',
 DRAWING='@T6G_MB_LIB.T6G(SCH_1):PAGE84',
 WATTAGE='1/16W',
 TOLERANCE='5%',
 MATERIAL='CHIP',
 PHYS_PAGE='85',
 XY='(-2950,1225)',
 ROT='0',
 VER='2',
 PACK_TYPE='0402LF',
 LOCATION='R6090',
 CDS_LIB='pure_quanta',
 CDS_PART_NAME='Q_RES_0402LF-4.7K,5%,1/16W,CHIP,CS24702JB10',
 PART_NUMBER='CS24702JB10',
 VALUE='4.7K',
 PRIM_FILE='./archive_libs/logical/q_res/chips/chips.prt';

PART_NAME
 R6092 'Q_RES_0402LF-0,5%,1/16W,CHIP,CS00002JB13':;

SECTION_NUMBER 1
 '@T6G_MB_LIB.T6G(SCH_1):PAGE84_I82@PURE_QUANTA.Q_RES(CHIPS)':
 C_PATH='@t6g_mb_lib.t6g(sch_1):page84_i82@pure_quanta.q_res(chips)',
 P_PATH='@t6g_mb_lib.t6g(sch_1):page85_i82@pure_quanta.q_res(chips)',
 PATH='I82',
 DRAWING='@T6G_MB_LIB.T6G(SCH_1):PAGE84',
 BOM_COST='MEM',
 WATTAGE='1/16W',
 TOLERANCE='5%',
 MATERIAL='CHIP',
 PHYS_PAGE='85',
 XY='(-7550,875)',
 ROT='0',
 VER='1',
 PACK_TYPE='0402LF',
 LOCATION='R6092',
 CDS_LIB='pure_quanta',
 CDS_PART_NAME='Q_RES_0402LF-0,5%,1/16W,CHIP,CS00002JB13',
 PART_NUMBER='CS00002JB13',
 VALUE='0',
 PRIM_FILE='./archive_libs/logical/q_res/chips/chips.prt';

PART_NAME
 R6093 'Q_RES_0402LF-0,5%,1/16W,CHIP,CS00002JB13':;

SECTION_NUMBER 1
 '@T6G_MB_LIB.T6G(SCH_1):PAGE84_I84@PURE_QUANTA.Q_RES(CHIPS)':
 C_PATH='@t6g_mb_lib.t6g(sch_1):page84_i84@pure_quanta.q_res(chips)',
 P_PATH='@t6g_mb_lib.t6g(sch_1):page85_i84@pure_quanta.q_res(chips)',
 PATH='I84',
 DRAWING='@T6G_MB_LIB.T6G(SCH_1):PAGE84',
 BOM_COST='MEM',
 WATTAGE='1/16W',
 TOLERANCE='5%',
 MATERIAL='CHIP',
 PHYS_PAGE='85',
 XY='(-7550,775)',
 ROT='0',
 VER='1',
 PACK_TYPE='0402LF',
 LOCATION='R6093',
 CDS_LIB='pure_quanta',
 CDS_PART_NAME='Q_RES_0402LF-0,5%,1/16W,CHIP,CS00002JB13',
 PART_NUMBER='CS00002JB13',
 VALUE='0',
 PRIM_FILE='./archive_libs/logical/q_res/chips/chips.prt';

PART_NAME
 R6094 'Q_RES_0402LF-0,5%,1/16W,EMPTY,CS00002JB13':;

SECTION_NUMBER 1
 '@T6G_MB_LIB.T6G(SCH_1):PAGE79_I128@PURE_QUANTA.Q_RES(CHIPS)':
 C_PATH='@t6g_mb_lib.t6g(sch_1):page79_i128@pure_quanta.q_res(chips)',
 P_PATH='@t6g_mb_lib.t6g(sch_1):page80_i128@pure_quanta.q_res(chips)',
 PATH='I128',
 DRAWING='@T6G_MB_LIB.T6G(SCH_1):PAGE79',
 BOM_COST='MEM',
 WATTAGE='1/16W',
 TOLERANCE='5%',
 MATERIAL='EMPTY',
 PHYS_PAGE='80',
 XY='(-8450,4300)',
 ROT='2',
 VER='1',
 PACK_TYPE='0402LF',
 LOCATION='R6094',
 CDS_LIB='pure_quanta',
 CDS_PART_NAME='Q_RES_0402LF-0,5%,1/16W,EMPTY,CS00002JB13',
 PART_NUMBER='CS00002JB13',
 VALUE='0',
 PRIM_FILE='./archive_libs/logical/q_res/chips/chips.prt';

PART_NAME
 R6095 'Q_RES_0402LF-0,5%,1/16W,CHIP,CS00002JB13':;

SECTION_NUMBER 1
 '@T6G_MB_LIB.T6G(SCH_1):PAGE79_I112@PURE_QUANTA.Q_RES(CHIPS)':
 C_PATH='@t6g_mb_lib.t6g(sch_1):page79_i112@pure_quanta.q_res(chips)',
 P_PATH='@t6g_mb_lib.t6g(sch_1):page80_i112@pure_quanta.q_res(chips)',
 PATH='I112',
 DRAWING='@T6G_MB_LIB.T6G(SCH_1):PAGE79',
 BOM_COST='MEM',
 WATTAGE='1/16W',
 TOLERANCE='5%',
 MATERIAL='CHIP',
 PHYS_PAGE='80',
 XY='(-6825,4000)',
 ROT='2',
 VER='1',
 PACK_TYPE='0402LF',
 LOCATION='R6095',
 CDS_LIB='pure_quanta',
 CDS_PART_NAME='Q_RES_0402LF-0,5%,1/16W,CHIP,CS00002JB13',
 PART_NUMBER='CS00002JB13',
 VALUE='0',
 PRIM_FILE='./archive_libs/logical/q_res/chips/chips.prt';

PART_NAME
 R6096 'Q_RES_0402LF-0,5%,1/16W,CHIP,CS00002JB13':;

SECTION_NUMBER 1
 '@T6G_MB_LIB.T6G(SCH_1):PAGE79_I115@PURE_QUANTA.Q_RES(CHIPS)':
 C_PATH='@t6g_mb_lib.t6g(sch_1):page79_i115@pure_quanta.q_res(chips)',
 P_PATH='@t6g_mb_lib.t6g(sch_1):page80_i115@pure_quanta.q_res(chips)',
 PATH='I115',
 DRAWING='@T6G_MB_LIB.T6G(SCH_1):PAGE79',
 BOM_COST='MEM',
 WATTAGE='1/16W',
 TOLERANCE='5%',
 MATERIAL='CHIP',
 PHYS_PAGE='80',
 XY='(-6825,3950)',
 ROT='2',
 VER='1',
 PACK_TYPE='0402LF',
 LOCATION='R6096',
 CDS_LIB='pure_quanta',
 CDS_PART_NAME='Q_RES_0402LF-0,5%,1/16W,CHIP,CS00002JB13',
 PART_NUMBER='CS00002JB13',
 VALUE='0',
 PRIM_FILE='./archive_libs/logical/q_res/chips/chips.prt';

PART_NAME
 R6097 'Q_RES_0402LF-0,5%,1/16W,CHIP,CS00002JB13':;

SECTION_NUMBER 1
 '@T6G_MB_LIB.T6G(SCH_1):PAGE244_I40@PURE_QUANTA.Q_RES(CHIPS)':
 C_PATH='@t6g_mb_lib.t6g(sch_1):page244_i40@pure_quanta.q_res(chips)',
 P_PATH='@t6g_mb_lib.t6g(sch_1):page189_i40@pure_quanta.q_res(chips)',
 PATH='I40',
 DRAWING='@T6G_MB_LIB.T6G(SCH_1):PAGE244',
 WATTAGE='1/16W',
 TOLERANCE='5%',
 MATERIAL='CHIP',
 PHYS_PAGE='189',
 XY='(-6250,7750)',
 ROT='0',
 VER='1',
 PACK_TYPE='0402LF',
 LOCATION='R6097',
 CDS_LIB='pure_quanta',
 CDS_PART_NAME='Q_RES_0402LF-0,5%,1/16W,CHIP,CS00002JB13',
 PART_NUMBER='CS00002JB13',
 VALUE='0',
 PRIM_FILE='./archive_libs/logical/q_res/chips/chips.prt';

PART_NAME
 R6098 'Q_RES_0402LF-10K,5%,1/16W,EMPTY,CS31002JB08':;

SECTION_NUMBER 1
 '@T6G_MB_LIB.T6G(SCH_1):PAGE75_I99@PURE_QUANTA.Q_RES(CHIPS)':
 C_PATH='@t6g_mb_lib.t6g(sch_1):page75_i99@pure_quanta.q_res(chips)',
 P_PATH='@t6g_mb_lib.t6g(sch_1):page76_i99@pure_quanta.q_res(chips)',
 PATH='I99',
 DRAWING='@T6G_MB_LIB.T6G(SCH_1):PAGE75',
 WATTAGE='1/16W',
 TOLERANCE='5%',
 MATERIAL='EMPTY',
 PHYS_PAGE='76',
 XY='(-8625,3150)',
 ROT='0',
 VER='1',
 PACK_TYPE='0402LF',
 LOCATION='R6098',
 CDS_LIB='pure_quanta',
 CDS_PART_NAME='Q_RES_0402LF-10K,5%,1/16W,EMPTY,CS31002JB08',
 PART_NUMBER='CS31002JB08',
 VALUE='10K',
 PRIM_FILE='./archive_libs/logical/q_res/chips/chips.prt';

PART_NAME
 R6099 'Q_RES_0402LF-0,5%,1/16W,CHIP,CS00002JB13':;

SECTION_NUMBER 1
 '@T6G_MB_LIB.T6G(SCH_1):PAGE245_I67@PURE_QUANTA.Q_RES(CHIPS)':
 C_PATH='@t6g_mb_lib.t6g(sch_1):page245_i67@pure_quanta.q_res(chips)',
 P_PATH='@t6g_mb_lib.t6g(sch_1):page190_i67@pure_quanta.q_res(chips)',
 PATH='I67',
 DRAWING='@T6G_MB_LIB.T6G(SCH_1):PAGE245',
 WATTAGE='1/16W',
 TOLERANCE='5%',
 MATERIAL='CHIP',
 PHYS_PAGE='190',
 XY='(1425,150)',
 ROT='0',
 VER='1',
 PACK_TYPE='0402LF',
 LOCATION='R6099',
 CDS_LIB='pure_quanta',
 CDS_PART_NAME='Q_RES_0402LF-0,5%,1/16W,CHIP,CS00002JB13',
 PART_NUMBER='CS00002JB13',
 VALUE='0',
 PRIM_FILE='./archive_libs/logical/q_res/chips/chips.prt';

PART_NAME
 R6100 'Q_RES_0402LF-49.9,1%,1/16W,CHIP,CS04992FB07':;

SECTION_NUMBER 1
 '@T6G_MB_LIB.T6G(SCH_1):PAGE34_I125@PURE_QUANTA.Q_RES(CHIPS)':
 C_PATH='@t6g_mb_lib.t6g(sch_1):page34_i125@pure_quanta.q_res(chips)',
 P_PATH='@t6g_mb_lib.t6g(sch_1):page34_i125@pure_quanta.q_res(chips)',
 PATH='I125',
 DRAWING='@T6G_MB_LIB.T6G(SCH_1):PAGE34',
 WATTAGE='1/16W',
 TOLERANCE='1%',
 MATERIAL='CHIP',
 PHYS_PAGE='34',
 XY='(-5025,2725)',
 ROT='0',
 VER='1',
 PACK_TYPE='0402LF',
 LOCATION='R6100',
 CDS_LIB='pure_quanta',
 CDS_PART_NAME='Q_RES_0402LF-49.9,1%,1/16W,CHIP,CS04992FB07',
 PART_NUMBER='CS04992FB07',
 VALUE='49.9',
 PRIM_FILE='./archive_libs/logical/q_res/chips/chips.prt';

PART_NAME
 R6101 'Q_RES_0402LF-0,5%,1/16W,CHIP,CS00002JB13':;

SECTION_NUMBER 1
 '@T6G_MB_LIB.T6G(SCH_1):PAGE148_I375@PURE_QUANTA.Q_RES(CHIPS)':
 C_PATH='@t6g_mb_lib.t6g(sch_1):page148_i375@pure_quanta.q_res(chips)',
 P_PATH='@t6g_mb_lib.t6g(sch_1):page171_i375@pure_quanta.q_res(chips)',
 PATH='I375',
 DRAWING='@T6G_MB_LIB.T6G(SCH_1):PAGE148',
 BOM_COST='MEM',
 WATTAGE='1/16W',
 TOLERANCE='5%',
 MATERIAL='CHIP',
 PHYS_PAGE='171',
 XY='(-6125,3875)',
 ROT='0',
 VER='1',
 PACK_TYPE='0402LF',
 LOCATION='R6101',
 CDS_LIB='pure_quanta',
 CDS_PART_NAME='Q_RES_0402LF-0,5%,1/16W,CHIP,CS00002JB13',
 PART_NUMBER='CS00002JB13',
 VALUE='0',
 PRIM_FILE='./archive_libs/logical/q_res/chips/chips.prt';

PART_NAME
 R6102 'Q_RES_0402LF-0,5%,1/16W,CHIP,CS00002JB13':;

SECTION_NUMBER 1
 '@T6G_MB_LIB.T6G(SCH_1):PAGE148_I376@PURE_QUANTA.Q_RES(CHIPS)':
 C_PATH='@t6g_mb_lib.t6g(sch_1):page148_i376@pure_quanta.q_res(chips)',
 P_PATH='@t6g_mb_lib.t6g(sch_1):page171_i376@pure_quanta.q_res(chips)',
 PATH='I376',
 DRAWING='@T6G_MB_LIB.T6G(SCH_1):PAGE148',
 BOM_COST='MEM',
 WATTAGE='1/16W',
 TOLERANCE='5%',
 MATERIAL='CHIP',
 PHYS_PAGE='171',
 XY='(-6175,1925)',
 ROT='0',
 VER='1',
 PACK_TYPE='0402LF',
 LOCATION='R6102',
 CDS_LIB='pure_quanta',
 CDS_PART_NAME='Q_RES_0402LF-0,5%,1/16W,CHIP,CS00002JB13',
 PART_NUMBER='CS00002JB13',
 VALUE='0',
 PRIM_FILE='./archive_libs/logical/q_res/chips/chips.prt';

PART_NAME
 R6103 'Q_RES_0402LF-0,5%,1/16W,CHIP,CS00002JB13':;

SECTION_NUMBER 1
 '@T6G_MB_LIB.T6G(SCH_1):PAGE150_I76@PURE_QUANTA.Q_RES(CHIPS)':
 C_PATH='@t6g_mb_lib.t6g(sch_1):page150_i76@pure_quanta.q_res(chips)',
 P_PATH='@t6g_mb_lib.t6g(sch_1):page173_i76@pure_quanta.q_res(chips)',
 PATH='I76',
 DRAWING='@T6G_MB_LIB.T6G(SCH_1):PAGE150',
 BOM_COST='MEM',
 WATTAGE='1/16W',
 TOLERANCE='5%',
 MATERIAL='CHIP',
 PHYS_PAGE='173',
 XY='(-4200,2250)',
 ROT='0',
 VER='1',
 PACK_TYPE='0402LF',
 LOCATION='R6103',
 CDS_LIB='pure_quanta',
 CDS_PART_NAME='Q_RES_0402LF-0,5%,1/16W,CHIP,CS00002JB13',
 PART_NUMBER='CS00002JB13',
 VALUE='0',
 PRIM_FILE='./archive_libs/logical/q_res/chips/chips.prt';

PART_NAME
 R6104 'Q_RES_0402LF-0,5%,1/16W,CHIP,CS00002JB13':;

SECTION_NUMBER 1
 '@T6G_MB_LIB.T6G(SCH_1):PAGE151_I48@PURE_QUANTA.Q_RES(CHIPS)':
 C_PATH='@t6g_mb_lib.t6g(sch_1):page151_i48@pure_quanta.q_res(chips)',
 P_PATH='@t6g_mb_lib.t6g(sch_1):page174_i48@pure_quanta.q_res(chips)',
 PATH='I48',
 DRAWING='@T6G_MB_LIB.T6G(SCH_1):PAGE151',
 BOM_COST='MEM',
 WATTAGE='1/16W',
 TOLERANCE='5%',
 MATERIAL='CHIP',
 PHYS_PAGE='174',
 XY='(-6050,4950)',
 ROT='0',
 VER='1',
 PACK_TYPE='0402LF',
 LOCATION='R6104',
 CDS_LIB='pure_quanta',
 CDS_PART_NAME='Q_RES_0402LF-0,5%,1/16W,CHIP,CS00002JB13',
 PART_NUMBER='CS00002JB13',
 VALUE='0',
 PRIM_FILE='./archive_libs/logical/q_res/chips/chips.prt';

PART_NAME
 R6105 'Q_RES_0402LF-0,5%,1/16W,CHIP,CS00002JB13':;

SECTION_NUMBER 1
 '@T6G_MB_LIB.T6G(SCH_1):PAGE151_I49@PURE_QUANTA.Q_RES(CHIPS)':
 C_PATH='@t6g_mb_lib.t6g(sch_1):page151_i49@pure_quanta.q_res(chips)',
 P_PATH='@t6g_mb_lib.t6g(sch_1):page174_i49@pure_quanta.q_res(chips)',
 PATH='I49',
 DRAWING='@T6G_MB_LIB.T6G(SCH_1):PAGE151',
 BOM_COST='MEM',
 WATTAGE='1/16W',
 TOLERANCE='5%',
 MATERIAL='CHIP',
 PHYS_PAGE='174',
 XY='(-4225,4425)',
 ROT='0',
 VER='1',
 PACK_TYPE='0402LF',
 LOCATION='R6105',
 CDS_LIB='pure_quanta',
 CDS_PART_NAME='Q_RES_0402LF-0,5%,1/16W,CHIP,CS00002JB13',
 PART_NUMBER='CS00002JB13',
 VALUE='0',
 PRIM_FILE='./archive_libs/logical/q_res/chips/chips.prt';

PART_NAME
 R6106 'Q_RES_0402LF-10K,5%,1/16W,CHIP,CS31002JB08':;

SECTION_NUMBER 1
 '@T6G_MB_LIB.T6G(SCH_1):PAGE144_I81@PURE_QUANTA.Q_RES(CHIPS)':
 C_PATH='@t6g_mb_lib.t6g(sch_1):page144_i81@pure_quanta.q_res(chips)',
 P_PATH='@t6g_mb_lib.t6g(sch_1):page167_i81@pure_quanta.q_res(chips)',
 PATH='I81',
 DRAWING='@T6G_MB_LIB.T6G(SCH_1):PAGE144',
 WATTAGE='1/16W',
 TOLERANCE='5%',
 MATERIAL='CHIP',
 PHYS_PAGE='167',
 XY='(-1100,2600)',
 ROT='2',
 VER='2',
 PACK_TYPE='0402LF',
 LOCATION='R6106',
 CDS_LIB='pure_quanta',
 CDS_PART_NAME='Q_RES_0402LF-10K,5%,1/16W,CHIP,CS31002JB08',
 PART_NUMBER='CS31002JB08',
 VALUE='10K',
 PRIM_FILE='./archive_libs/logical/q_res/chips/chips.prt';

PART_NAME
 R6107 'Q_RES_0402LF-10K,5%,1/16W,CHIP,CS31002JB08':;

SECTION_NUMBER 1
 '@T6G_MB_LIB.T6G(SCH_1):PAGE144_I83@PURE_QUANTA.Q_RES(CHIPS)':
 C_PATH='@t6g_mb_lib.t6g(sch_1):page144_i83@pure_quanta.q_res(chips)',
 P_PATH='@t6g_mb_lib.t6g(sch_1):page167_i83@pure_quanta.q_res(chips)',
 PATH='I83',
 DRAWING='@T6G_MB_LIB.T6G(SCH_1):PAGE144',
 WATTAGE='1/16W',
 TOLERANCE='5%',
 MATERIAL='CHIP',
 PHYS_PAGE='167',
 XY='(-4600,2450)',
 ROT='2',
 VER='2',
 PACK_TYPE='0402LF',
 LOCATION='R6107',
 CDS_LIB='pure_quanta',
 CDS_PART_NAME='Q_RES_0402LF-10K,5%,1/16W,CHIP,CS31002JB08',
 PART_NUMBER='CS31002JB08',
 VALUE='10K',
 PRIM_FILE='./archive_libs/logical/q_res/chips/chips.prt';

PART_NAME
 R6108 'Q_RES_0402LF-0,5%,1/16W,CHIP,CS00002JB13':;

SECTION_NUMBER 1
 '@T6G_MB_LIB.T6G(SCH_1):PAGE149_I159@PURE_QUANTA.Q_RES(CHIPS)':
 C_PATH='@t6g_mb_lib.t6g(sch_1):page149_i159@pure_quanta.q_res(chips)',
 P_PATH='@t6g_mb_lib.t6g(sch_1):page172_i159@pure_quanta.q_res(chips)',
 PATH='I159',
 DRAWING='@T6G_MB_LIB.T6G(SCH_1):PAGE149',
 WATTAGE='1/16W',
 TOLERANCE='5%',
 MATERIAL='CHIP',
 PHYS_PAGE='172',
 XY='(-8400,3975)',
 ROT='0',
 VER='1',
 PACK_TYPE='0402LF',
 LOCATION='R6108',
 CDS_LIB='pure_quanta',
 CDS_PART_NAME='Q_RES_0402LF-0,5%,1/16W,CHIP,CS00002JB13',
 PART_NUMBER='CS00002JB13',
 VALUE='0',
 PRIM_FILE='./archive_libs/logical/q_res/chips/chips.prt';

PART_NAME
 R6109 'Q_RES_0402LF-0,5%,1/16W,CHIP,CS00002JB13':;

SECTION_NUMBER 1
 '@T6G_MB_LIB.T6G(SCH_1):PAGE150_I78@PURE_QUANTA.Q_RES(CHIPS)':
 C_PATH='@t6g_mb_lib.t6g(sch_1):page150_i78@pure_quanta.q_res(chips)',
 P_PATH='@t6g_mb_lib.t6g(sch_1):page173_i78@pure_quanta.q_res(chips)',
 PATH='I78',
 DRAWING='@T6G_MB_LIB.T6G(SCH_1):PAGE150',
 WATTAGE='1/16W',
 TOLERANCE='5%',
 MATERIAL='CHIP',
 PHYS_PAGE='173',
 XY='(-6775,2150)',
 ROT='0',
 VER='1',
 PACK_TYPE='0402LF',
 LOCATION='R6109',
 CDS_LIB='pure_quanta',
 CDS_PART_NAME='Q_RES_0402LF-0,5%,1/16W,CHIP,CS00002JB13',
 PART_NUMBER='CS00002JB13',
 VALUE='0',
 PRIM_FILE='./archive_libs/logical/q_res/chips/chips.prt';

PART_NAME
 R6110 'Q_RES_0402LF-0,5%,1/16W,CHIP,CS00002JB13':;

SECTION_NUMBER 1
 '@T6G_MB_LIB.T6G(SCH_1):PAGE151_I50@PURE_QUANTA.Q_RES(CHIPS)':
 C_PATH='@t6g_mb_lib.t6g(sch_1):page151_i50@pure_quanta.q_res(chips)',
 P_PATH='@t6g_mb_lib.t6g(sch_1):page174_i50@pure_quanta.q_res(chips)',
 PATH='I50',
 DRAWING='@T6G_MB_LIB.T6G(SCH_1):PAGE151',
 WATTAGE='1/16W',
 TOLERANCE='5%',
 MATERIAL='CHIP',
 PHYS_PAGE='174',
 XY='(-950,3425)',
 ROT='0',
 VER='1',
 PACK_TYPE='0402LF',
 LOCATION='R6110',
 CDS_LIB='pure_quanta',
 CDS_PART_NAME='Q_RES_0402LF-0,5%,1/16W,CHIP,CS00002JB13',
 PART_NUMBER='CS00002JB13',
 VALUE='0',
 PRIM_FILE='./archive_libs/logical/q_res/chips/chips.prt';

PART_NAME
 R6111 'Q_RES_0402LF-0,5%,1/16W,CHIP,CS00002JB13':;

SECTION_NUMBER 1
 '@T6G_MB_LIB.T6G(SCH_1):PAGE149_I160@PURE_QUANTA.Q_RES(CHIPS)':
 C_PATH='@t6g_mb_lib.t6g(sch_1):page149_i160@pure_quanta.q_res(chips)',
 P_PATH='@t6g_mb_lib.t6g(sch_1):page172_i160@pure_quanta.q_res(chips)',
 PATH='I160',
 DRAWING='@T6G_MB_LIB.T6G(SCH_1):PAGE149',
 WATTAGE='1/16W',
 TOLERANCE='5%',
 MATERIAL='CHIP',
 PHYS_PAGE='172',
 XY='(-5675,3925)',
 ROT='0',
 VER='1',
 PACK_TYPE='0402LF',
 LOCATION='R6111',
 CDS_LIB='pure_quanta',
 CDS_PART_NAME='Q_RES_0402LF-0,5%,1/16W,CHIP,CS00002JB13',
 PART_NUMBER='CS00002JB13',
 VALUE='0',
 PRIM_FILE='./archive_libs/logical/q_res/chips/chips.prt';

PART_NAME
 R6112 'Q_RES_0402LF-33.2,1%,1/16W,CHIP,CS03322FB03':;

SECTION_NUMBER 1
 '@T6G_MB_LIB.T6G(SCH_1):PAGE84_I91@PURE_QUANTA.Q_RES(CHIPS)':
 C_PATH='@t6g_mb_lib.t6g(sch_1):page84_i91@pure_quanta.q_res(chips)',
 P_PATH='@t6g_mb_lib.t6g(sch_1):page85_i91@pure_quanta.q_res(chips)',
 PATH='I91',
 DRAWING='@T6G_MB_LIB.T6G(SCH_1):PAGE84',
 BOM_COST='MEM',
 WATTAGE='1/16W',
 TOLERANCE='1%',
 MATERIAL='CHIP',
 PHYS_PAGE='85',
 XY='(-7550,1150)',
 ROT='0',
 VER='1',
 PACK_TYPE='0402LF',
 LOCATION='R6112',
 CDS_LIB='pure_quanta',
 CDS_PART_NAME='Q_RES_0402LF-33.2,1%,1/16W,CHIP,CS03322FB03',
 PART_NUMBER='CS03322FB03',
 VALUE='33.2',
 PRIM_FILE='./archive_libs/logical/q_res/chips/chips.prt';

PART_NAME
 R6113 'Q_RES_0402LF-33.2,1%,1/16W,CHIP,CS03322FB03':;

SECTION_NUMBER 1
 '@T6G_MB_LIB.T6G(SCH_1):PAGE84_I75@PURE_QUANTA.Q_RES(CHIPS)':
 C_PATH='@t6g_mb_lib.t6g(sch_1):page84_i75@pure_quanta.q_res(chips)',
 P_PATH='@t6g_mb_lib.t6g(sch_1):page85_i75@pure_quanta.q_res(chips)',
 PATH='I75',
 DRAWING='@T6G_MB_LIB.T6G(SCH_1):PAGE84',
 BOM_COST='MEM',
 WATTAGE='1/16W',
 TOLERANCE='1%',
 MATERIAL='CHIP',
 PHYS_PAGE='85',
 XY='(-7550,1000)',
 ROT='0',
 VER='1',
 PACK_TYPE='0402LF',
 LOCATION='R6113',
 CDS_LIB='pure_quanta',
 CDS_PART_NAME='Q_RES_0402LF-33.2,1%,1/16W,CHIP,CS03322FB03',
 PART_NUMBER='CS03322FB03',
 VALUE='33.2',
 PRIM_FILE='./archive_libs/logical/q_res/chips/chips.prt';

PART_NAME
 R6114 'Q_RES_0402LF-2K,1%,1/16W,CHIP,CS22002FB07':;

SECTION_NUMBER 1
 '@T6G_MB_LIB.T6G(SCH_1):PAGE82_I137@PURE_QUANTA.Q_RES(CHIPS)':
 C_PATH='@t6g_mb_lib.t6g(sch_1):page82_i137@pure_quanta.q_res(chips)',
 P_PATH='@t6g_mb_lib.t6g(sch_1):page83_i137@pure_quanta.q_res(chips)',
 PATH='I137',
 DRAWING='@T6G_MB_LIB.T6G(SCH_1):PAGE82',
 WATTAGE='1/16W',
 TOLERANCE='1%',
 MATERIAL='CHIP',
 PHYS_PAGE='83',
 XY='(-5350,5075)',
 ROT='0',
 VER='1',
 PACK_TYPE='0402LF',
 LOCATION='R6114',
 CDS_LIB='pure_quanta',
 CDS_PART_NAME='Q_RES_0402LF-2K,1%,1/16W,CHIP,CS22002FB07',
 PART_NUMBER='CS22002FB07',
 VALUE='2K',
 PRIM_FILE='./archive_libs/logical/q_res/chips/chips.prt';

PART_NAME
 R6115 'Q_RES_0402LF-2K,1%,1/16W,CHIP,CS22002FB07':;

SECTION_NUMBER 1
 '@T6G_MB_LIB.T6G(SCH_1):PAGE82_I141@PURE_QUANTA.Q_RES(CHIPS)':
 C_PATH='@t6g_mb_lib.t6g(sch_1):page82_i141@pure_quanta.q_res(chips)',
 P_PATH='@t6g_mb_lib.t6g(sch_1):page83_i141@pure_quanta.q_res(chips)',
 PATH='I141',
 DRAWING='@T6G_MB_LIB.T6G(SCH_1):PAGE82',
 WATTAGE='1/16W',
 TOLERANCE='1%',
 MATERIAL='CHIP',
 PHYS_PAGE='83',
 XY='(-5350,5025)',
 ROT='0',
 VER='1',
 PACK_TYPE='0402LF',
 LOCATION='R6115',
 CDS_LIB='pure_quanta',
 CDS_PART_NAME='Q_RES_0402LF-2K,1%,1/16W,CHIP,CS22002FB07',
 PART_NUMBER='CS22002FB07',
 VALUE='2K',
 PRIM_FILE='./archive_libs/logical/q_res/chips/chips.prt';

PART_NAME
 R6116 'Q_RES_0402LF-0,5%,1/16W,CHIP,CS00002JB13':;

SECTION_NUMBER 1
 '@T6G_MB_LIB.T6G(SCH_1):PAGE79_I129@PURE_QUANTA.Q_RES(CHIPS)':
 C_PATH='@t6g_mb_lib.t6g(sch_1):page79_i129@pure_quanta.q_res(chips)',
 P_PATH='@t6g_mb_lib.t6g(sch_1):page80_i129@pure_quanta.q_res(chips)',
 PATH='I129',
 DRAWING='@T6G_MB_LIB.T6G(SCH_1):PAGE79',
 BOM_COST='MEM',
 WATTAGE='1/16W',
 TOLERANCE='5%',
 MATERIAL='CHIP',
 PHYS_PAGE='80',
 XY='(-8450,4150)',
 ROT='2',
 VER='1',
 PACK_TYPE='0402LF',
 LOCATION='R6116',
 CDS_LIB='pure_quanta',
 CDS_PART_NAME='Q_RES_0402LF-0,5%,1/16W,CHIP,CS00002JB13',
 PART_NUMBER='CS00002JB13',
 VALUE='0',
 PRIM_FILE='./archive_libs/logical/q_res/chips/chips.prt';

PART_NAME
 R6117 'Q_RES_0402LF-100,1%,1/16W,CHIP,CS11002FB07':;

SECTION_NUMBER 1
 '@T6G_MB_LIB.T6G(SCH_1):PAGE79_I131@PURE_QUANTA.Q_RES(CHIPS)':
 C_PATH='@t6g_mb_lib.t6g(sch_1):page79_i131@pure_quanta.q_res(chips)',
 P_PATH='@t6g_mb_lib.t6g(sch_1):page80_i131@pure_quanta.q_res(chips)',
 PATH='I131',
 DRAWING='@T6G_MB_LIB.T6G(SCH_1):PAGE79',
 BOM_COST='MEM',
 WATTAGE='1/16W',
 TOLERANCE='1%',
 MATERIAL='CHIP',
 PHYS_PAGE='80',
 XY='(-2775,3950)',
 ROT='2',
 VER='1',
 PACK_TYPE='0402LF',
 LOCATION='R6117',
 CDS_LIB='pure_quanta',
 CDS_PART_NAME='Q_RES_0402LF-100,1%,1/16W,CHIP,CS11002FB07',
 PART_NUMBER='CS11002FB07',
 VALUE='100',
 PRIM_FILE='./archive_libs/logical/q_res/chips/chips.prt';

PART_NAME
 R6118 'Q_RES_0402LF-0,5%,1/16W,CHIP,CS00002JB13':;

SECTION_NUMBER 1
 '@T6G_MB_LIB.T6G(SCH_1):PAGE84_I103@PURE_QUANTA.Q_RES(CHIPS)':
 C_PATH='@t6g_mb_lib.t6g(sch_1):page84_i103@pure_quanta.q_res(chips)',
 P_PATH='@t6g_mb_lib.t6g(sch_1):page85_i103@pure_quanta.q_res(chips)',
 PATH='I103',
 DRAWING='@T6G_MB_LIB.T6G(SCH_1):PAGE84',
 BOM_COST='MEM',
 WATTAGE='1/16W',
 TOLERANCE='5%',
 MATERIAL='CHIP',
 PHYS_PAGE='85',
 XY='(-1275,3850)',
 ROT='2',
 VER='1',
 PACK_TYPE='0402LF',
 LOCATION='R6118',
 CDS_LIB='pure_quanta',
 CDS_PART_NAME='Q_RES_0402LF-0,5%,1/16W,CHIP,CS00002JB13',
 PART_NUMBER='CS00002JB13',
 VALUE='0',
 PRIM_FILE='./archive_libs/logical/q_res/chips/chips.prt';

PART_NAME
 R6119 'Q_RES_0402LF-0,5%,1/16W,CHIP,CS00002JB13':;

SECTION_NUMBER 1
 '@T6G_MB_LIB.T6G(SCH_1):PAGE315_I40@PURE_QUANTA.Q_RES(CHIPS)':
 C_PATH='@t6g_mb_lib.t6g(sch_1):page315_i40@pure_quanta.q_res(chips)',
 P_PATH='@t6g_mb_lib.t6g(sch_1):page269_i40@pure_quanta.q_res(chips)',
 PATH='I40',
 DRAWING='@T6G_MB_LIB.T6G(SCH_1):PAGE315',
 SEC_TYPE='0402LF',
 WATTAGE='1/16W',
 TOLERANCE='5%',
 MATERIAL='CHIP',
 PHYS_PAGE='269',
 XY='(-3900,2025)',
 ROT='0',
 VER='1',
 PACK_TYPE='0402LF',
 LOCATION='R6119',
 SEC='1',
 CDS_LIB='pure_quanta',
 CDS_PART_NAME='Q_RES_0402LF-0,5%,1/16W,CHIP,CS00002JB13',
 PART_NUMBER='CS00002JB13',
 VALUE='0',
 PRIM_FILE='./archive_libs/logical/q_res/chips/chips.prt';

PART_NAME
 R6120 'Q_RES_0402LF-1K,1%,1/16W,CHIP,CS21002FB06':;

SECTION_NUMBER 1
 '@T6G_MB_LIB.T6G(SCH_1):PAGE83_I115@PURE_QUANTA.Q_RES(CHIPS)':
 C_PATH='@t6g_mb_lib.t6g(sch_1):page83_i115@pure_quanta.q_res(chips)',
 P_PATH='@t6g_mb_lib.t6g(sch_1):page84_i115@pure_quanta.q_res(chips)',
 PATH='I115',
 DRAWING='@T6G_MB_LIB.T6G(SCH_1):PAGE83',
 WATTAGE='1/16W',
 TOLERANCE='1%',
 MATERIAL='CHIP',
 PHYS_PAGE='84',
 XY='(-8700,4350)',
 ROT='0',
 VER='2',
 PACK_TYPE='0402LF',
 LOCATION='R6120',
 CDS_LIB='pure_quanta',
 CDS_PART_NAME='Q_RES_0402LF-1K,1%,1/16W,CHIP,CS21002FB06',
 PART_NUMBER='CS21002FB06',
 VALUE='1K',
 PRIM_FILE='./archive_libs/logical/q_res/chips/chips.prt';

PART_NAME
 R6121 'Q_RES_0402LF-1K,1%,1/16W,EMPTY,CS21002FB06':;

SECTION_NUMBER 1
 '@T6G_MB_LIB.T6G(SCH_1):PAGE83_I120@PURE_QUANTA.Q_RES(CHIPS)':
 C_PATH='@t6g_mb_lib.t6g(sch_1):page83_i120@pure_quanta.q_res(chips)',
 P_PATH='@t6g_mb_lib.t6g(sch_1):page84_i120@pure_quanta.q_res(chips)',
 PATH='I120',
 DRAWING='@T6G_MB_LIB.T6G(SCH_1):PAGE83',
 WATTAGE='1/16W',
 TOLERANCE='1%',
 MATERIAL='EMPTY',
 PHYS_PAGE='84',
 XY='(-8375,4350)',
 ROT='0',
 VER='2',
 PACK_TYPE='0402LF',
 LOCATION='R6121',
 CDS_LIB='pure_quanta',
 CDS_PART_NAME='Q_RES_0402LF-1K,1%,1/16W,EMPTY,CS21002FB06',
 PART_NUMBER='CS21002FB06',
 VALUE='1K',
 PRIM_FILE='./archive_libs/logical/q_res/chips/chips.prt';

PART_NAME
 R6122 'Q_RES_0402LF-1K,1%,1/16W,EMPTY,CS21002FB06':;

SECTION_NUMBER 1
 '@T6G_MB_LIB.T6G(SCH_1):PAGE83_I50@PURE_QUANTA.Q_RES(CHIPS)':
 C_PATH='@t6g_mb_lib.t6g(sch_1):page83_i50@pure_quanta.q_res(chips)',
 P_PATH='@t6g_mb_lib.t6g(sch_1):page84_i50@pure_quanta.q_res(chips)',
 PATH='I50',
 DRAWING='@T6G_MB_LIB.T6G(SCH_1):PAGE83',
 WATTAGE='1/16W',
 TOLERANCE='1%',
 MATERIAL='EMPTY',
 PHYS_PAGE='84',
 XY='(-8050,4350)',
 ROT='0',
 VER='2',
 PACK_TYPE='0402LF',
 LOCATION='R6122',
 CDS_LIB='pure_quanta',
 CDS_PART_NAME='Q_RES_0402LF-1K,1%,1/16W,EMPTY,CS21002FB06',
 PART_NUMBER='CS21002FB06',
 VALUE='1K',
 PRIM_FILE='./archive_libs/logical/q_res/chips/chips.prt';

PART_NAME
 R6123 'Q_RES_0402LF-1K,1%,1/16W,EMPTY,CS21002FB06':;

SECTION_NUMBER 1
 '@T6G_MB_LIB.T6G(SCH_1):PAGE83_I71@PURE_QUANTA.Q_RES(CHIPS)':
 C_PATH='@t6g_mb_lib.t6g(sch_1):page83_i71@pure_quanta.q_res(chips)',
 P_PATH='@t6g_mb_lib.t6g(sch_1):page84_i71@pure_quanta.q_res(chips)',
 PATH='I71',
 DRAWING='@T6G_MB_LIB.T6G(SCH_1):PAGE83',
 WATTAGE='1/16W',
 TOLERANCE='1%',
 MATERIAL='EMPTY',
 PHYS_PAGE='84',
 XY='(-7700,4350)',
 ROT='0',
 VER='2',
 PACK_TYPE='0402LF',
 LOCATION='R6123',
 CDS_LIB='pure_quanta',
 CDS_PART_NAME='Q_RES_0402LF-1K,1%,1/16W,EMPTY,CS21002FB06',
 PART_NUMBER='CS21002FB06',
 VALUE='1K',
 PRIM_FILE='./archive_libs/logical/q_res/chips/chips.prt';

PART_NAME
 R6124 'Q_RES_0402LF-1K,1%,1/16W,EMPTY,CS21002FB06':;

SECTION_NUMBER 1
 '@T6G_MB_LIB.T6G(SCH_1):PAGE83_I72@PURE_QUANTA.Q_RES(CHIPS)':
 C_PATH='@t6g_mb_lib.t6g(sch_1):page83_i72@pure_quanta.q_res(chips)',
 P_PATH='@t6g_mb_lib.t6g(sch_1):page84_i72@pure_quanta.q_res(chips)',
 PATH='I72',
 DRAWING='@T6G_MB_LIB.T6G(SCH_1):PAGE83',
 WATTAGE='1/16W',
 TOLERANCE='1%',
 MATERIAL='EMPTY',
 PHYS_PAGE='84',
 XY='(-7350,4350)',
 ROT='0',
 VER='2',
 PACK_TYPE='0402LF',
 LOCATION='R6124',
 CDS_LIB='pure_quanta',
 CDS_PART_NAME='Q_RES_0402LF-1K,1%,1/16W,EMPTY,CS21002FB06',
 PART_NUMBER='CS21002FB06',
 VALUE='1K',
 PRIM_FILE='./archive_libs/logical/q_res/chips/chips.prt';

PART_NAME
 R6125 'Q_RES_0402LF-1K,1%,1/16W,EMPTY,CS21002FB06':;

SECTION_NUMBER 1
 '@T6G_MB_LIB.T6G(SCH_1):PAGE83_I116@PURE_QUANTA.Q_RES(CHIPS)':
 C_PATH='@t6g_mb_lib.t6g(sch_1):page83_i116@pure_quanta.q_res(chips)',
 P_PATH='@t6g_mb_lib.t6g(sch_1):page84_i116@pure_quanta.q_res(chips)',
 PATH='I116',
 DRAWING='@T6G_MB_LIB.T6G(SCH_1):PAGE83',
 WATTAGE='1/16W',
 TOLERANCE='1%',
 MATERIAL='EMPTY',
 PHYS_PAGE='84',
 XY='(-8700,3400)',
 ROT='0',
 VER='2',
 PACK_TYPE='0402LF',
 LOCATION='R6125',
 CDS_LIB='pure_quanta',
 CDS_PART_NAME='Q_RES_0402LF-1K,1%,1/16W,EMPTY,CS21002FB06',
 PART_NUMBER='CS21002FB06',
 VALUE='1K',
 PRIM_FILE='./archive_libs/logical/q_res/chips/chips.prt';

PART_NAME
 R6126 'Q_RES_0402LF-1K,1%,1/16W,CHIP,CS21002FB06':;

SECTION_NUMBER 1
 '@T6G_MB_LIB.T6G(SCH_1):PAGE83_I119@PURE_QUANTA.Q_RES(CHIPS)':
 C_PATH='@t6g_mb_lib.t6g(sch_1):page83_i119@pure_quanta.q_res(chips)',
 P_PATH='@t6g_mb_lib.t6g(sch_1):page84_i119@pure_quanta.q_res(chips)',
 PATH='I119',
 DRAWING='@T6G_MB_LIB.T6G(SCH_1):PAGE83',
 WATTAGE='1/16W',
 TOLERANCE='1%',
 MATERIAL='CHIP',
 PHYS_PAGE='84',
 XY='(-8375,3400)',
 ROT='0',
 VER='2',
 PACK_TYPE='0402LF',
 LOCATION='R6126',
 CDS_LIB='pure_quanta',
 CDS_PART_NAME='Q_RES_0402LF-1K,1%,1/16W,CHIP,CS21002FB06',
 PART_NUMBER='CS21002FB06',
 VALUE='1K',
 PRIM_FILE='./archive_libs/logical/q_res/chips/chips.prt';

PART_NAME
 R6127 'Q_RES_0402LF-1K,1%,1/16W,CHIP,CS21002FB06':;

SECTION_NUMBER 1
 '@T6G_MB_LIB.T6G(SCH_1):PAGE83_I46@PURE_QUANTA.Q_RES(CHIPS)':
 C_PATH='@t6g_mb_lib.t6g(sch_1):page83_i46@pure_quanta.q_res(chips)',
 P_PATH='@t6g_mb_lib.t6g(sch_1):page84_i46@pure_quanta.q_res(chips)',
 PATH='I46',
 DRAWING='@T6G_MB_LIB.T6G(SCH_1):PAGE83',
 WATTAGE='1/16W',
 TOLERANCE='1%',
 MATERIAL='CHIP',
 PHYS_PAGE='84',
 XY='(-8050,3400)',
 ROT='0',
 VER='2',
 PACK_TYPE='0402LF',
 LOCATION='R6127',
 CDS_LIB='pure_quanta',
 CDS_PART_NAME='Q_RES_0402LF-1K,1%,1/16W,CHIP,CS21002FB06',
 PART_NUMBER='CS21002FB06',
 VALUE='1K',
 PRIM_FILE='./archive_libs/logical/q_res/chips/chips.prt';

PART_NAME
 R6128 'Q_RES_0402LF-1K,1%,1/16W,CHIP,CS21002FB06':;

SECTION_NUMBER 1
 '@T6G_MB_LIB.T6G(SCH_1):PAGE83_I64@PURE_QUANTA.Q_RES(CHIPS)':
 C_PATH='@t6g_mb_lib.t6g(sch_1):page83_i64@pure_quanta.q_res(chips)',
 P_PATH='@t6g_mb_lib.t6g(sch_1):page84_i64@pure_quanta.q_res(chips)',
 PATH='I64',
 DRAWING='@T6G_MB_LIB.T6G(SCH_1):PAGE83',
 WATTAGE='1/16W',
 TOLERANCE='1%',
 MATERIAL='CHIP',
 PHYS_PAGE='84',
 XY='(-7700,3400)',
 ROT='0',
 VER='2',
 PACK_TYPE='0402LF',
 LOCATION='R6128',
 CDS_LIB='pure_quanta',
 CDS_PART_NAME='Q_RES_0402LF-1K,1%,1/16W,CHIP,CS21002FB06',
 PART_NUMBER='CS21002FB06',
 VALUE='1K',
 PRIM_FILE='./archive_libs/logical/q_res/chips/chips.prt';

PART_NAME
 R6129 'Q_RES_0402LF-1K,1%,1/16W,CHIP,CS21002FB06':;

SECTION_NUMBER 1
 '@T6G_MB_LIB.T6G(SCH_1):PAGE83_I65@PURE_QUANTA.Q_RES(CHIPS)':
 C_PATH='@t6g_mb_lib.t6g(sch_1):page83_i65@pure_quanta.q_res(chips)',
 P_PATH='@t6g_mb_lib.t6g(sch_1):page84_i65@pure_quanta.q_res(chips)',
 PATH='I65',
 DRAWING='@T6G_MB_LIB.T6G(SCH_1):PAGE83',
 WATTAGE='1/16W',
 TOLERANCE='1%',
 MATERIAL='CHIP',
 PHYS_PAGE='84',
 XY='(-7350,3400)',
 ROT='0',
 VER='2',
 PACK_TYPE='0402LF',
 LOCATION='R6129',
 CDS_LIB='pure_quanta',
 CDS_PART_NAME='Q_RES_0402LF-1K,1%,1/16W,CHIP,CS21002FB06',
 PART_NUMBER='CS21002FB06',
 VALUE='1K',
 PRIM_FILE='./archive_libs/logical/q_res/chips/chips.prt';

PART_NAME
 R6130 'Q_RES_0402LF-1K,1%,1/16W,CHIP,CS21002FB06':;

SECTION_NUMBER 1
 '@T6G_MB_LIB.T6G(SCH_1):PAGE83_I131@PURE_QUANTA.Q_RES(CHIPS)':
 C_PATH='@t6g_mb_lib.t6g(sch_1):page83_i131@pure_quanta.q_res(chips)',
 P_PATH='@t6g_mb_lib.t6g(sch_1):page84_i131@pure_quanta.q_res(chips)',
 PATH='I131',
 DRAWING='@T6G_MB_LIB.T6G(SCH_1):PAGE83',
 WATTAGE='1/16W',
 TOLERANCE='1%',
 MATERIAL='CHIP',
 PHYS_PAGE='84',
 XY='(-3650,4650)',
 ROT='0',
 VER='2',
 PACK_TYPE='0402LF',
 LOCATION='R6130',
 CDS_LIB='pure_quanta',
 CDS_PART_NAME='Q_RES_0402LF-1K,1%,1/16W,CHIP,CS21002FB06',
 PART_NUMBER='CS21002FB06',
 VALUE='1K',
 PRIM_FILE='./archive_libs/logical/q_res/chips/chips.prt';

PART_NAME
 R6131 'Q_RES_0402LF-1K,1%,1/16W,EMPTY,CS21002FB06':;

SECTION_NUMBER 1
 '@T6G_MB_LIB.T6G(SCH_1):PAGE83_I134@PURE_QUANTA.Q_RES(CHIPS)':
 C_PATH='@t6g_mb_lib.t6g(sch_1):page83_i134@pure_quanta.q_res(chips)',
 P_PATH='@t6g_mb_lib.t6g(sch_1):page84_i134@pure_quanta.q_res(chips)',
 PATH='I134',
 DRAWING='@T6G_MB_LIB.T6G(SCH_1):PAGE83',
 WATTAGE='1/16W',
 TOLERANCE='1%',
 MATERIAL='EMPTY',
 PHYS_PAGE='84',
 XY='(-3300,4650)',
 ROT='0',
 VER='2',
 PACK_TYPE='0402LF',
 LOCATION='R6131',
 CDS_LIB='pure_quanta',
 CDS_PART_NAME='Q_RES_0402LF-1K,1%,1/16W,EMPTY,CS21002FB06',
 PART_NUMBER='CS21002FB06',
 VALUE='1K',
 PRIM_FILE='./archive_libs/logical/q_res/chips/chips.prt';

PART_NAME
 R6132 'Q_RES_0402LF-1K,1%,1/16W,EMPTY,CS21002FB06':;

SECTION_NUMBER 1
 '@T6G_MB_LIB.T6G(SCH_1):PAGE83_I135@PURE_QUANTA.Q_RES(CHIPS)':
 C_PATH='@t6g_mb_lib.t6g(sch_1):page83_i135@pure_quanta.q_res(chips)',
 P_PATH='@t6g_mb_lib.t6g(sch_1):page84_i135@pure_quanta.q_res(chips)',
 PATH='I135',
 DRAWING='@T6G_MB_LIB.T6G(SCH_1):PAGE83',
 WATTAGE='1/16W',
 TOLERANCE='1%',
 MATERIAL='EMPTY',
 PHYS_PAGE='84',
 XY='(-2950,4650)',
 ROT='0',
 VER='2',
 PACK_TYPE='0402LF',
 LOCATION='R6132',
 CDS_LIB='pure_quanta',
 CDS_PART_NAME='Q_RES_0402LF-1K,1%,1/16W,EMPTY,CS21002FB06',
 PART_NUMBER='CS21002FB06',
 VALUE='1K',
 PRIM_FILE='./archive_libs/logical/q_res/chips/chips.prt';

PART_NAME
 R6133 'Q_RES_0402LF-1K,1%,1/16W,EMPTY,CS21002FB06':;

SECTION_NUMBER 1
 '@T6G_MB_LIB.T6G(SCH_1):PAGE83_I132@PURE_QUANTA.Q_RES(CHIPS)':
 C_PATH='@t6g_mb_lib.t6g(sch_1):page83_i132@pure_quanta.q_res(chips)',
 P_PATH='@t6g_mb_lib.t6g(sch_1):page84_i132@pure_quanta.q_res(chips)',
 PATH='I132',
 DRAWING='@T6G_MB_LIB.T6G(SCH_1):PAGE83',
 WATTAGE='1/16W',
 TOLERANCE='1%',
 MATERIAL='EMPTY',
 PHYS_PAGE='84',
 XY='(-3650,3700)',
 ROT='0',
 VER='2',
 PACK_TYPE='0402LF',
 LOCATION='R6133',
 CDS_LIB='pure_quanta',
 CDS_PART_NAME='Q_RES_0402LF-1K,1%,1/16W,EMPTY,CS21002FB06',
 PART_NUMBER='CS21002FB06',
 VALUE='1K',
 PRIM_FILE='./archive_libs/logical/q_res/chips/chips.prt';

PART_NAME
 R6134 'Q_RES_0402LF-1K,1%,1/16W,CHIP,CS21002FB06':;

SECTION_NUMBER 1
 '@T6G_MB_LIB.T6G(SCH_1):PAGE83_I133@PURE_QUANTA.Q_RES(CHIPS)':
 C_PATH='@t6g_mb_lib.t6g(sch_1):page83_i133@pure_quanta.q_res(chips)',
 P_PATH='@t6g_mb_lib.t6g(sch_1):page84_i133@pure_quanta.q_res(chips)',
 PATH='I133',
 DRAWING='@T6G_MB_LIB.T6G(SCH_1):PAGE83',
 WATTAGE='1/16W',
 TOLERANCE='1%',
 MATERIAL='CHIP',
 PHYS_PAGE='84',
 XY='(-3300,3700)',
 ROT='0',
 VER='2',
 PACK_TYPE='0402LF',
 LOCATION='R6134',
 CDS_LIB='pure_quanta',
 CDS_PART_NAME='Q_RES_0402LF-1K,1%,1/16W,CHIP,CS21002FB06',
 PART_NUMBER='CS21002FB06',
 VALUE='1K',
 PRIM_FILE='./archive_libs/logical/q_res/chips/chips.prt';

PART_NAME
 R6135 'Q_RES_0402LF-1K,1%,1/16W,CHIP,CS21002FB06':;

SECTION_NUMBER 1
 '@T6G_MB_LIB.T6G(SCH_1):PAGE83_I136@PURE_QUANTA.Q_RES(CHIPS)':
 C_PATH='@t6g_mb_lib.t6g(sch_1):page83_i136@pure_quanta.q_res(chips)',
 P_PATH='@t6g_mb_lib.t6g(sch_1):page84_i136@pure_quanta.q_res(chips)',
 PATH='I136',
 DRAWING='@T6G_MB_LIB.T6G(SCH_1):PAGE83',
 WATTAGE='1/16W',
 TOLERANCE='1%',
 MATERIAL='CHIP',
 PHYS_PAGE='84',
 XY='(-2950,3700)',
 ROT='0',
 VER='2',
 PACK_TYPE='0402LF',
 LOCATION='R6135',
 CDS_LIB='pure_quanta',
 CDS_PART_NAME='Q_RES_0402LF-1K,1%,1/16W,CHIP,CS21002FB06',
 PART_NUMBER='CS21002FB06',
 VALUE='1K',
 PRIM_FILE='./archive_libs/logical/q_res/chips/chips.prt';

PART_NAME
 R6136 'Q_RES_0402LF-1K,1%,1/16W,CHIP,CS21002FB06':;

SECTION_NUMBER 1
 '@T6G_MB_LIB.T6G(SCH_1):PAGE83_I117@PURE_QUANTA.Q_RES(CHIPS)':
 C_PATH='@t6g_mb_lib.t6g(sch_1):page83_i117@pure_quanta.q_res(chips)',
 P_PATH='@t6g_mb_lib.t6g(sch_1):page84_i117@pure_quanta.q_res(chips)',
 PATH='I117',
 DRAWING='@T6G_MB_LIB.T6G(SCH_1):PAGE83',
 WATTAGE='1/16W',
 TOLERANCE='1%',
 MATERIAL='CHIP',
 PHYS_PAGE='84',
 XY='(-8700,2075)',
 ROT='0',
 VER='2',
 PACK_TYPE='0402LF',
 LOCATION='R6136',
 CDS_LIB='pure_quanta',
 CDS_PART_NAME='Q_RES_0402LF-1K,1%,1/16W,CHIP,CS21002FB06',
 PART_NUMBER='CS21002FB06',
 VALUE='1K',
 PRIM_FILE='./archive_libs/logical/q_res/chips/chips.prt';

PART_NAME
 R6137 'Q_RES_0402LF-1K,1%,1/16W,EMPTY,CS21002FB06':;

SECTION_NUMBER 1
 '@T6G_MB_LIB.T6G(SCH_1):PAGE83_I121@PURE_QUANTA.Q_RES(CHIPS)':
 C_PATH='@t6g_mb_lib.t6g(sch_1):page83_i121@pure_quanta.q_res(chips)',
 P_PATH='@t6g_mb_lib.t6g(sch_1):page84_i121@pure_quanta.q_res(chips)',
 PATH='I121',
 DRAWING='@T6G_MB_LIB.T6G(SCH_1):PAGE83',
 WATTAGE='1/16W',
 TOLERANCE='1%',
 MATERIAL='EMPTY',
 PHYS_PAGE='84',
 XY='(-8375,2075)',
 ROT='0',
 VER='2',
 PACK_TYPE='0402LF',
 LOCATION='R6137',
 CDS_LIB='pure_quanta',
 CDS_PART_NAME='Q_RES_0402LF-1K,1%,1/16W,EMPTY,CS21002FB06',
 PART_NUMBER='CS21002FB06',
 VALUE='1K',
 PRIM_FILE='./archive_libs/logical/q_res/chips/chips.prt';

PART_NAME
 R6138 'Q_RES_0402LF-1K,1%,1/16W,EMPTY,CS21002FB06':;

SECTION_NUMBER 1
 '@T6G_MB_LIB.T6G(SCH_1):PAGE83_I39@PURE_QUANTA.Q_RES(CHIPS)':
 C_PATH='@t6g_mb_lib.t6g(sch_1):page83_i39@pure_quanta.q_res(chips)',
 P_PATH='@t6g_mb_lib.t6g(sch_1):page84_i39@pure_quanta.q_res(chips)',
 PATH='I39',
 DRAWING='@T6G_MB_LIB.T6G(SCH_1):PAGE83',
 WATTAGE='1/16W',
 TOLERANCE='1%',
 MATERIAL='EMPTY',
 PHYS_PAGE='84',
 XY='(-8050,2075)',
 ROT='0',
 VER='2',
 PACK_TYPE='0402LF',
 LOCATION='R6138',
 CDS_LIB='pure_quanta',
 CDS_PART_NAME='Q_RES_0402LF-1K,1%,1/16W,EMPTY,CS21002FB06',
 PART_NUMBER='CS21002FB06',
 VALUE='1K',
 PRIM_FILE='./archive_libs/logical/q_res/chips/chips.prt';

PART_NAME
 R6139 'Q_RES_0402LF-1K,1%,1/16W,EMPTY,CS21002FB06':;

SECTION_NUMBER 1
 '@T6G_MB_LIB.T6G(SCH_1):PAGE83_I55@PURE_QUANTA.Q_RES(CHIPS)':
 C_PATH='@t6g_mb_lib.t6g(sch_1):page83_i55@pure_quanta.q_res(chips)',
 P_PATH='@t6g_mb_lib.t6g(sch_1):page84_i55@pure_quanta.q_res(chips)',
 PATH='I55',
 DRAWING='@T6G_MB_LIB.T6G(SCH_1):PAGE83',
 WATTAGE='1/16W',
 TOLERANCE='1%',
 MATERIAL='EMPTY',
 PHYS_PAGE='84',
 XY='(-7700,2075)',
 ROT='0',
 VER='2',
 PACK_TYPE='0402LF',
 LOCATION='R6139',
 CDS_LIB='pure_quanta',
 CDS_PART_NAME='Q_RES_0402LF-1K,1%,1/16W,EMPTY,CS21002FB06',
 PART_NUMBER='CS21002FB06',
 VALUE='1K',
 PRIM_FILE='./archive_libs/logical/q_res/chips/chips.prt';

PART_NAME
 R6140 'Q_RES_0402LF-1K,1%,1/16W,EMPTY,CS21002FB06':;

SECTION_NUMBER 1
 '@T6G_MB_LIB.T6G(SCH_1):PAGE83_I56@PURE_QUANTA.Q_RES(CHIPS)':
 C_PATH='@t6g_mb_lib.t6g(sch_1):page83_i56@pure_quanta.q_res(chips)',
 P_PATH='@t6g_mb_lib.t6g(sch_1):page84_i56@pure_quanta.q_res(chips)',
 PATH='I56',
 DRAWING='@T6G_MB_LIB.T6G(SCH_1):PAGE83',
 WATTAGE='1/16W',
 TOLERANCE='1%',
 MATERIAL='EMPTY',
 PHYS_PAGE='84',
 XY='(-7350,2075)',
 ROT='0',
 VER='2',
 PACK_TYPE='0402LF',
 LOCATION='R6140',
 CDS_LIB='pure_quanta',
 CDS_PART_NAME='Q_RES_0402LF-1K,1%,1/16W,EMPTY,CS21002FB06',
 PART_NUMBER='CS21002FB06',
 VALUE='1K',
 PRIM_FILE='./archive_libs/logical/q_res/chips/chips.prt';

PART_NAME
 R6141 'Q_RES_0402LF-1K,1%,1/16W,EMPTY,CS21002FB06':;

SECTION_NUMBER 1
 '@T6G_MB_LIB.T6G(SCH_1):PAGE83_I118@PURE_QUANTA.Q_RES(CHIPS)':
 C_PATH='@t6g_mb_lib.t6g(sch_1):page83_i118@pure_quanta.q_res(chips)',
 P_PATH='@t6g_mb_lib.t6g(sch_1):page84_i118@pure_quanta.q_res(chips)',
 PATH='I118',
 DRAWING='@T6G_MB_LIB.T6G(SCH_1):PAGE83',
 WATTAGE='1/16W',
 TOLERANCE='1%',
 MATERIAL='EMPTY',
 PHYS_PAGE='84',
 XY='(-8700,1125)',
 ROT='0',
 VER='2',
 PACK_TYPE='0402LF',
 LOCATION='R6141',
 CDS_LIB='pure_quanta',
 CDS_PART_NAME='Q_RES_0402LF-1K,1%,1/16W,EMPTY,CS21002FB06',
 PART_NUMBER='CS21002FB06',
 VALUE='1K',
 PRIM_FILE='./archive_libs/logical/q_res/chips/chips.prt';

PART_NAME
 R6142 'Q_RES_0402LF-1K,1%,1/16W,CHIP,CS21002FB06':;

SECTION_NUMBER 1
 '@T6G_MB_LIB.T6G(SCH_1):PAGE83_I122@PURE_QUANTA.Q_RES(CHIPS)':
 C_PATH='@t6g_mb_lib.t6g(sch_1):page83_i122@pure_quanta.q_res(chips)',
 P_PATH='@t6g_mb_lib.t6g(sch_1):page84_i122@pure_quanta.q_res(chips)',
 PATH='I122',
 DRAWING='@T6G_MB_LIB.T6G(SCH_1):PAGE83',
 WATTAGE='1/16W',
 TOLERANCE='1%',
 MATERIAL='CHIP',
 PHYS_PAGE='84',
 XY='(-8375,1125)',
 ROT='0',
 VER='2',
 PACK_TYPE='0402LF',
 LOCATION='R6142',
 CDS_LIB='pure_quanta',
 CDS_PART_NAME='Q_RES_0402LF-1K,1%,1/16W,CHIP,CS21002FB06',
 PART_NUMBER='CS21002FB06',
 VALUE='1K',
 PRIM_FILE='./archive_libs/logical/q_res/chips/chips.prt';

PART_NAME
 R6143 'Q_RES_0402LF-1K,1%,1/16W,CHIP,CS21002FB06':;

SECTION_NUMBER 1
 '@T6G_MB_LIB.T6G(SCH_1):PAGE83_I36@PURE_QUANTA.Q_RES(CHIPS)':
 C_PATH='@t6g_mb_lib.t6g(sch_1):page83_i36@pure_quanta.q_res(chips)',
 P_PATH='@t6g_mb_lib.t6g(sch_1):page84_i36@pure_quanta.q_res(chips)',
 PATH='I36',
 DRAWING='@T6G_MB_LIB.T6G(SCH_1):PAGE83',
 WATTAGE='1/16W',
 TOLERANCE='1%',
 MATERIAL='CHIP',
 PHYS_PAGE='84',
 XY='(-8050,1125)',
 ROT='0',
 VER='2',
 PACK_TYPE='0402LF',
 LOCATION='R6143',
 CDS_LIB='pure_quanta',
 CDS_PART_NAME='Q_RES_0402LF-1K,1%,1/16W,CHIP,CS21002FB06',
 PART_NUMBER='CS21002FB06',
 VALUE='1K',
 PRIM_FILE='./archive_libs/logical/q_res/chips/chips.prt';

PART_NAME
 R6144 'Q_RES_0402LF-1K,1%,1/16W,CHIP,CS21002FB06':;

SECTION_NUMBER 1
 '@T6G_MB_LIB.T6G(SCH_1):PAGE83_I52@PURE_QUANTA.Q_RES(CHIPS)':
 C_PATH='@t6g_mb_lib.t6g(sch_1):page83_i52@pure_quanta.q_res(chips)',
 P_PATH='@t6g_mb_lib.t6g(sch_1):page84_i52@pure_quanta.q_res(chips)',
 PATH='I52',
 DRAWING='@T6G_MB_LIB.T6G(SCH_1):PAGE83',
 WATTAGE='1/16W',
 TOLERANCE='1%',
 MATERIAL='CHIP',
 PHYS_PAGE='84',
 XY='(-7700,1125)',
 ROT='0',
 VER='2',
 PACK_TYPE='0402LF',
 LOCATION='R6144',
 CDS_LIB='pure_quanta',
 CDS_PART_NAME='Q_RES_0402LF-1K,1%,1/16W,CHIP,CS21002FB06',
 PART_NUMBER='CS21002FB06',
 VALUE='1K',
 PRIM_FILE='./archive_libs/logical/q_res/chips/chips.prt';

PART_NAME
 R6145 'Q_RES_0402LF-1K,1%,1/16W,CHIP,CS21002FB06':;

SECTION_NUMBER 1
 '@T6G_MB_LIB.T6G(SCH_1):PAGE83_I54@PURE_QUANTA.Q_RES(CHIPS)':
 C_PATH='@t6g_mb_lib.t6g(sch_1):page83_i54@pure_quanta.q_res(chips)',
 P_PATH='@t6g_mb_lib.t6g(sch_1):page84_i54@pure_quanta.q_res(chips)',
 PATH='I54',
 DRAWING='@T6G_MB_LIB.T6G(SCH_1):PAGE83',
 WATTAGE='1/16W',
 TOLERANCE='1%',
 MATERIAL='CHIP',
 PHYS_PAGE='84',
 XY='(-7350,1125)',
 ROT='0',
 VER='2',
 PACK_TYPE='0402LF',
 LOCATION='R6145',
 CDS_LIB='pure_quanta',
 CDS_PART_NAME='Q_RES_0402LF-1K,1%,1/16W,CHIP,CS21002FB06',
 PART_NUMBER='CS21002FB06',
 VALUE='1K',
 PRIM_FILE='./archive_libs/logical/q_res/chips/chips.prt';

PART_NAME
 R6146 'Q_RES_0402LF-1K,1%,1/16W,CHIP,CS21002FB06':;

SECTION_NUMBER 1
 '@T6G_MB_LIB.T6G(SCH_1):PAGE83_I138@PURE_QUANTA.Q_RES(CHIPS)':
 C_PATH='@t6g_mb_lib.t6g(sch_1):page83_i138@pure_quanta.q_res(chips)',
 P_PATH='@t6g_mb_lib.t6g(sch_1):page84_i138@pure_quanta.q_res(chips)',
 PATH='I138',
 DRAWING='@T6G_MB_LIB.T6G(SCH_1):PAGE83',
 WATTAGE='1/16W',
 TOLERANCE='1%',
 MATERIAL='CHIP',
 PHYS_PAGE='84',
 XY='(-3650,2000)',
 ROT='0',
 VER='2',
 PACK_TYPE='0402LF',
 LOCATION='R6146',
 CDS_LIB='pure_quanta',
 CDS_PART_NAME='Q_RES_0402LF-1K,1%,1/16W,CHIP,CS21002FB06',
 PART_NUMBER='CS21002FB06',
 VALUE='1K',
 PRIM_FILE='./archive_libs/logical/q_res/chips/chips.prt';

PART_NAME
 R6147 'Q_RES_0402LF-1K,1%,1/16W,EMPTY,CS21002FB06':;

SECTION_NUMBER 1
 '@T6G_MB_LIB.T6G(SCH_1):PAGE83_I140@PURE_QUANTA.Q_RES(CHIPS)':
 C_PATH='@t6g_mb_lib.t6g(sch_1):page83_i140@pure_quanta.q_res(chips)',
 P_PATH='@t6g_mb_lib.t6g(sch_1):page84_i140@pure_quanta.q_res(chips)',
 PATH='I140',
 DRAWING='@T6G_MB_LIB.T6G(SCH_1):PAGE83',
 WATTAGE='1/16W',
 TOLERANCE='1%',
 MATERIAL='EMPTY',
 PHYS_PAGE='84',
 XY='(-3300,2000)',
 ROT='0',
 VER='2',
 PACK_TYPE='0402LF',
 LOCATION='R6147',
 CDS_LIB='pure_quanta',
 CDS_PART_NAME='Q_RES_0402LF-1K,1%,1/16W,EMPTY,CS21002FB06',
 PART_NUMBER='CS21002FB06',
 VALUE='1K',
 PRIM_FILE='./archive_libs/logical/q_res/chips/chips.prt';

PART_NAME
 R6148 'Q_RES_0402LF-1K,1%,1/16W,EMPTY,CS21002FB06':;

SECTION_NUMBER 1
 '@T6G_MB_LIB.T6G(SCH_1):PAGE83_I142@PURE_QUANTA.Q_RES(CHIPS)':
 C_PATH='@t6g_mb_lib.t6g(sch_1):page83_i142@pure_quanta.q_res(chips)',
 P_PATH='@t6g_mb_lib.t6g(sch_1):page84_i142@pure_quanta.q_res(chips)',
 PATH='I142',
 DRAWING='@T6G_MB_LIB.T6G(SCH_1):PAGE83',
 WATTAGE='1/16W',
 TOLERANCE='1%',
 MATERIAL='EMPTY',
 PHYS_PAGE='84',
 XY='(-2950,2000)',
 ROT='0',
 VER='2',
 PACK_TYPE='0402LF',
 LOCATION='R6148',
 CDS_LIB='pure_quanta',
 CDS_PART_NAME='Q_RES_0402LF-1K,1%,1/16W,EMPTY,CS21002FB06',
 PART_NUMBER='CS21002FB06',
 VALUE='1K',
 PRIM_FILE='./archive_libs/logical/q_res/chips/chips.prt';

PART_NAME
 R6149 'Q_RES_0402LF-1K,1%,1/16W,EMPTY,CS21002FB06':;

SECTION_NUMBER 1
 '@T6G_MB_LIB.T6G(SCH_1):PAGE83_I137@PURE_QUANTA.Q_RES(CHIPS)':
 C_PATH='@t6g_mb_lib.t6g(sch_1):page83_i137@pure_quanta.q_res(chips)',
 P_PATH='@t6g_mb_lib.t6g(sch_1):page84_i137@pure_quanta.q_res(chips)',
 PATH='I137',
 DRAWING='@T6G_MB_LIB.T6G(SCH_1):PAGE83',
 WATTAGE='1/16W',
 TOLERANCE='1%',
 MATERIAL='EMPTY',
 PHYS_PAGE='84',
 XY='(-3650,1050)',
 ROT='0',
 VER='2',
 PACK_TYPE='0402LF',
 LOCATION='R6149',
 CDS_LIB='pure_quanta',
 CDS_PART_NAME='Q_RES_0402LF-1K,1%,1/16W,EMPTY,CS21002FB06',
 PART_NUMBER='CS21002FB06',
 VALUE='1K',
 PRIM_FILE='./archive_libs/logical/q_res/chips/chips.prt';

PART_NAME
 R6150 'Q_RES_0402LF-1K,1%,1/16W,CHIP,CS21002FB06':;

SECTION_NUMBER 1
 '@T6G_MB_LIB.T6G(SCH_1):PAGE83_I139@PURE_QUANTA.Q_RES(CHIPS)':
 C_PATH='@t6g_mb_lib.t6g(sch_1):page83_i139@pure_quanta.q_res(chips)',
 P_PATH='@t6g_mb_lib.t6g(sch_1):page84_i139@pure_quanta.q_res(chips)',
 PATH='I139',
 DRAWING='@T6G_MB_LIB.T6G(SCH_1):PAGE83',
 WATTAGE='1/16W',
 TOLERANCE='1%',
 MATERIAL='CHIP',
 PHYS_PAGE='84',
 XY='(-3300,1050)',
 ROT='0',
 VER='2',
 PACK_TYPE='0402LF',
 LOCATION='R6150',
 CDS_LIB='pure_quanta',
 CDS_PART_NAME='Q_RES_0402LF-1K,1%,1/16W,CHIP,CS21002FB06',
 PART_NUMBER='CS21002FB06',
 VALUE='1K',
 PRIM_FILE='./archive_libs/logical/q_res/chips/chips.prt';

PART_NAME
 R6151 'Q_RES_0402LF-1K,1%,1/16W,CHIP,CS21002FB06':;

SECTION_NUMBER 1
 '@T6G_MB_LIB.T6G(SCH_1):PAGE83_I141@PURE_QUANTA.Q_RES(CHIPS)':
 C_PATH='@t6g_mb_lib.t6g(sch_1):page83_i141@pure_quanta.q_res(chips)',
 P_PATH='@t6g_mb_lib.t6g(sch_1):page84_i141@pure_quanta.q_res(chips)',
 PATH='I141',
 DRAWING='@T6G_MB_LIB.T6G(SCH_1):PAGE83',
 WATTAGE='1/16W',
 TOLERANCE='1%',
 MATERIAL='CHIP',
 PHYS_PAGE='84',
 XY='(-2950,1050)',
 ROT='0',
 VER='2',
 PACK_TYPE='0402LF',
 LOCATION='R6151',
 CDS_LIB='pure_quanta',
 CDS_PART_NAME='Q_RES_0402LF-1K,1%,1/16W,CHIP,CS21002FB06',
 PART_NUMBER='CS21002FB06',
 VALUE='1K',
 PRIM_FILE='./archive_libs/logical/q_res/chips/chips.prt';

PART_NAME
 R6152 'Q_RES_0201LF-0,5%,1/20W,CHIP,CS00001JE10':
 ROOM='PCIE REDRIVER BOM1';

SECTION_NUMBER 1
 '@T6G_MB_LIB.T6G(SCH_1):PAGE112_I8@PURE_QUANTA.Q_RES(CHIPS)':
 C_PATH='@t6g_mb_lib.t6g(sch_1):page112_i8@pure_quanta.q_res(chips)',
 P_PATH='@t6g_mb_lib.t6g(sch_1):page113_i8@pure_quanta.q_res(chips)',
 PATH='I8',
 DRAWING='@T6G_MB_LIB.T6G(SCH_1):PAGE112',
 WATTAGE='1/20W',
 TOLERANCE='5%',
 MATERIAL='CHIP',
 PHYS_PAGE='113',
 XY='(-7150,5325)',
 ROT='0',
 VER='1',
 PACK_TYPE='0201LF',
 LOCATION='R6152',
 CDS_LIB='pure_quanta',
 CDS_PART_NAME='Q_RES_0201LF-0,5%,1/20W,CHIP,CS00001JE10',
 ROOM='PCIE REDRIVER BOM1',
 PART_NUMBER='CS00001JE10',
 VALUE='0',
 PRIM_FILE='./archive_libs/logical/q_res/chips/chips.prt';

PART_NAME
 R6153 'Q_RES_0201LF-0,5%,1/20W,CHIP,CS00001JE10':
 ROOM='PCIE REDRIVER BOM1';

SECTION_NUMBER 1
 '@T6G_MB_LIB.T6G(SCH_1):PAGE112_I3@PURE_QUANTA.Q_RES(CHIPS)':
 C_PATH='@t6g_mb_lib.t6g(sch_1):page112_i3@pure_quanta.q_res(chips)',
 P_PATH='@t6g_mb_lib.t6g(sch_1):page113_i3@pure_quanta.q_res(chips)',
 PATH='I3',
 DRAWING='@T6G_MB_LIB.T6G(SCH_1):PAGE112',
 WATTAGE='1/20W',
 TOLERANCE='5%',
 MATERIAL='CHIP',
 PHYS_PAGE='113',
 XY='(-7150,5275)',
 ROT='0',
 VER='1',
 PACK_TYPE='0201LF',
 LOCATION='R6153',
 CDS_LIB='pure_quanta',
 CDS_PART_NAME='Q_RES_0201LF-0,5%,1/20W,CHIP,CS00001JE10',
 ROOM='PCIE REDRIVER BOM1',
 PART_NUMBER='CS00001JE10',
 VALUE='0',
 PRIM_FILE='./archive_libs/logical/q_res/chips/chips.prt';

PART_NAME
 R6154 'Q_RES_0201LF-0,5%,1/20W,CHIP,CS00001JE10':
 ROOM='PCIE REDRIVER BOM2';

SECTION_NUMBER 1
 '@T6G_MB_LIB.T6G(SCH_1):PAGE112_I1@PURE_QUANTA.Q_RES(CHIPS)':
 C_PATH='@t6g_mb_lib.t6g(sch_1):page112_i1@pure_quanta.q_res(chips)',
 P_PATH='@t6g_mb_lib.t6g(sch_1):page113_i1@pure_quanta.q_res(chips)',
 PATH='I1',
 DRAWING='@T6G_MB_LIB.T6G(SCH_1):PAGE112',
 WATTAGE='1/20W',
 TOLERANCE='5%',
 MATERIAL='CHIP',
 PHYS_PAGE='113',
 XY='(-7125,4975)',
 ROT='0',
 VER='1',
 PACK_TYPE='0201LF',
 LOCATION='R6154',
 CDS_LIB='pure_quanta',
 CDS_PART_NAME='Q_RES_0201LF-0,5%,1/20W,CHIP,CS00001JE10',
 ROOM='PCIE REDRIVER BOM2',
 PART_NUMBER='CS00001JE10',
 VALUE='0',
 PRIM_FILE='./archive_libs/logical/q_res/chips/chips.prt';

PART_NAME
 R6155 'Q_RES_0201LF-0,5%,1/20W,CHIP,CS00001JE10':
 ROOM='PCIE REDRIVER BOM2';

SECTION_NUMBER 1
 '@T6G_MB_LIB.T6G(SCH_1):PAGE112_I2@PURE_QUANTA.Q_RES(CHIPS)':
 C_PATH='@t6g_mb_lib.t6g(sch_1):page112_i2@pure_quanta.q_res(chips)',
 P_PATH='@t6g_mb_lib.t6g(sch_1):page113_i2@pure_quanta.q_res(chips)',
 PATH='I2',
 DRAWING='@T6G_MB_LIB.T6G(SCH_1):PAGE112',
 WATTAGE='1/20W',
 TOLERANCE='5%',
 MATERIAL='CHIP',
 PHYS_PAGE='113',
 XY='(-7125,4925)',
 ROT='0',
 VER='1',
 PACK_TYPE='0201LF',
 LOCATION='R6155',
 CDS_LIB='pure_quanta',
 CDS_PART_NAME='Q_RES_0201LF-0,5%,1/20W,CHIP,CS00001JE10',
 ROOM='PCIE REDRIVER BOM2',
 PART_NUMBER='CS00001JE10',
 VALUE='0',
 PRIM_FILE='./archive_libs/logical/q_res/chips/chips.prt';

PART_NAME
 R6156 'Q_RES_0201LF-0,5%,1/20W,CHIP,CS00001JE10':
 ROOM='PCIE REDRIVER BOM1';

SECTION_NUMBER 1
 '@T6G_MB_LIB.T6G(SCH_1):PAGE112_I21@PURE_QUANTA.Q_RES(CHIPS)':
 C_PATH='@t6g_mb_lib.t6g(sch_1):page112_i21@pure_quanta.q_res(chips)',
 P_PATH='@t6g_mb_lib.t6g(sch_1):page113_i21@pure_quanta.q_res(chips)',
 PATH='I21',
 DRAWING='@T6G_MB_LIB.T6G(SCH_1):PAGE112',
 WATTAGE='1/20W',
 TOLERANCE='5%',
 MATERIAL='CHIP',
 PHYS_PAGE='113',
 XY='(-7225,4200)',
 ROT='0',
 VER='1',
 PACK_TYPE='0201LF',
 LOCATION='R6156',
 CDS_LIB='pure_quanta',
 CDS_PART_NAME='Q_RES_0201LF-0,5%,1/20W,CHIP,CS00001JE10',
 ROOM='PCIE REDRIVER BOM1',
 PART_NUMBER='CS00001JE10',
 VALUE='0',
 PRIM_FILE='./archive_libs/logical/q_res/chips/chips.prt';

PART_NAME
 R6157 'Q_RES_0201LF-0,5%,1/20W,CHIP,CS00001JE10':
 ROOM='PCIE REDRIVER BOM1';

SECTION_NUMBER 1
 '@T6G_MB_LIB.T6G(SCH_1):PAGE112_I22@PURE_QUANTA.Q_RES(CHIPS)':
 C_PATH='@t6g_mb_lib.t6g(sch_1):page112_i22@pure_quanta.q_res(chips)',
 P_PATH='@t6g_mb_lib.t6g(sch_1):page113_i22@pure_quanta.q_res(chips)',
 PATH='I22',
 DRAWING='@T6G_MB_LIB.T6G(SCH_1):PAGE112',
 WATTAGE='1/20W',
 TOLERANCE='5%',
 MATERIAL='CHIP',
 PHYS_PAGE='113',
 XY='(-7225,4150)',
 ROT='0',
 VER='1',
 PACK_TYPE='0201LF',
 LOCATION='R6157',
 CDS_LIB='pure_quanta',
 CDS_PART_NAME='Q_RES_0201LF-0,5%,1/20W,CHIP,CS00001JE10',
 ROOM='PCIE REDRIVER BOM1',
 PART_NUMBER='CS00001JE10',
 VALUE='0',
 PRIM_FILE='./archive_libs/logical/q_res/chips/chips.prt';

PART_NAME
 R6158 'Q_RES_0201LF-0,5%,1/20W,CHIP,CS00001JE10':
 ROOM='PCIE REDRIVER BOM2';

SECTION_NUMBER 1
 '@T6G_MB_LIB.T6G(SCH_1):PAGE112_I24@PURE_QUANTA.Q_RES(CHIPS)':
 C_PATH='@t6g_mb_lib.t6g(sch_1):page112_i24@pure_quanta.q_res(chips)',
 P_PATH='@t6g_mb_lib.t6g(sch_1):page113_i24@pure_quanta.q_res(chips)',
 PATH='I24',
 DRAWING='@T6G_MB_LIB.T6G(SCH_1):PAGE112',
 WATTAGE='1/20W',
 TOLERANCE='5%',
 MATERIAL='CHIP',
 PHYS_PAGE='113',
 XY='(-7200,3850)',
 ROT='0',
 VER='1',
 PACK_TYPE='0201LF',
 LOCATION='R6158',
 CDS_LIB='pure_quanta',
 CDS_PART_NAME='Q_RES_0201LF-0,5%,1/20W,CHIP,CS00001JE10',
 ROOM='PCIE REDRIVER BOM2',
 PART_NUMBER='CS00001JE10',
 VALUE='0',
 PRIM_FILE='./archive_libs/logical/q_res/chips/chips.prt';

PART_NAME
 R6159 'Q_RES_0201LF-0,5%,1/20W,CHIP,CS00001JE10':
 ROOM='PCIE REDRIVER BOM2';

SECTION_NUMBER 1
 '@T6G_MB_LIB.T6G(SCH_1):PAGE112_I23@PURE_QUANTA.Q_RES(CHIPS)':
 C_PATH='@t6g_mb_lib.t6g(sch_1):page112_i23@pure_quanta.q_res(chips)',
 P_PATH='@t6g_mb_lib.t6g(sch_1):page113_i23@pure_quanta.q_res(chips)',
 PATH='I23',
 DRAWING='@T6G_MB_LIB.T6G(SCH_1):PAGE112',
 WATTAGE='1/20W',
 TOLERANCE='5%',
 MATERIAL='CHIP',
 PHYS_PAGE='113',
 XY='(-7200,3800)',
 ROT='0',
 VER='1',
 PACK_TYPE='0201LF',
 LOCATION='R6159',
 CDS_LIB='pure_quanta',
 CDS_PART_NAME='Q_RES_0201LF-0,5%,1/20W,CHIP,CS00001JE10',
 ROOM='PCIE REDRIVER BOM2',
 PART_NUMBER='CS00001JE10',
 VALUE='0',
 PRIM_FILE='./archive_libs/logical/q_res/chips/chips.prt';

PART_NAME
 R6160 'Q_RES_0402LF-1K,1%,1/16W,CHIP,CS21002FB06':
 ROOM='PCIE REDRIVER BOM2';

SECTION_NUMBER 1
 '@T6G_MB_LIB.T6G(SCH_1):PAGE111_I12@PURE_QUANTA.Q_RES(CHIPS)':
 C_PATH='@t6g_mb_lib.t6g(sch_1):page111_i12@pure_quanta.q_res(chips)',
 P_PATH='@t6g_mb_lib.t6g(sch_1):page112_i12@pure_quanta.q_res(chips)',
 PATH='I12',
 DRAWING='@T6G_MB_LIB.T6G(SCH_1):PAGE111',
 WATTAGE='1/16W',
 TOLERANCE='1%',
 MATERIAL='CHIP',
 PHYS_PAGE='112',
 XY='(-7525,4875)',
 ROT='0',
 VER='2',
 PACK_TYPE='0402LF',
 LOCATION='R6160',
 CDS_LIB='pure_quanta',
 CDS_PART_NAME='Q_RES_0402LF-1K,1%,1/16W,CHIP,CS21002FB06',
 ROOM='PCIE REDRIVER BOM2',
 PART_NUMBER='CS21002FB06',
 VALUE='1K',
 PRIM_FILE='./archive_libs/logical/q_res/chips/chips.prt';

PART_NAME
 R6162 'Q_RES_0402LF-0,5%,1/16W,CHIP,CS00002JB13':
 ROOM='PCIE REDRIVER BOM2';

SECTION_NUMBER 1
 '@T6G_MB_LIB.T6G(SCH_1):PAGE111_I23@PURE_QUANTA.Q_RES(CHIPS)':
 C_PATH='@t6g_mb_lib.t6g(sch_1):page111_i23@pure_quanta.q_res(chips)',
 P_PATH='@t6g_mb_lib.t6g(sch_1):page112_i23@pure_quanta.q_res(chips)',
 PATH='I23',
 DRAWING='@T6G_MB_LIB.T6G(SCH_1):PAGE111',
 WATTAGE='1/16W',
 TOLERANCE='5%',
 MATERIAL='CHIP',
 PHYS_PAGE='112',
 XY='(-3275,5225)',
 ROT='0',
 VER='1',
 PACK_TYPE='0402LF',
 LOCATION='R6162',
 CDS_LIB='pure_quanta',
 CDS_PART_NAME='Q_RES_0402LF-0,5%,1/16W,CHIP,CS00002JB13',
 ROOM='PCIE REDRIVER BOM2',
 PART_NUMBER='CS00002JB13',
 VALUE='0',
 PRIM_FILE='./archive_libs/logical/q_res/chips/chips.prt';

PART_NAME
 R6163 'Q_RES_0402LF-1K,1%,1/16W,EMPTY,CS21002FB06':
 ROOM='PCIE REDRIVER BOM2';

SECTION_NUMBER 1
 '@T6G_MB_LIB.T6G(SCH_1):PAGE111_I39@PURE_QUANTA.Q_RES(CHIPS)':
 C_PATH='@t6g_mb_lib.t6g(sch_1):page111_i39@pure_quanta.q_res(chips)',
 P_PATH='@t6g_mb_lib.t6g(sch_1):page112_i39@pure_quanta.q_res(chips)',
 PATH='I39',
 DRAWING='@T6G_MB_LIB.T6G(SCH_1):PAGE111',
 WATTAGE='1/16W',
 TOLERANCE='1%',
 MATERIAL='EMPTY',
 PHYS_PAGE='112',
 XY='(-7000,3425)',
 ROT='0',
 VER='2',
 PACK_TYPE='0402LF',
 LOCATION='R6163',
 CDS_LIB='pure_quanta',
 CDS_PART_NAME='Q_RES_0402LF-1K,1%,1/16W,EMPTY,CS21002FB06',
 ROOM='PCIE REDRIVER BOM2',
 PART_NUMBER='CS21002FB06',
 VALUE='1K',
 PRIM_FILE='./archive_libs/logical/q_res/chips/chips.prt';

PART_NAME
 R6164 'Q_RES_0402LF-1K,1%,1/16W,CHIP,CS21002FB06':
 ROOM='PCIE REDRIVER BOM2';

SECTION_NUMBER 1
 '@T6G_MB_LIB.T6G(SCH_1):PAGE111_I32@PURE_QUANTA.Q_RES(CHIPS)':
 C_PATH='@t6g_mb_lib.t6g(sch_1):page111_i32@pure_quanta.q_res(chips)',
 P_PATH='@t6g_mb_lib.t6g(sch_1):page112_i32@pure_quanta.q_res(chips)',
 PATH='I32',
 DRAWING='@T6G_MB_LIB.T6G(SCH_1):PAGE111',
 WATTAGE='1/16W',
 TOLERANCE='1%',
 MATERIAL='CHIP',
 PHYS_PAGE='112',
 XY='(-7000,2850)',
 ROT='0',
 VER='2',
 PACK_TYPE='0402LF',
 LOCATION='R6164',
 CDS_LIB='pure_quanta',
 CDS_PART_NAME='Q_RES_0402LF-1K,1%,1/16W,CHIP,CS21002FB06',
 ROOM='PCIE REDRIVER BOM2',
 PART_NUMBER='CS21002FB06',
 VALUE='1K',
 PRIM_FILE='./archive_libs/logical/q_res/chips/chips.prt';

PART_NAME
 R6165 'Q_RES_0402LF-1K,1%,1/16W,EMPTY,CS21002FB06':
 ROOM='PCIE REDRIVER BOM2';

SECTION_NUMBER 1
 '@T6G_MB_LIB.T6G(SCH_1):PAGE111_I41@PURE_QUANTA.Q_RES(CHIPS)':
 C_PATH='@t6g_mb_lib.t6g(sch_1):page111_i41@pure_quanta.q_res(chips)',
 P_PATH='@t6g_mb_lib.t6g(sch_1):page112_i41@pure_quanta.q_res(chips)',
 PATH='I41',
 DRAWING='@T6G_MB_LIB.T6G(SCH_1):PAGE111',
 WATTAGE='1/16W',
 TOLERANCE='1%',
 MATERIAL='EMPTY',
 PHYS_PAGE='112',
 XY='(-6550,3425)',
 ROT='0',
 VER='2',
 PACK_TYPE='0402LF',
 LOCATION='R6165',
 CDS_LIB='pure_quanta',
 CDS_PART_NAME='Q_RES_0402LF-1K,1%,1/16W,EMPTY,CS21002FB06',
 ROOM='PCIE REDRIVER BOM2',
 PART_NUMBER='CS21002FB06',
 VALUE='1K',
 PRIM_FILE='./archive_libs/logical/q_res/chips/chips.prt';

PART_NAME
 R6166 'Q_RES_0402LF-1K,1%,1/16W,EMPTY,CS21002FB06':
 ROOM='PCIE REDRIVER BOM2';

SECTION_NUMBER 1
 '@T6G_MB_LIB.T6G(SCH_1):PAGE111_I40@PURE_QUANTA.Q_RES(CHIPS)':
 C_PATH='@t6g_mb_lib.t6g(sch_1):page111_i40@pure_quanta.q_res(chips)',
 P_PATH='@t6g_mb_lib.t6g(sch_1):page112_i40@pure_quanta.q_res(chips)',
 PATH='I40',
 DRAWING='@T6G_MB_LIB.T6G(SCH_1):PAGE111',
 WATTAGE='1/16W',
 TOLERANCE='1%',
 MATERIAL='EMPTY',
 PHYS_PAGE='112',
 XY='(-6550,2850)',
 ROT='0',
 VER='2',
 PACK_TYPE='0402LF',
 LOCATION='R6166',
 CDS_LIB='pure_quanta',
 CDS_PART_NAME='Q_RES_0402LF-1K,1%,1/16W,EMPTY,CS21002FB06',
 ROOM='PCIE REDRIVER BOM2',
 PART_NUMBER='CS21002FB06',
 VALUE='1K',
 PRIM_FILE='./archive_libs/logical/q_res/chips/chips.prt';

PART_NAME
 R6167 'Q_RES_0402LF-1K,1%,1/16W,EMPTY,CS21002FB06':
 ROOM='PCIE REDRIVER BOM2';

SECTION_NUMBER 1
 '@T6G_MB_LIB.T6G(SCH_1):PAGE111_I57@PURE_QUANTA.Q_RES(CHIPS)':
 C_PATH='@t6g_mb_lib.t6g(sch_1):page111_i57@pure_quanta.q_res(chips)',
 P_PATH='@t6g_mb_lib.t6g(sch_1):page112_i57@pure_quanta.q_res(chips)',
 PATH='I57',
 DRAWING='@T6G_MB_LIB.T6G(SCH_1):PAGE111',
 WATTAGE='1/16W',
 TOLERANCE='1%',
 MATERIAL='EMPTY',
 PHYS_PAGE='112',
 XY='(-6975,1725)',
 ROT='0',
 VER='2',
 PACK_TYPE='0402LF',
 LOCATION='R6167',
 CDS_LIB='pure_quanta',
 CDS_PART_NAME='Q_RES_0402LF-1K,1%,1/16W,EMPTY,CS21002FB06',
 ROOM='PCIE REDRIVER BOM2',
 PART_NUMBER='CS21002FB06',
 VALUE='1K',
 PRIM_FILE='./archive_libs/logical/q_res/chips/chips.prt';

PART_NAME
 R6168 'Q_RES_0402LF-1K,1%,1/16W,CHIP,CS21002FB06':
 ROOM='PCIE REDRIVER BOM2';

SECTION_NUMBER 1
 '@T6G_MB_LIB.T6G(SCH_1):PAGE111_I58@PURE_QUANTA.Q_RES(CHIPS)':
 C_PATH='@t6g_mb_lib.t6g(sch_1):page111_i58@pure_quanta.q_res(chips)',
 P_PATH='@t6g_mb_lib.t6g(sch_1):page112_i58@pure_quanta.q_res(chips)',
 PATH='I58',
 DRAWING='@T6G_MB_LIB.T6G(SCH_1):PAGE111',
 WATTAGE='1/16W',
 TOLERANCE='1%',
 MATERIAL='CHIP',
 PHYS_PAGE='112',
 XY='(-6975,1150)',
 ROT='0',
 VER='2',
 PACK_TYPE='0402LF',
 LOCATION='R6168',
 CDS_LIB='pure_quanta',
 CDS_PART_NAME='Q_RES_0402LF-1K,1%,1/16W,CHIP,CS21002FB06',
 ROOM='PCIE REDRIVER BOM2',
 PART_NUMBER='CS21002FB06',
 VALUE='1K',
 PRIM_FILE='./archive_libs/logical/q_res/chips/chips.prt';

PART_NAME
 R6169 'Q_RES_0402LF-1K,1%,1/16W,EMPTY,CS21002FB06':
 ROOM='PCIE REDRIVER BOM2';

SECTION_NUMBER 1
 '@T6G_MB_LIB.T6G(SCH_1):PAGE111_I53@PURE_QUANTA.Q_RES(CHIPS)':
 C_PATH='@t6g_mb_lib.t6g(sch_1):page111_i53@pure_quanta.q_res(chips)',
 P_PATH='@t6g_mb_lib.t6g(sch_1):page112_i53@pure_quanta.q_res(chips)',
 PATH='I53',
 DRAWING='@T6G_MB_LIB.T6G(SCH_1):PAGE111',
 WATTAGE='1/16W',
 TOLERANCE='1%',
 MATERIAL='EMPTY',
 PHYS_PAGE='112',
 XY='(-6525,1725)',
 ROT='0',
 VER='2',
 PACK_TYPE='0402LF',
 LOCATION='R6169',
 CDS_LIB='pure_quanta',
 CDS_PART_NAME='Q_RES_0402LF-1K,1%,1/16W,EMPTY,CS21002FB06',
 ROOM='PCIE REDRIVER BOM2',
 PART_NUMBER='CS21002FB06',
 VALUE='1K',
 PRIM_FILE='./archive_libs/logical/q_res/chips/chips.prt';

PART_NAME
 R6170 'Q_RES_0402LF-1K,1%,1/16W,CHIP,CS21002FB06':
 ROOM='PCIE REDRIVER BOM2';

SECTION_NUMBER 1
 '@T6G_MB_LIB.T6G(SCH_1):PAGE111_I60@PURE_QUANTA.Q_RES(CHIPS)':
 C_PATH='@t6g_mb_lib.t6g(sch_1):page111_i60@pure_quanta.q_res(chips)',
 P_PATH='@t6g_mb_lib.t6g(sch_1):page112_i60@pure_quanta.q_res(chips)',
 PATH='I60',
 DRAWING='@T6G_MB_LIB.T6G(SCH_1):PAGE111',
 WATTAGE='1/16W',
 TOLERANCE='1%',
 MATERIAL='CHIP',
 PHYS_PAGE='112',
 XY='(-6525,1150)',
 ROT='0',
 VER='2',
 PACK_TYPE='0402LF',
 LOCATION='R6170',
 CDS_LIB='pure_quanta',
 CDS_PART_NAME='Q_RES_0402LF-1K,1%,1/16W,CHIP,CS21002FB06',
 ROOM='PCIE REDRIVER BOM2',
 PART_NUMBER='CS21002FB06',
 VALUE='1K',
 PRIM_FILE='./archive_libs/logical/q_res/chips/chips.prt';

PART_NAME
 R6171 'Q_RES_0402LF-1K,1%,1/16W,EMPTY,CS21002FB06':
 ROOM='PCIE REDRIVER BOM2';

SECTION_NUMBER 1
 '@T6G_MB_LIB.T6G(SCH_1):PAGE111_I48@PURE_QUANTA.Q_RES(CHIPS)':
 C_PATH='@t6g_mb_lib.t6g(sch_1):page111_i48@pure_quanta.q_res(chips)',
 P_PATH='@t6g_mb_lib.t6g(sch_1):page112_i48@pure_quanta.q_res(chips)',
 PATH='I48',
 DRAWING='@T6G_MB_LIB.T6G(SCH_1):PAGE111',
 WATTAGE='1/16W',
 TOLERANCE='1%',
 MATERIAL='EMPTY',
 PHYS_PAGE='112',
 XY='(-5075,3425)',
 ROT='0',
 VER='2',
 PACK_TYPE='0402LF',
 LOCATION='R6171',
 CDS_LIB='pure_quanta',
 CDS_PART_NAME='Q_RES_0402LF-1K,1%,1/16W,EMPTY,CS21002FB06',
 ROOM='PCIE REDRIVER BOM2',
 PART_NUMBER='CS21002FB06',
 VALUE='1K',
 PRIM_FILE='./archive_libs/logical/q_res/chips/chips.prt';

PART_NAME
 R6172 'Q_RES_0402LF-1K,1%,1/16W,CHIP,CS21002FB06':
 ROOM='PCIE REDRIVER BOM2';

SECTION_NUMBER 1
 '@T6G_MB_LIB.T6G(SCH_1):PAGE111_I49@PURE_QUANTA.Q_RES(CHIPS)':
 C_PATH='@t6g_mb_lib.t6g(sch_1):page111_i49@pure_quanta.q_res(chips)',
 P_PATH='@t6g_mb_lib.t6g(sch_1):page112_i49@pure_quanta.q_res(chips)',
 PATH='I49',
 DRAWING='@T6G_MB_LIB.T6G(SCH_1):PAGE111',
 WATTAGE='1/16W',
 TOLERANCE='1%',
 MATERIAL='CHIP',
 PHYS_PAGE='112',
 XY='(-5075,2850)',
 ROT='0',
 VER='2',
 PACK_TYPE='0402LF',
 LOCATION='R6172',
 CDS_LIB='pure_quanta',
 CDS_PART_NAME='Q_RES_0402LF-1K,1%,1/16W,CHIP,CS21002FB06',
 ROOM='PCIE REDRIVER BOM2',
 PART_NUMBER='CS21002FB06',
 VALUE='1K',
 PRIM_FILE='./archive_libs/logical/q_res/chips/chips.prt';

PART_NAME
 R6173 'Q_RES_0402LF-1K,1%,1/16W,EMPTY,CS21002FB06':
 ROOM='PCIE REDRIVER BOM2';

SECTION_NUMBER 1
 '@T6G_MB_LIB.T6G(SCH_1):PAGE111_I44@PURE_QUANTA.Q_RES(CHIPS)':
 C_PATH='@t6g_mb_lib.t6g(sch_1):page111_i44@pure_quanta.q_res(chips)',
 P_PATH='@t6g_mb_lib.t6g(sch_1):page112_i44@pure_quanta.q_res(chips)',
 PATH='I44',
 DRAWING='@T6G_MB_LIB.T6G(SCH_1):PAGE111',
 WATTAGE='1/16W',
 TOLERANCE='1%',
 MATERIAL='EMPTY',
 PHYS_PAGE='112',
 XY='(-4625,3425)',
 ROT='0',
 VER='2',
 PACK_TYPE='0402LF',
 LOCATION='R6173',
 CDS_LIB='pure_quanta',
 CDS_PART_NAME='Q_RES_0402LF-1K,1%,1/16W,EMPTY,CS21002FB06',
 ROOM='PCIE REDRIVER BOM2',
 PART_NUMBER='CS21002FB06',
 VALUE='1K',
 PRIM_FILE='./archive_libs/logical/q_res/chips/chips.prt';

PART_NAME
 R6174 'Q_RES_0402LF-1K,1%,1/16W,EMPTY,CS21002FB06':
 ROOM='PCIE REDRIVER BOM2';

SECTION_NUMBER 1
 '@T6G_MB_LIB.T6G(SCH_1):PAGE111_I45@PURE_QUANTA.Q_RES(CHIPS)':
 C_PATH='@t6g_mb_lib.t6g(sch_1):page111_i45@pure_quanta.q_res(chips)',
 P_PATH='@t6g_mb_lib.t6g(sch_1):page112_i45@pure_quanta.q_res(chips)',
 PATH='I45',
 DRAWING='@T6G_MB_LIB.T6G(SCH_1):PAGE111',
 WATTAGE='1/16W',
 TOLERANCE='1%',
 MATERIAL='EMPTY',
 PHYS_PAGE='112',
 XY='(-4625,2850)',
 ROT='0',
 VER='2',
 PACK_TYPE='0402LF',
 LOCATION='R6174',
 CDS_LIB='pure_quanta',
 CDS_PART_NAME='Q_RES_0402LF-1K,1%,1/16W,EMPTY,CS21002FB06',
 ROOM='PCIE REDRIVER BOM2',
 PART_NUMBER='CS21002FB06',
 VALUE='1K',
 PRIM_FILE='./archive_libs/logical/q_res/chips/chips.prt';

PART_NAME
 R6175 'Q_RES_0402LF-1K,1%,1/16W,EMPTY,CS21002FB06':
 ROOM='PCIE REDRIVER BOM2';

SECTION_NUMBER 1
 '@T6G_MB_LIB.T6G(SCH_1):PAGE111_I63@PURE_QUANTA.Q_RES(CHIPS)':
 C_PATH='@t6g_mb_lib.t6g(sch_1):page111_i63@pure_quanta.q_res(chips)',
 P_PATH='@t6g_mb_lib.t6g(sch_1):page112_i63@pure_quanta.q_res(chips)',
 PATH='I63',
 DRAWING='@T6G_MB_LIB.T6G(SCH_1):PAGE111',
 WATTAGE='1/16W',
 TOLERANCE='1%',
 MATERIAL='EMPTY',
 PHYS_PAGE='112',
 XY='(-4825,1625)',
 ROT='0',
 VER='2',
 PACK_TYPE='0402LF',
 LOCATION='R6175',
 CDS_LIB='pure_quanta',
 CDS_PART_NAME='Q_RES_0402LF-1K,1%,1/16W,EMPTY,CS21002FB06',
 ROOM='PCIE REDRIVER BOM2',
 PART_NUMBER='CS21002FB06',
 VALUE='1K',
 PRIM_FILE='./archive_libs/logical/q_res/chips/chips.prt';

PART_NAME
 R6176 'Q_RES_0402LF-1K,1%,1/16W,EMPTY,CS21002FB06':
 ROOM='PCIE REDRIVER BOM2';

SECTION_NUMBER 1
 '@T6G_MB_LIB.T6G(SCH_1):PAGE111_I64@PURE_QUANTA.Q_RES(CHIPS)':
 C_PATH='@t6g_mb_lib.t6g(sch_1):page111_i64@pure_quanta.q_res(chips)',
 P_PATH='@t6g_mb_lib.t6g(sch_1):page112_i64@pure_quanta.q_res(chips)',
 PATH='I64',
 DRAWING='@T6G_MB_LIB.T6G(SCH_1):PAGE111',
 WATTAGE='1/16W',
 TOLERANCE='1%',
 MATERIAL='EMPTY',
 PHYS_PAGE='112',
 XY='(-4825,1050)',
 ROT='0',
 VER='2',
 PACK_TYPE='0402LF',
 LOCATION='R6176',
 CDS_LIB='pure_quanta',
 CDS_PART_NAME='Q_RES_0402LF-1K,1%,1/16W,EMPTY,CS21002FB06',
 ROOM='PCIE REDRIVER BOM2',
 PART_NUMBER='CS21002FB06',
 VALUE='1K',
 PRIM_FILE='./archive_libs/logical/q_res/chips/chips.prt';

PART_NAME
 R6177 'Q_RES_0402LF-1K,1%,1/16W,CHIP,CS21002FB06':
 ROOM='PCIE REDRIVER BOM2';

SECTION_NUMBER 1
 '@T6G_MB_LIB.T6G(SCH_1):PAGE111_I77@PURE_QUANTA.Q_RES(CHIPS)':
 C_PATH='@t6g_mb_lib.t6g(sch_1):page111_i77@pure_quanta.q_res(chips)',
 P_PATH='@t6g_mb_lib.t6g(sch_1):page112_i77@pure_quanta.q_res(chips)',
 PATH='I77',
 DRAWING='@T6G_MB_LIB.T6G(SCH_1):PAGE111',
 WATTAGE='1/16W',
 TOLERANCE='1%',
 MATERIAL='CHIP',
 PHYS_PAGE='112',
 XY='(-3475,1650)',
 ROT='0',
 VER='2',
 PACK_TYPE='0402LF',
 LOCATION='R6177',
 CDS_LIB='pure_quanta',
 CDS_PART_NAME='Q_RES_0402LF-1K,1%,1/16W,CHIP,CS21002FB06',
 ROOM='PCIE REDRIVER BOM2',
 PART_NUMBER='CS21002FB06',
 VALUE='1K',
 PRIM_FILE='./archive_libs/logical/q_res/chips/chips.prt';

PART_NAME
 R6178 'Q_RES_0402LF-1K,1%,1/16W,EMPTY,CS21002FB06':
 ROOM='PCIE REDRIVER BOM2';

SECTION_NUMBER 1
 '@T6G_MB_LIB.T6G(SCH_1):PAGE111_I68@PURE_QUANTA.Q_RES(CHIPS)':
 C_PATH='@t6g_mb_lib.t6g(sch_1):page111_i68@pure_quanta.q_res(chips)',
 P_PATH='@t6g_mb_lib.t6g(sch_1):page112_i68@pure_quanta.q_res(chips)',
 PATH='I68',
 DRAWING='@T6G_MB_LIB.T6G(SCH_1):PAGE111',
 WATTAGE='1/16W',
 TOLERANCE='1%',
 MATERIAL='EMPTY',
 PHYS_PAGE='112',
 XY='(-3475,1075)',
 ROT='0',
 VER='2',
 PACK_TYPE='0402LF',
 LOCATION='R6178',
 CDS_LIB='pure_quanta',
 CDS_PART_NAME='Q_RES_0402LF-1K,1%,1/16W,EMPTY,CS21002FB06',
 ROOM='PCIE REDRIVER BOM2',
 PART_NUMBER='CS21002FB06',
 VALUE='1K',
 PRIM_FILE='./archive_libs/logical/q_res/chips/chips.prt';

PART_NAME
 R6179 'Q_RES_0402LF-1K,1%,1/16W,CHIP,CS21002FB06':
 ROOM='PCIE REDRIVER BOM2';

SECTION_NUMBER 1
 '@T6G_MB_LIB.T6G(SCH_1):PAGE111_I78@PURE_QUANTA.Q_RES(CHIPS)':
 C_PATH='@t6g_mb_lib.t6g(sch_1):page111_i78@pure_quanta.q_res(chips)',
 P_PATH='@t6g_mb_lib.t6g(sch_1):page112_i78@pure_quanta.q_res(chips)',
 PATH='I78',
 DRAWING='@T6G_MB_LIB.T6G(SCH_1):PAGE111',
 WATTAGE='1/16W',
 TOLERANCE='1%',
 MATERIAL='CHIP',
 PHYS_PAGE='112',
 XY='(-2125,1625)',
 ROT='0',
 VER='2',
 PACK_TYPE='0402LF',
 LOCATION='R6179',
 CDS_LIB='pure_quanta',
 CDS_PART_NAME='Q_RES_0402LF-1K,1%,1/16W,CHIP,CS21002FB06',
 ROOM='PCIE REDRIVER BOM2',
 PART_NUMBER='CS21002FB06',
 VALUE='1K',
 PRIM_FILE='./archive_libs/logical/q_res/chips/chips.prt';

PART_NAME
 R6180 'Q_RES_0402LF-1K,1%,1/16W,EMPTY,CS21002FB06':
 ROOM='PCIE REDRIVER BOM2';

SECTION_NUMBER 1
 '@T6G_MB_LIB.T6G(SCH_1):PAGE111_I73@PURE_QUANTA.Q_RES(CHIPS)':
 C_PATH='@t6g_mb_lib.t6g(sch_1):page111_i73@pure_quanta.q_res(chips)',
 P_PATH='@t6g_mb_lib.t6g(sch_1):page112_i73@pure_quanta.q_res(chips)',
 PATH='I73',
 DRAWING='@T6G_MB_LIB.T6G(SCH_1):PAGE111',
 WATTAGE='1/16W',
 TOLERANCE='1%',
 MATERIAL='EMPTY',
 PHYS_PAGE='112',
 XY='(-2125,1050)',
 ROT='0',
 VER='2',
 PACK_TYPE='0402LF',
 LOCATION='R6180',
 CDS_LIB='pure_quanta',
 CDS_PART_NAME='Q_RES_0402LF-1K,1%,1/16W,EMPTY,CS21002FB06',
 ROOM='PCIE REDRIVER BOM2',
 PART_NUMBER='CS21002FB06',
 VALUE='1K',
 PRIM_FILE='./archive_libs/logical/q_res/chips/chips.prt';

PART_NAME
 R6181 'Q_RES_0402LF-4.7K,5%,1/16W,CHIP,CS24702JB10':;

SECTION_NUMBER 1
 '@T6G_MB_LIB.T6G(SCH_1):PAGE148_I381@PURE_QUANTA.Q_RES(CHIPS)':
 C_PATH='@t6g_mb_lib.t6g(sch_1):page148_i381@pure_quanta.q_res(chips)',
 P_PATH='@t6g_mb_lib.t6g(sch_1):page171_i381@pure_quanta.q_res(chips)',
 PATH='I381',
 DRAWING='@T6G_MB_LIB.T6G(SCH_1):PAGE148',
 WATTAGE='1/16W',
 TOLERANCE='5%',
 MATERIAL='CHIP',
 PHYS_PAGE='171',
 XY='(-5400,1550)',
 ROT='0',
 VER='2',
 PACK_TYPE='0402LF',
 LOCATION='R6181',
 CDS_LIB='pure_quanta',
 CDS_PART_NAME='Q_RES_0402LF-4.7K,5%,1/16W,CHIP,CS24702JB10',
 PART_NUMBER='CS24702JB10',
 VALUE='4.7K',
 PRIM_FILE='./archive_libs/logical/q_res/chips/chips.prt';

PART_NAME
 R6182 'Q_RES_0402LF-4.7K,5%,1/16W,CHIP,CS24702JB10':;

SECTION_NUMBER 1
 '@T6G_MB_LIB.T6G(SCH_1):PAGE148_I384@PURE_QUANTA.Q_RES(CHIPS)':
 C_PATH='@t6g_mb_lib.t6g(sch_1):page148_i384@pure_quanta.q_res(chips)',
 P_PATH='@t6g_mb_lib.t6g(sch_1):page171_i384@pure_quanta.q_res(chips)',
 PATH='I384',
 DRAWING='@T6G_MB_LIB.T6G(SCH_1):PAGE148',
 WATTAGE='1/16W',
 TOLERANCE='5%',
 MATERIAL='CHIP',
 PHYS_PAGE='171',
 XY='(-4250,3575)',
 ROT='0',
 VER='2',
 PACK_TYPE='0402LF',
 LOCATION='R6182',
 CDS_LIB='pure_quanta',
 CDS_PART_NAME='Q_RES_0402LF-4.7K,5%,1/16W,CHIP,CS24702JB10',
 PART_NUMBER='CS24702JB10',
 VALUE='4.7K',
 PRIM_FILE='./archive_libs/logical/q_res/chips/chips.prt';

PART_NAME
 R6183 'Q_RES_0402LF-0,5%,1/16W,CHIP,CS00002JB13':;

SECTION_NUMBER 1
 '@T6G_MB_LIB.T6G(SCH_1):PAGE81_I164@PURE_QUANTA.Q_RES(CHIPS)':
 C_PATH='@t6g_mb_lib.t6g(sch_1):page81_i164@pure_quanta.q_res(chips)',
 P_PATH='@t6g_mb_lib.t6g(sch_1):page82_i164@pure_quanta.q_res(chips)',
 PATH='I164',
 DRAWING='@T6G_MB_LIB.T6G(SCH_1):PAGE81',
 BOM_COST='MEM',
 WATTAGE='1/16W',
 TOLERANCE='5%',
 MATERIAL='CHIP',
 PHYS_PAGE='82',
 XY='(-6325,3825)',
 ROT='0',
 VER='1',
 PACK_TYPE='0402LF',
 LOCATION='R6183',
 CDS_LIB='pure_quanta',
 CDS_PART_NAME='Q_RES_0402LF-0,5%,1/16W,CHIP,CS00002JB13',
 PART_NUMBER='CS00002JB13',
 VALUE='0',
 PRIM_FILE='./archive_libs/logical/q_res/chips/chips.prt';

PART_NAME
 R6184 'Q_RES_0402LF-0,5%,1/16W,CHIP,CS00002JB13':;

SECTION_NUMBER 1
 '@T6G_MB_LIB.T6G(SCH_1):PAGE81_I165@PURE_QUANTA.Q_RES(CHIPS)':
 C_PATH='@t6g_mb_lib.t6g(sch_1):page81_i165@pure_quanta.q_res(chips)',
 P_PATH='@t6g_mb_lib.t6g(sch_1):page82_i165@pure_quanta.q_res(chips)',
 PATH='I165',
 DRAWING='@T6G_MB_LIB.T6G(SCH_1):PAGE81',
 BOM_COST='MEM',
 WATTAGE='1/16W',
 TOLERANCE='5%',
 MATERIAL='CHIP',
 PHYS_PAGE='82',
 XY='(-6325,3775)',
 ROT='0',
 VER='1',
 PACK_TYPE='0402LF',
 LOCATION='R6184',
 CDS_LIB='pure_quanta',
 CDS_PART_NAME='Q_RES_0402LF-0,5%,1/16W,CHIP,CS00002JB13',
 PART_NUMBER='CS00002JB13',
 VALUE='0',
 PRIM_FILE='./archive_libs/logical/q_res/chips/chips.prt';

PART_NAME
 R6185 'Q_RES_0402LF-10K,1%,1/16W,CHIP,CS31002FB08':;

SECTION_NUMBER 1
 '@T6G_MB_LIB.T6G(SCH_1):PAGE82_I143@PURE_QUANTA.Q_RES(CHIPS)':
 C_PATH='@t6g_mb_lib.t6g(sch_1):page82_i143@pure_quanta.q_res(chips)',
 P_PATH='@t6g_mb_lib.t6g(sch_1):page83_i143@pure_quanta.q_res(chips)',
 PATH='I143',
 DRAWING='@T6G_MB_LIB.T6G(SCH_1):PAGE82',
 BOM_COST='MEM',
 WATTAGE='1/16W',
 TOLERANCE='1%',
 MATERIAL='CHIP',
 PHYS_PAGE='83',
 XY='(-2875,3250)',
 ROT='0',
 VER='2',
 PACK_TYPE='0402LF',
 LOCATION='R6185',
 CDS_LIB='pure_quanta',
 CDS_PART_NAME='Q_RES_0402LF-10K,1%,1/16W,CHIP,CS31002FB08',
 PART_NUMBER='CS31002FB08',
 VALUE='10K',
 PRIM_FILE='./archive_libs/logical/q_res/chips/chips.prt';

PART_NAME
 R6186 'Q_RES_0402LF-4.7K,5%,1/16W,EMPTY,CS24702JB10':;

SECTION_NUMBER 1
 '@T6G_MB_LIB.T6G(SCH_1):PAGE82_I146@PURE_QUANTA.Q_RES(CHIPS)':
 C_PATH='@t6g_mb_lib.t6g(sch_1):page82_i146@pure_quanta.q_res(chips)',
 P_PATH='@t6g_mb_lib.t6g(sch_1):page83_i146@pure_quanta.q_res(chips)',
 PATH='I146',
 DRAWING='@T6G_MB_LIB.T6G(SCH_1):PAGE82',
 WATTAGE='1/16W',
 TOLERANCE='5%',
 MATERIAL='EMPTY',
 PHYS_PAGE='83',
 XY='(-7050,5175)',
 ROT='0',
 VER='1',
 PACK_TYPE='0402LF',
 LOCATION='R6186',
 CDS_LIB='pure_quanta',
 CDS_PART_NAME='Q_RES_0402LF-4.7K,5%,1/16W,EMPTY,CS24702JB10',
 PART_NUMBER='CS24702JB10',
 VALUE='4.7K',
 PRIM_FILE='./archive_libs/logical/q_res/chips/chips.prt';

PART_NAME
 R6187 'Q_RES_0402LF-10K,1%,1/16W,EMPTY,CS31002FB08':;

SECTION_NUMBER 1
 '@T6G_MB_LIB.T6G(SCH_1):PAGE82_I151@PURE_QUANTA.Q_RES(CHIPS)':
 C_PATH='@t6g_mb_lib.t6g(sch_1):page82_i151@pure_quanta.q_res(chips)',
 P_PATH='@t6g_mb_lib.t6g(sch_1):page83_i151@pure_quanta.q_res(chips)',
 PATH='I151',
 DRAWING='@T6G_MB_LIB.T6G(SCH_1):PAGE82',
 WATTAGE='1/16W',
 TOLERANCE='1%',
 MATERIAL='EMPTY',
 PHYS_PAGE='83',
 XY='(-2675,3225)',
 ROT='0',
 VER='2',
 PACK_TYPE='0402LF',
 LOCATION='R6187',
 CDS_LIB='pure_quanta',
 CDS_PART_NAME='Q_RES_0402LF-10K,1%,1/16W,EMPTY,CS31002FB08',
 PART_NUMBER='CS31002FB08',
 VALUE='10K',
 PRIM_FILE='./archive_libs/logical/q_res/chips/chips.prt';

PART_NAME
 R6188 'Q_RES_0402LF-4.7K,5%,1/16W,EMPTY,CS24702JB10':;

SECTION_NUMBER 1
 '@T6G_MB_LIB.T6G(SCH_1):PAGE82_I152@PURE_QUANTA.Q_RES(CHIPS)':
 C_PATH='@t6g_mb_lib.t6g(sch_1):page82_i152@pure_quanta.q_res(chips)',
 P_PATH='@t6g_mb_lib.t6g(sch_1):page83_i152@pure_quanta.q_res(chips)',
 PATH='I152',
 DRAWING='@T6G_MB_LIB.T6G(SCH_1):PAGE82',
 WATTAGE='1/16W',
 TOLERANCE='5%',
 MATERIAL='EMPTY',
 PHYS_PAGE='83',
 XY='(-7050,5125)',
 ROT='0',
 VER='1',
 PACK_TYPE='0402LF',
 LOCATION='R6188',
 CDS_LIB='pure_quanta',
 CDS_PART_NAME='Q_RES_0402LF-4.7K,5%,1/16W,EMPTY,CS24702JB10',
 PART_NUMBER='CS24702JB10',
 VALUE='4.7K',
 PRIM_FILE='./archive_libs/logical/q_res/chips/chips.prt';

PART_NAME
 R6190 'Q_RES_0201LF-0,5%,1/20W,CHIP,CS00001JE10':
 ROOM='USB3_HUB1';

SECTION_NUMBER 1
 '@T6G_MB_LIB.T6G(SCH_1):PAGE158_I6@PURE_QUANTA.Q_RES(CHIPS)':
 C_PATH='@t6g_mb_lib.t6g(sch_1):page158_i6@pure_quanta.q_res(chips)',
 P_PATH='@t6g_mb_lib.t6g(sch_1):page180_i6@pure_quanta.q_res(chips)',
 PATH='I6',
 DRAWING='@T6G_MB_LIB.T6G(SCH_1):PAGE158',
 WATTAGE='1/20W',
 TOLERANCE='5%',
 MATERIAL='CHIP',
 PHYS_PAGE='180',
 XY='(-7550,6000)',
 ROT='0',
 VER='1',
 PACK_TYPE='0201LF',
 LOCATION='R6190',
 CDS_LIB='pure_quanta',
 CDS_PART_NAME='Q_RES_0201LF-0,5%,1/20W,CHIP,CS00001JE10',
 ROOM='USB3_HUB1',
 PART_NUMBER='CS00001JE10',
 VALUE='0',
 PRIM_FILE='./archive_libs/logical/q_res/chips/chips.prt';

PART_NAME
 R6191 'Q_RES_0201LF-0,5%,1/20W,CHIP,CS00001JE10':
 ROOM='USB3_HUB1';

SECTION_NUMBER 1
 '@T6G_MB_LIB.T6G(SCH_1):PAGE158_I5@PURE_QUANTA.Q_RES(CHIPS)':
 C_PATH='@t6g_mb_lib.t6g(sch_1):page158_i5@pure_quanta.q_res(chips)',
 P_PATH='@t6g_mb_lib.t6g(sch_1):page180_i5@pure_quanta.q_res(chips)',
 PATH='I5',
 DRAWING='@T6G_MB_LIB.T6G(SCH_1):PAGE158',
 WATTAGE='1/20W',
 TOLERANCE='5%',
 MATERIAL='CHIP',
 PHYS_PAGE='180',
 XY='(-7550,5950)',
 ROT='0',
 VER='1',
 PACK_TYPE='0201LF',
 LOCATION='R6191',
 CDS_LIB='pure_quanta',
 CDS_PART_NAME='Q_RES_0201LF-0,5%,1/20W,CHIP,CS00001JE10',
 ROOM='USB3_HUB1',
 PART_NUMBER='CS00001JE10',
 VALUE='0',
 PRIM_FILE='./archive_libs/logical/q_res/chips/chips.prt';

PART_NAME
 R6192 'Q_RES_0201LF-0,5%,1/20W,CHIP,CS00001JE10':
 ROOM='USB3_HUB2';

SECTION_NUMBER 1
 '@T6G_MB_LIB.T6G(SCH_1):PAGE158_I3@PURE_QUANTA.Q_RES(CHIPS)':
 C_PATH='@t6g_mb_lib.t6g(sch_1):page158_i3@pure_quanta.q_res(chips)',
 P_PATH='@t6g_mb_lib.t6g(sch_1):page180_i3@pure_quanta.q_res(chips)',
 PATH='I3',
 DRAWING='@T6G_MB_LIB.T6G(SCH_1):PAGE158',
 WATTAGE='1/20W',
 TOLERANCE='5%',
 MATERIAL='CHIP',
 PHYS_PAGE='180',
 XY='(-7525,5650)',
 ROT='0',
 VER='1',
 PACK_TYPE='0201LF',
 LOCATION='R6192',
 CDS_LIB='pure_quanta',
 CDS_PART_NAME='Q_RES_0201LF-0,5%,1/20W,CHIP,CS00001JE10',
 ROOM='USB3_HUB2',
 PART_NUMBER='CS00001JE10',
 VALUE='0',
 PRIM_FILE='./archive_libs/logical/q_res/chips/chips.prt';

PART_NAME
 R6193 'Q_RES_0201LF-0,5%,1/20W,CHIP,CS00001JE10':
 ROOM='USB3_HUB2';

SECTION_NUMBER 1
 '@T6G_MB_LIB.T6G(SCH_1):PAGE158_I4@PURE_QUANTA.Q_RES(CHIPS)':
 C_PATH='@t6g_mb_lib.t6g(sch_1):page158_i4@pure_quanta.q_res(chips)',
 P_PATH='@t6g_mb_lib.t6g(sch_1):page180_i4@pure_quanta.q_res(chips)',
 PATH='I4',
 DRAWING='@T6G_MB_LIB.T6G(SCH_1):PAGE158',
 WATTAGE='1/20W',
 TOLERANCE='5%',
 MATERIAL='CHIP',
 PHYS_PAGE='180',
 XY='(-7525,5600)',
 ROT='0',
 VER='1',
 PACK_TYPE='0201LF',
 LOCATION='R6193',
 CDS_LIB='pure_quanta',
 CDS_PART_NAME='Q_RES_0201LF-0,5%,1/20W,CHIP,CS00001JE10',
 ROOM='USB3_HUB2',
 PART_NUMBER='CS00001JE10',
 VALUE='0',
 PRIM_FILE='./archive_libs/logical/q_res/chips/chips.prt';

PART_NAME
 R6194 'Q_RES_0201LF-0,5%,1/20W,CHIP,CS00001JE10':
 ROOM='USB3_HUB1';

SECTION_NUMBER 1
 '@T6G_MB_LIB.T6G(SCH_1):PAGE158_I72@PURE_QUANTA.Q_RES(CHIPS)':
 C_PATH='@t6g_mb_lib.t6g(sch_1):page158_i72@pure_quanta.q_res(chips)',
 P_PATH='@t6g_mb_lib.t6g(sch_1):page180_i72@pure_quanta.q_res(chips)',
 PATH='I72',
 DRAWING='@T6G_MB_LIB.T6G(SCH_1):PAGE158',
 WATTAGE='1/20W',
 TOLERANCE='5%',
 MATERIAL='CHIP',
 PHYS_PAGE='180',
 XY='(-2975,6000)',
 ROT='0',
 VER='1',
 PACK_TYPE='0201LF',
 LOCATION='R6194',
 CDS_LIB='pure_quanta',
 CDS_PART_NAME='Q_RES_0201LF-0,5%,1/20W,CHIP,CS00001JE10',
 ROOM='USB3_HUB1',
 PART_NUMBER='CS00001JE10',
 VALUE='0',
 PRIM_FILE='./archive_libs/logical/q_res/chips/chips.prt';

PART_NAME
 R6195 'Q_RES_0201LF-0,5%,1/20W,CHIP,CS00001JE10':
 ROOM='USB3_HUB1';

SECTION_NUMBER 1
 '@T6G_MB_LIB.T6G(SCH_1):PAGE158_I71@PURE_QUANTA.Q_RES(CHIPS)':
 C_PATH='@t6g_mb_lib.t6g(sch_1):page158_i71@pure_quanta.q_res(chips)',
 P_PATH='@t6g_mb_lib.t6g(sch_1):page180_i71@pure_quanta.q_res(chips)',
 PATH='I71',
 DRAWING='@T6G_MB_LIB.T6G(SCH_1):PAGE158',
 WATTAGE='1/20W',
 TOLERANCE='5%',
 MATERIAL='CHIP',
 PHYS_PAGE='180',
 XY='(-2975,5950)',
 ROT='0',
 VER='1',
 PACK_TYPE='0201LF',
 LOCATION='R6195',
 CDS_LIB='pure_quanta',
 CDS_PART_NAME='Q_RES_0201LF-0,5%,1/20W,CHIP,CS00001JE10',
 ROOM='USB3_HUB1',
 PART_NUMBER='CS00001JE10',
 VALUE='0',
 PRIM_FILE='./archive_libs/logical/q_res/chips/chips.prt';

PART_NAME
 R6196 'Q_RES_0201LF-0,5%,1/20W,CHIP,CS00001JE10':
 ROOM='USB3_HUB2';

SECTION_NUMBER 1
 '@T6G_MB_LIB.T6G(SCH_1):PAGE158_I73@PURE_QUANTA.Q_RES(CHIPS)':
 C_PATH='@t6g_mb_lib.t6g(sch_1):page158_i73@pure_quanta.q_res(chips)',
 P_PATH='@t6g_mb_lib.t6g(sch_1):page180_i73@pure_quanta.q_res(chips)',
 PATH='I73',
 DRAWING='@T6G_MB_LIB.T6G(SCH_1):PAGE158',
 WATTAGE='1/20W',
 TOLERANCE='5%',
 MATERIAL='CHIP',
 PHYS_PAGE='180',
 XY='(-2950,5425)',
 ROT='0',
 VER='1',
 PACK_TYPE='0201LF',
 LOCATION='R6196',
 CDS_LIB='pure_quanta',
 CDS_PART_NAME='Q_RES_0201LF-0,5%,1/20W,CHIP,CS00001JE10',
 ROOM='USB3_HUB2',
 PART_NUMBER='CS00001JE10',
 VALUE='0',
 PRIM_FILE='./archive_libs/logical/q_res/chips/chips.prt';

PART_NAME
 R6197 'Q_RES_0201LF-0,5%,1/20W,CHIP,CS00001JE10':
 ROOM='USB3_HUB2';

SECTION_NUMBER 1
 '@T6G_MB_LIB.T6G(SCH_1):PAGE158_I74@PURE_QUANTA.Q_RES(CHIPS)':
 C_PATH='@t6g_mb_lib.t6g(sch_1):page158_i74@pure_quanta.q_res(chips)',
 P_PATH='@t6g_mb_lib.t6g(sch_1):page180_i74@pure_quanta.q_res(chips)',
 PATH='I74',
 DRAWING='@T6G_MB_LIB.T6G(SCH_1):PAGE158',
 WATTAGE='1/20W',
 TOLERANCE='5%',
 MATERIAL='CHIP',
 PHYS_PAGE='180',
 XY='(-2950,5375)',
 ROT='0',
 VER='1',
 PACK_TYPE='0201LF',
 LOCATION='R6197',
 CDS_LIB='pure_quanta',
 CDS_PART_NAME='Q_RES_0201LF-0,5%,1/20W,CHIP,CS00001JE10',
 ROOM='USB3_HUB2',
 PART_NUMBER='CS00001JE10',
 VALUE='0',
 PRIM_FILE='./archive_libs/logical/q_res/chips/chips.prt';

PART_NAME
 R6200 'Q_RES_0402LF-0,5%,1/16W,CHIP,CS00002JB13':;

SECTION_NUMBER 1
 '@T6G_MB_LIB.T6G(SCH_1):PAGE252_I83@PURE_QUANTA.Q_RES(CHIPS)':
 C_PATH='@t6g_mb_lib.t6g(sch_1):page252_i83@pure_quanta.q_res(chips)',
 P_PATH='@t6g_mb_lib.t6g(sch_1):page250_i83@pure_quanta.q_res(chips)',
 PATH='I83',
 DRAWING='@T6G_MB_LIB.T6G(SCH_1):PAGE252',
 WATTAGE='1/16W',
 TOLERANCE='5%',
 MATERIAL='CHIP',
 PHYS_PAGE='250',
 XY='(-5400,4575)',
 ROT='2',
 VER='1',
 PACK_TYPE='0402LF',
 LOCATION='R6200',
 CDS_LIB='pure_quanta',
 CDS_PART_NAME='Q_RES_0402LF-0,5%,1/16W,CHIP,CS00002JB13',
 PART_NUMBER='CS00002JB13',
 VALUE='0',
 PRIM_FILE='./archive_libs/logical/q_res/chips/chips.prt';

PART_NAME
 R6201 'Q_RES_0402LF-0,5%,1/16W,CHIP,CS00002JB13':;

SECTION_NUMBER 1
 '@T6G_MB_LIB.T6G(SCH_1):PAGE252_I84@PURE_QUANTA.Q_RES(CHIPS)':
 C_PATH='@t6g_mb_lib.t6g(sch_1):page252_i84@pure_quanta.q_res(chips)',
 P_PATH='@t6g_mb_lib.t6g(sch_1):page250_i84@pure_quanta.q_res(chips)',
 PATH='I84',
 DRAWING='@T6G_MB_LIB.T6G(SCH_1):PAGE252',
 WATTAGE='1/16W',
 TOLERANCE='5%',
 MATERIAL='CHIP',
 PHYS_PAGE='250',
 XY='(-5400,4525)',
 ROT='2',
 VER='1',
 PACK_TYPE='0402LF',
 LOCATION='R6201',
 CDS_LIB='pure_quanta',
 CDS_PART_NAME='Q_RES_0402LF-0,5%,1/16W,CHIP,CS00002JB13',
 PART_NUMBER='CS00002JB13',
 VALUE='0',
 PRIM_FILE='./archive_libs/logical/q_res/chips/chips.prt';

PART_NAME
 R6202 'Q_RES_0402LF-200,1%,1/16W,CHIP,CS12002FB06':
 ROOM='USB3_HUB1_CYP';

SECTION_NUMBER 1
 '@T6G_MB_LIB.T6G(SCH_1):PAGE153_I37@PURE_QUANTA.Q_RES(CHIPS)':
 C_PATH='@t6g_mb_lib.t6g(sch_1):page153_i37@pure_quanta.q_res(chips)',
 P_PATH='@t6g_mb_lib.t6g(sch_1):page176_i37@pure_quanta.q_res(chips)',
 PATH='I37',
 DRAWING='@T6G_MB_LIB.T6G(SCH_1):PAGE153',
 WATTAGE='1/16W',
 TOLERANCE='1%',
 MATERIAL='CHIP',
 PHYS_PAGE='176',
 XY='(-7000,4225)',
 ROT='0',
 VER='1',
 PACK_TYPE='0402LF',
 LOCATION='R6202',
 CDS_LIB='pure_quanta',
 CDS_PART_NAME='Q_RES_0402LF-200,1%,1/16W,CHIP,CS12002FB06',
 ROOM='USB3_HUB1_CYP',
 PART_NUMBER='CS12002FB06',
 VALUE='200',
 PRIM_FILE='./archive_libs/logical/q_res/chips/chips.prt';

PART_NAME
 R6203 'Q_RES_0402LF-6.04K,1%,1/16W,CHIP,CS26042FB04':
 ROOM='USB3_HUB1_CYP';

SECTION_NUMBER 1
 '@T6G_MB_LIB.T6G(SCH_1):PAGE153_I39@PURE_QUANTA.Q_RES(CHIPS)':
 C_PATH='@t6g_mb_lib.t6g(sch_1):page153_i39@pure_quanta.q_res(chips)',
 P_PATH='@t6g_mb_lib.t6g(sch_1):page176_i39@pure_quanta.q_res(chips)',
 PATH='I39',
 DRAWING='@T6G_MB_LIB.T6G(SCH_1):PAGE153',
 WATTAGE='1/16W',
 TOLERANCE='1%',
 MATERIAL='CHIP',
 PHYS_PAGE='176',
 XY='(-7025,4125)',
 ROT='0',
 VER='1',
 PACK_TYPE='0402LF',
 LOCATION='R6203',
 CDS_LIB='pure_quanta',
 CDS_PART_NAME='Q_RES_0402LF-6.04K,1%,1/16W,CHIP,CS26042FB04',
 ROOM='USB3_HUB1_CYP',
 PART_NUMBER='CS26042FB04',
 VALUE='6.04K',
 PRIM_FILE='./archive_libs/logical/q_res/chips/chips.prt';

PART_NAME
 R6204 'Q_RES_0402LF-10K,1%,1/16W,CHIP,CS31002FB08':
 ROOM='USB3_HUB1_CYP';

SECTION_NUMBER 1
 '@T6G_MB_LIB.T6G(SCH_1):PAGE153_I41@PURE_QUANTA.Q_RES(CHIPS)':
 C_PATH='@t6g_mb_lib.t6g(sch_1):page153_i41@pure_quanta.q_res(chips)',
 P_PATH='@t6g_mb_lib.t6g(sch_1):page176_i41@pure_quanta.q_res(chips)',
 PATH='I41',
 DRAWING='@T6G_MB_LIB.T6G(SCH_1):PAGE153',
 WATTAGE='1/16W',
 TOLERANCE='1%',
 MATERIAL='CHIP',
 PHYS_PAGE='176',
 XY='(-7175,3275)',
 ROT='0',
 VER='2',
 PACK_TYPE='0402LF',
 LOCATION='R6204',
 CDS_LIB='pure_quanta',
 CDS_PART_NAME='Q_RES_0402LF-10K,1%,1/16W,CHIP,CS31002FB08',
 ROOM='USB3_HUB1_CYP',
 PART_NUMBER='CS31002FB08',
 VALUE='10K',
 PRIM_FILE='./archive_libs/logical/q_res/chips/chips.prt';

PART_NAME
 R6205 'Q_RES_0402LF-10K,1%,1/16W,CHIP,CS31002FB08':
 ROOM='USB3_HUB1_CYP';

SECTION_NUMBER 1
 '@T6G_MB_LIB.T6G(SCH_1):PAGE153_I43@PURE_QUANTA.Q_RES(CHIPS)':
 C_PATH='@t6g_mb_lib.t6g(sch_1):page153_i43@pure_quanta.q_res(chips)',
 P_PATH='@t6g_mb_lib.t6g(sch_1):page176_i43@pure_quanta.q_res(chips)',
 PATH='I43',
 DRAWING='@T6G_MB_LIB.T6G(SCH_1):PAGE153',
 WATTAGE='1/16W',
 TOLERANCE='1%',
 MATERIAL='CHIP',
 PHYS_PAGE='176',
 XY='(-7475,3275)',
 ROT='0',
 VER='2',
 PACK_TYPE='0402LF',
 LOCATION='R6205',
 CDS_LIB='pure_quanta',
 CDS_PART_NAME='Q_RES_0402LF-10K,1%,1/16W,CHIP,CS31002FB08',
 ROOM='USB3_HUB1_CYP',
 PART_NUMBER='CS31002FB08',
 VALUE='10K',
 PRIM_FILE='./archive_libs/logical/q_res/chips/chips.prt';

PART_NAME
 R6206 'Q_RES_0402LF-10K,1%,1/16W,CHIP,CS31002FB08':
 ROOM='USB3_HUB1_CYP';

SECTION_NUMBER 1
 '@T6G_MB_LIB.T6G(SCH_1):PAGE153_I44@PURE_QUANTA.Q_RES(CHIPS)':
 C_PATH='@t6g_mb_lib.t6g(sch_1):page153_i44@pure_quanta.q_res(chips)',
 P_PATH='@t6g_mb_lib.t6g(sch_1):page176_i44@pure_quanta.q_res(chips)',
 PATH='I44',
 DRAWING='@T6G_MB_LIB.T6G(SCH_1):PAGE153',
 WATTAGE='1/16W',
 TOLERANCE='1%',
 MATERIAL='CHIP',
 PHYS_PAGE='176',
 XY='(-7775,3275)',
 ROT='0',
 VER='2',
 PACK_TYPE='0402LF',
 LOCATION='R6206',
 CDS_LIB='pure_quanta',
 CDS_PART_NAME='Q_RES_0402LF-10K,1%,1/16W,CHIP,CS31002FB08',
 ROOM='USB3_HUB1_CYP',
 PART_NUMBER='CS31002FB08',
 VALUE='10K',
 PRIM_FILE='./archive_libs/logical/q_res/chips/chips.prt';

PART_NAME
 R6207 'Q_RES_0402LF-10K,1%,1/16W,CHIP,CS31002FB08':
 ROOM='USB3_HUB1_CYP';

SECTION_NUMBER 1
 '@T6G_MB_LIB.T6G(SCH_1):PAGE153_I45@PURE_QUANTA.Q_RES(CHIPS)':
 C_PATH='@t6g_mb_lib.t6g(sch_1):page153_i45@pure_quanta.q_res(chips)',
 P_PATH='@t6g_mb_lib.t6g(sch_1):page176_i45@pure_quanta.q_res(chips)',
 PATH='I45',
 DRAWING='@T6G_MB_LIB.T6G(SCH_1):PAGE153',
 WATTAGE='1/16W',
 TOLERANCE='1%',
 MATERIAL='CHIP',
 PHYS_PAGE='176',
 XY='(-8100,3275)',
 ROT='0',
 VER='2',
 PACK_TYPE='0402LF',
 LOCATION='R6207',
 CDS_LIB='pure_quanta',
 CDS_PART_NAME='Q_RES_0402LF-10K,1%,1/16W,CHIP,CS31002FB08',
 ROOM='USB3_HUB1_CYP',
 PART_NUMBER='CS31002FB08',
 VALUE='10K',
 PRIM_FILE='./archive_libs/logical/q_res/chips/chips.prt';

PART_NAME
 R6208 'Q_RES_0402LF-10K,1%,1/16W,CHIP,CS31002FB08':
 ROOM='USB3_HUB1_CYP';

SECTION_NUMBER 1
 '@T6G_MB_LIB.T6G(SCH_1):PAGE153_I47@PURE_QUANTA.Q_RES(CHIPS)':
 C_PATH='@t6g_mb_lib.t6g(sch_1):page153_i47@pure_quanta.q_res(chips)',
 P_PATH='@t6g_mb_lib.t6g(sch_1):page176_i47@pure_quanta.q_res(chips)',
 PATH='I47',
 DRAWING='@T6G_MB_LIB.T6G(SCH_1):PAGE153',
 WATTAGE='1/16W',
 TOLERANCE='1%',
 MATERIAL='CHIP',
 PHYS_PAGE='176',
 XY='(-7025,6300)',
 ROT='0',
 VER='2',
 PACK_TYPE='0402LF',
 LOCATION='R6208',
 CDS_LIB='pure_quanta',
 CDS_PART_NAME='Q_RES_0402LF-10K,1%,1/16W,CHIP,CS31002FB08',
 ROOM='USB3_HUB1_CYP',
 PART_NUMBER='CS31002FB08',
 VALUE='10K',
 PRIM_FILE='./archive_libs/logical/q_res/chips/chips.prt';

PART_NAME
 R6209 'Q_RES_0402LF-10K,1%,1/16W,CHIP,CS31002FB08':
 ROOM='USB3_HUB1_CYP';

SECTION_NUMBER 1
 '@T6G_MB_LIB.T6G(SCH_1):PAGE153_I48@PURE_QUANTA.Q_RES(CHIPS)':
 C_PATH='@t6g_mb_lib.t6g(sch_1):page153_i48@pure_quanta.q_res(chips)',
 P_PATH='@t6g_mb_lib.t6g(sch_1):page176_i48@pure_quanta.q_res(chips)',
 PATH='I48',
 DRAWING='@T6G_MB_LIB.T6G(SCH_1):PAGE153',
 WATTAGE='1/16W',
 TOLERANCE='1%',
 MATERIAL='CHIP',
 PHYS_PAGE='176',
 XY='(-7025,5800)',
 ROT='0',
 VER='2',
 PACK_TYPE='0402LF',
 LOCATION='R6209',
 CDS_LIB='pure_quanta',
 CDS_PART_NAME='Q_RES_0402LF-10K,1%,1/16W,CHIP,CS31002FB08',
 ROOM='USB3_HUB1_CYP',
 PART_NUMBER='CS31002FB08',
 VALUE='10K',
 PRIM_FILE='./archive_libs/logical/q_res/chips/chips.prt';

PART_NAME
 R6210 'Q_RES_0402LF-0,5%,1/16W,CHIP,CS00002JB13':
 ROOM='HSC BOM2';

SECTION_NUMBER 1
 '@T6G_MB_LIB.T6G(SCH_1):PAGE371_I73@PURE_QUANTA.Q_RES(CHIPS)':
 C_PATH='@t6g_mb_lib.t6g(sch_1):page371_i73@pure_quanta.q_res(chips)',
 P_PATH='@t6g_mb_lib.t6g(sch_1):page267_i73@pure_quanta.q_res(chips)',
 PATH='I73',
 DRAWING='@T6G_MB_LIB.T6G(SCH_1):PAGE371',
 WATTAGE='1/16W',
 TOLERANCE='5%',
 MATERIAL='CHIP',
 PHYS_PAGE='267',
 XY='(-5275,4925)',
 ROT='0',
 VER='1',
 PACK_TYPE='0402LF',
 LOCATION='R6210',
 CDS_LIB='pure_quanta',
 CDS_PART_NAME='Q_RES_0402LF-0,5%,1/16W,CHIP,CS00002JB13',
 ROOM='HSC BOM2',
 PART_NUMBER='CS00002JB13',
 VALUE='0',
 PRIM_FILE='./archive_libs/logical/q_res/chips/chips.prt';

PART_NAME
 R6211 'Q_RES_0402LF-2.2K,5%,1/16W,CHIP,CS22202JB07':;

SECTION_NUMBER 1
 '@T6G_MB_LIB.T6G(SCH_1):PAGE252_I89@PURE_QUANTA.Q_RES(CHIPS)':
 C_PATH='@t6g_mb_lib.t6g(sch_1):page252_i89@pure_quanta.q_res(chips)',
 P_PATH='@t6g_mb_lib.t6g(sch_1):page250_i89@pure_quanta.q_res(chips)',
 PATH='I89',
 DRAWING='@T6G_MB_LIB.T6G(SCH_1):PAGE252',
 WATTAGE='1/16W',
 TOLERANCE='5%',
 MATERIAL='CHIP',
 PHYS_PAGE='250',
 XY='(-2125,1600)',
 ROT='0',
 VER='1',
 PACK_TYPE='0402LF',
 LOCATION='R6211',
 CDS_LIB='pure_quanta',
 CDS_PART_NAME='Q_RES_0402LF-2.2K,5%,1/16W,CHIP,CS22202JB07',
 PART_NUMBER='CS22202JB07',
 VALUE='2.2K',
 PRIM_FILE='./archive_libs/logical/q_res/chips/chips.prt';

PART_NAME
 R6212 'Q_RES_0402LF-2.2K,5%,1/16W,CHIP,CS22202JB07':;

SECTION_NUMBER 1
 '@T6G_MB_LIB.T6G(SCH_1):PAGE252_I90@PURE_QUANTA.Q_RES(CHIPS)':
 C_PATH='@t6g_mb_lib.t6g(sch_1):page252_i90@pure_quanta.q_res(chips)',
 P_PATH='@t6g_mb_lib.t6g(sch_1):page250_i90@pure_quanta.q_res(chips)',
 PATH='I90',
 DRAWING='@T6G_MB_LIB.T6G(SCH_1):PAGE252',
 WATTAGE='1/16W',
 TOLERANCE='5%',
 MATERIAL='CHIP',
 PHYS_PAGE='250',
 XY='(-2125,1550)',
 ROT='0',
 VER='1',
 PACK_TYPE='0402LF',
 LOCATION='R6212',
 CDS_LIB='pure_quanta',
 CDS_PART_NAME='Q_RES_0402LF-2.2K,5%,1/16W,CHIP,CS22202JB07',
 PART_NUMBER='CS22202JB07',
 VALUE='2.2K',
 PRIM_FILE='./archive_libs/logical/q_res/chips/chips.prt';

PART_NAME
 R6213 'Q_RES_0402LF-10K,1%,1/16W,CHIP,CS31002FB08':
 ROOM='USB3_HUB1_CYP';

SECTION_NUMBER 1
 '@T6G_MB_LIB.T6G(SCH_1):PAGE153_I87@PURE_QUANTA.Q_RES(CHIPS)':
 C_PATH='@t6g_mb_lib.t6g(sch_1):page153_i87@pure_quanta.q_res(chips)',
 P_PATH='@t6g_mb_lib.t6g(sch_1):page176_i87@pure_quanta.q_res(chips)',
 PATH='I87',
 DRAWING='@T6G_MB_LIB.T6G(SCH_1):PAGE153',
 WATTAGE='1/16W',
 TOLERANCE='1%',
 MATERIAL='CHIP',
 PHYS_PAGE='176',
 XY='(-3300,1125)',
 ROT='0',
 VER='2',
 PACK_TYPE='0402LF',
 LOCATION='R6213',
 CDS_LIB='pure_quanta',
 CDS_PART_NAME='Q_RES_0402LF-10K,1%,1/16W,CHIP,CS31002FB08',
 ROOM='USB3_HUB1_CYP',
 PART_NUMBER='CS31002FB08',
 VALUE='10K',
 PRIM_FILE='./archive_libs/logical/q_res/chips/chips.prt';

PART_NAME
 R6214 'Q_RES_0402LF-10K,1%,1/16W,EMPTY,CS31002FB08':
 ROOM='USB3_HUB1_CYP';

SECTION_NUMBER 1
 '@T6G_MB_LIB.T6G(SCH_1):PAGE153_I88@PURE_QUANTA.Q_RES(CHIPS)':
 C_PATH='@t6g_mb_lib.t6g(sch_1):page153_i88@pure_quanta.q_res(chips)',
 P_PATH='@t6g_mb_lib.t6g(sch_1):page176_i88@pure_quanta.q_res(chips)',
 PATH='I88',
 DRAWING='@T6G_MB_LIB.T6G(SCH_1):PAGE153',
 WATTAGE='1/16W',
 TOLERANCE='1%',
 MATERIAL='EMPTY',
 PHYS_PAGE='176',
 XY='(-3300,750)',
 ROT='0',
 VER='2',
 PACK_TYPE='0402LF',
 LOCATION='R6214',
 CDS_LIB='pure_quanta',
 CDS_PART_NAME='Q_RES_0402LF-10K,1%,1/16W,EMPTY,CS31002FB08',
 ROOM='USB3_HUB1_CYP',
 PART_NUMBER='CS31002FB08',
 VALUE='10K',
 PRIM_FILE='./archive_libs/logical/q_res/chips/chips.prt';

PART_NAME
 R6215 'Q_RES_0402LF-10K,1%,1/16W,CHIP,CS31002FB08':
 ROOM='USB3_HUB1_CYP';

SECTION_NUMBER 1
 '@T6G_MB_LIB.T6G(SCH_1):PAGE153_I89@PURE_QUANTA.Q_RES(CHIPS)':
 C_PATH='@t6g_mb_lib.t6g(sch_1):page153_i89@pure_quanta.q_res(chips)',
 P_PATH='@t6g_mb_lib.t6g(sch_1):page176_i89@pure_quanta.q_res(chips)',
 PATH='I89',
 DRAWING='@T6G_MB_LIB.T6G(SCH_1):PAGE153',
 WATTAGE='1/16W',
 TOLERANCE='1%',
 MATERIAL='CHIP',
 PHYS_PAGE='176',
 XY='(-2850,1125)',
 ROT='0',
 VER='2',
 PACK_TYPE='0402LF',
 LOCATION='R6215',
 CDS_LIB='pure_quanta',
 CDS_PART_NAME='Q_RES_0402LF-10K,1%,1/16W,CHIP,CS31002FB08',
 ROOM='USB3_HUB1_CYP',
 PART_NUMBER='CS31002FB08',
 VALUE='10K',
 PRIM_FILE='./archive_libs/logical/q_res/chips/chips.prt';

PART_NAME
 R6216 'Q_RES_0402LF-10K,1%,1/16W,EMPTY,CS31002FB08':
 ROOM='USB3_HUB1_CYP';

SECTION_NUMBER 1
 '@T6G_MB_LIB.T6G(SCH_1):PAGE153_I90@PURE_QUANTA.Q_RES(CHIPS)':
 C_PATH='@t6g_mb_lib.t6g(sch_1):page153_i90@pure_quanta.q_res(chips)',
 P_PATH='@t6g_mb_lib.t6g(sch_1):page176_i90@pure_quanta.q_res(chips)',
 PATH='I90',
 DRAWING='@T6G_MB_LIB.T6G(SCH_1):PAGE153',
 WATTAGE='1/16W',
 TOLERANCE='1%',
 MATERIAL='EMPTY',
 PHYS_PAGE='176',
 XY='(-2850,725)',
 ROT='0',
 VER='2',
 PACK_TYPE='0402LF',
 LOCATION='R6216',
 CDS_LIB='pure_quanta',
 CDS_PART_NAME='Q_RES_0402LF-10K,1%,1/16W,EMPTY,CS31002FB08',
 ROOM='USB3_HUB1_CYP',
 PART_NUMBER='CS31002FB08',
 VALUE='10K',
 PRIM_FILE='./archive_libs/logical/q_res/chips/chips.prt';

PART_NAME
 R6217 'Q_RES_0402LF-10K,1%,1/16W,EMPTY,CS31002FB08':
 ROOM='USB3_HUB1_CYP';

SECTION_NUMBER 1
 '@T6G_MB_LIB.T6G(SCH_1):PAGE153_I68@PURE_QUANTA.Q_RES(CHIPS)':
 C_PATH='@t6g_mb_lib.t6g(sch_1):page153_i68@pure_quanta.q_res(chips)',
 P_PATH='@t6g_mb_lib.t6g(sch_1):page176_i68@pure_quanta.q_res(chips)',
 PATH='I68',
 DRAWING='@T6G_MB_LIB.T6G(SCH_1):PAGE153',
 WATTAGE='1/16W',
 TOLERANCE='1%',
 MATERIAL='EMPTY',
 PHYS_PAGE='176',
 XY='(-1050,2400)',
 ROT='2',
 VER='2',
 PACK_TYPE='0402LF',
 LOCATION='R6217',
 CDS_LIB='pure_quanta',
 CDS_PART_NAME='Q_RES_0402LF-10K,1%,1/16W,EMPTY,CS31002FB08',
 ROOM='USB3_HUB1_CYP',
 PART_NUMBER='CS31002FB08',
 VALUE='10K',
 PRIM_FILE='./archive_libs/logical/q_res/chips/chips.prt';

PART_NAME
 R6218 'Q_RES_0402LF-10K,1%,1/16W,EMPTY,CS31002FB08':
 ROOM='USB3_HUB1_CYP';

SECTION_NUMBER 1
 '@T6G_MB_LIB.T6G(SCH_1):PAGE153_I69@PURE_QUANTA.Q_RES(CHIPS)':
 C_PATH='@t6g_mb_lib.t6g(sch_1):page153_i69@pure_quanta.q_res(chips)',
 P_PATH='@t6g_mb_lib.t6g(sch_1):page176_i69@pure_quanta.q_res(chips)',
 PATH='I69',
 DRAWING='@T6G_MB_LIB.T6G(SCH_1):PAGE153',
 WATTAGE='1/16W',
 TOLERANCE='1%',
 MATERIAL='EMPTY',
 PHYS_PAGE='176',
 XY='(-850,3200)',
 ROT='0',
 VER='2',
 PACK_TYPE='0402LF',
 LOCATION='R6218',
 CDS_LIB='pure_quanta',
 CDS_PART_NAME='Q_RES_0402LF-10K,1%,1/16W,EMPTY,CS31002FB08',
 ROOM='USB3_HUB1_CYP',
 PART_NUMBER='CS31002FB08',
 VALUE='10K',
 PRIM_FILE='./archive_libs/logical/q_res/chips/chips.prt';

PART_NAME
 R6219 'Q_RES_0402LF-10K,1%,1/16W,CHIP,CS31002FB08':
 ROOM='USB3_HUB1_CYP';

SECTION_NUMBER 1
 '@T6G_MB_LIB.T6G(SCH_1):PAGE153_I66@PURE_QUANTA.Q_RES(CHIPS)':
 C_PATH='@t6g_mb_lib.t6g(sch_1):page153_i66@pure_quanta.q_res(chips)',
 P_PATH='@t6g_mb_lib.t6g(sch_1):page176_i66@pure_quanta.q_res(chips)',
 PATH='I66',
 DRAWING='@T6G_MB_LIB.T6G(SCH_1):PAGE153',
 WATTAGE='1/16W',
 TOLERANCE='1%',
 MATERIAL='CHIP',
 PHYS_PAGE='176',
 XY='(-850,2375)',
 ROT='0',
 VER='2',
 PACK_TYPE='0402LF',
 LOCATION='R6219',
 CDS_LIB='pure_quanta',
 CDS_PART_NAME='Q_RES_0402LF-10K,1%,1/16W,CHIP,CS31002FB08',
 ROOM='USB3_HUB1_CYP',
 PART_NUMBER='CS31002FB08',
 VALUE='10K',
 PRIM_FILE='./archive_libs/logical/q_res/chips/chips.prt';

PART_NAME
 R6220 'Q_RES_0402LF-10K,1%,1/16W,EMPTY,CS31002FB08':
 ROOM='USB3_HUB1_CYP';

SECTION_NUMBER 1
 '@T6G_MB_LIB.T6G(SCH_1):PAGE153_I70@PURE_QUANTA.Q_RES(CHIPS)':
 C_PATH='@t6g_mb_lib.t6g(sch_1):page153_i70@pure_quanta.q_res(chips)',
 P_PATH='@t6g_mb_lib.t6g(sch_1):page176_i70@pure_quanta.q_res(chips)',
 PATH='I70',
 DRAWING='@T6G_MB_LIB.T6G(SCH_1):PAGE153',
 WATTAGE='1/16W',
 TOLERANCE='1%',
 MATERIAL='EMPTY',
 PHYS_PAGE='176',
 XY='(-450,3200)',
 ROT='0',
 VER='2',
 PACK_TYPE='0402LF',
 LOCATION='R6220',
 CDS_LIB='pure_quanta',
 CDS_PART_NAME='Q_RES_0402LF-10K,1%,1/16W,EMPTY,CS31002FB08',
 ROOM='USB3_HUB1_CYP',
 PART_NUMBER='CS31002FB08',
 VALUE='10K',
 PRIM_FILE='./archive_libs/logical/q_res/chips/chips.prt';

PART_NAME
 R6221 'Q_RES_0402LF-10K,1%,1/16W,CHIP,CS31002FB08':
 ROOM='USB3_HUB1_CYP';

SECTION_NUMBER 1
 '@T6G_MB_LIB.T6G(SCH_1):PAGE153_I67@PURE_QUANTA.Q_RES(CHIPS)':
 C_PATH='@t6g_mb_lib.t6g(sch_1):page153_i67@pure_quanta.q_res(chips)',
 P_PATH='@t6g_mb_lib.t6g(sch_1):page176_i67@pure_quanta.q_res(chips)',
 PATH='I67',
 DRAWING='@T6G_MB_LIB.T6G(SCH_1):PAGE153',
 WATTAGE='1/16W',
 TOLERANCE='1%',
 MATERIAL='CHIP',
 PHYS_PAGE='176',
 XY='(-450,2375)',
 ROT='0',
 VER='2',
 PACK_TYPE='0402LF',
 LOCATION='R6221',
 CDS_LIB='pure_quanta',
 CDS_PART_NAME='Q_RES_0402LF-10K,1%,1/16W,CHIP,CS31002FB08',
 ROOM='USB3_HUB1_CYP',
 PART_NUMBER='CS31002FB08',
 VALUE='10K',
 PRIM_FILE='./archive_libs/logical/q_res/chips/chips.prt';

PART_NAME
 R6222 'Q_RES_0402LF-10K,1%,1/16W,CHIP,CS31002FB08':
 ROOM='USB3_HUB1_CYP';

SECTION_NUMBER 1
 '@T6G_MB_LIB.T6G(SCH_1):PAGE153_I65@PURE_QUANTA.Q_RES(CHIPS)':
 C_PATH='@t6g_mb_lib.t6g(sch_1):page153_i65@pure_quanta.q_res(chips)',
 P_PATH='@t6g_mb_lib.t6g(sch_1):page176_i65@pure_quanta.q_res(chips)',
 PATH='I65',
 DRAWING='@T6G_MB_LIB.T6G(SCH_1):PAGE153',
 WATTAGE='1/16W',
 TOLERANCE='1%',
 MATERIAL='CHIP',
 PHYS_PAGE='176',
 XY='(-1050,3225)',
 ROT='2',
 VER='2',
 PACK_TYPE='0402LF',
 LOCATION='R6222',
 CDS_LIB='pure_quanta',
 CDS_PART_NAME='Q_RES_0402LF-10K,1%,1/16W,CHIP,CS31002FB08',
 ROOM='USB3_HUB1_CYP',
 PART_NUMBER='CS31002FB08',
 VALUE='10K',
 PRIM_FILE='./archive_libs/logical/q_res/chips/chips.prt';

PART_NAME
 R6223 'Q_RES_0402LF-1K,1%,1/16W,CHIP,CS21002FB06':
 ROOM='USB3_HUB1_CYP',
 REUSE_ID='3';

SECTION_NUMBER 1
 '@T6G_MB_LIB.T6G(SCH_1):PAGE153_I77@PURE_QUANTA.Q_RES(CHIPS)':
 C_PATH='@t6g_mb_lib.t6g(sch_1):page153_i77@pure_quanta.q_res(chips)',
 P_PATH='@t6g_mb_lib.t6g(sch_1):page176_i77@pure_quanta.q_res(chips)',
 PATH='I77',
 DRAWING='@T6G_MB_LIB.T6G(SCH_1):PAGE153',
 BOM_COST='VR_SYSTEM ',
 WATTAGE='1/16W',
 TOLERANCE='1%',
 MATERIAL='CHIP',
 PHYS_PAGE='176',
 XY='(-2700,2425)',
 ROT='2',
 VER='2',
 PACK_TYPE='0402LF',
 LOCATION='R6223',
 CDS_LIB='pure_quanta',
 CDS_PART_NAME='Q_RES_0402LF-1K,1%,1/16W,CHIP,CS21002FB06',
 REUSE_ID='3',
 ROOM='USB3_HUB1_CYP',
 PART_NUMBER='CS21002FB06',
 VALUE='1K',
 PRIM_FILE='./archive_libs/logical/q_res/chips/chips.prt';

PART_NAME
 R6224 'Q_RES_0402LF-33.2,1%,1/16W,EMPTY,CS03322FB03':
 ROOM='USB3_HUB1_CYP';

SECTION_NUMBER 1
 '@T6G_MB_LIB.T6G(SCH_1):PAGE153_I84@PURE_QUANTA.Q_RES(CHIPS)':
 C_PATH='@t6g_mb_lib.t6g(sch_1):page153_i84@pure_quanta.q_res(chips)',
 P_PATH='@t6g_mb_lib.t6g(sch_1):page176_i84@pure_quanta.q_res(chips)',
 PATH='I84',
 DRAWING='@T6G_MB_LIB.T6G(SCH_1):PAGE153',
 WATTAGE='1/16W',
 TOLERANCE='1%',
 MATERIAL='EMPTY',
 PHYS_PAGE='176',
 XY='(-3200,2800)',
 ROT='0',
 VER='1',
 PACK_TYPE='0402LF',
 LOCATION='R6224',
 CDS_LIB='pure_quanta',
 CDS_PART_NAME='Q_RES_0402LF-33.2,1%,1/16W,EMPTY,CS03322FB03',
 ROOM='USB3_HUB1_CYP',
 PART_NUMBER='CS03322FB03',
 VALUE='33.2',
 PRIM_FILE='./archive_libs/logical/q_res/chips/chips.prt';

PART_NAME
 R6225 'Q_RES_0402LF-33.2,1%,1/16W,EMPTY,CS03322FB03':
 ROOM='USB3_HUB1_CYP';

SECTION_NUMBER 1
 '@T6G_MB_LIB.T6G(SCH_1):PAGE153_I83@PURE_QUANTA.Q_RES(CHIPS)':
 C_PATH='@t6g_mb_lib.t6g(sch_1):page153_i83@pure_quanta.q_res(chips)',
 P_PATH='@t6g_mb_lib.t6g(sch_1):page176_i83@pure_quanta.q_res(chips)',
 PATH='I83',
 DRAWING='@T6G_MB_LIB.T6G(SCH_1):PAGE153',
 WATTAGE='1/16W',
 TOLERANCE='1%',
 MATERIAL='EMPTY',
 PHYS_PAGE='176',
 XY='(-3200,2750)',
 ROT='0',
 VER='1',
 PACK_TYPE='0402LF',
 LOCATION='R6225',
 CDS_LIB='pure_quanta',
 CDS_PART_NAME='Q_RES_0402LF-33.2,1%,1/16W,EMPTY,CS03322FB03',
 ROOM='USB3_HUB1_CYP',
 PART_NUMBER='CS03322FB03',
 VALUE='33.2',
 PRIM_FILE='./archive_libs/logical/q_res/chips/chips.prt';

PART_NAME
 R6226 'Q_RES_0402LF-10K,1%,1/16W,EMPTY,CS31002FB08':
 ROOM='USB3_HUB1_CYP';

SECTION_NUMBER 1
 '@T6G_MB_LIB.T6G(SCH_1):PAGE153_I85@PURE_QUANTA.Q_RES(CHIPS)':
 C_PATH='@t6g_mb_lib.t6g(sch_1):page153_i85@pure_quanta.q_res(chips)',
 P_PATH='@t6g_mb_lib.t6g(sch_1):page176_i85@pure_quanta.q_res(chips)',
 PATH='I85',
 DRAWING='@T6G_MB_LIB.T6G(SCH_1):PAGE153',
 SEC_TYPE='0402LF',
 WATTAGE='1/16W',
 TOLERANCE='1%',
 MATERIAL='EMPTY',
 PHYS_PAGE='176',
 XY='(-2900,3300)',
 ROT='0',
 VER='2',
 PACK_TYPE='0402LF',
 LOCATION='R6226',
 SEC='1',
 CDS_LIB='pure_quanta',
 CDS_PART_NAME='Q_RES_0402LF-10K,1%,1/16W,EMPTY,CS31002FB08',
 ROOM='USB3_HUB1_CYP',
 PART_NUMBER='CS31002FB08',
 VALUE='10K',
 PRIM_FILE='./archive_libs/logical/q_res/chips/chips.prt';

PART_NAME
 R6227 'Q_RES_0402LF-10K,1%,1/16W,EMPTY,CS31002FB08':
 ROOM='USB3_HUB1_CYP';

SECTION_NUMBER 1
 '@T6G_MB_LIB.T6G(SCH_1):PAGE153_I86@PURE_QUANTA.Q_RES(CHIPS)':
 C_PATH='@t6g_mb_lib.t6g(sch_1):page153_i86@pure_quanta.q_res(chips)',
 P_PATH='@t6g_mb_lib.t6g(sch_1):page176_i86@pure_quanta.q_res(chips)',
 PATH='I86',
 DRAWING='@T6G_MB_LIB.T6G(SCH_1):PAGE153',
 SEC_TYPE='0402LF',
 WATTAGE='1/16W',
 TOLERANCE='1%',
 MATERIAL='EMPTY',
 PHYS_PAGE='176',
 XY='(-2975,3300)',
 ROT='2',
 VER='2',
 PACK_TYPE='0402LF',
 LOCATION='R6227',
 SEC='1',
 CDS_LIB='pure_quanta',
 CDS_PART_NAME='Q_RES_0402LF-10K,1%,1/16W,EMPTY,CS31002FB08',
 ROOM='USB3_HUB1_CYP',
 PART_NUMBER='CS31002FB08',
 VALUE='10K',
 PRIM_FILE='./archive_libs/logical/q_res/chips/chips.prt';

PART_NAME
 R6228 'Q_RES_0402LF-0,5%,1/16W,CHIP,CS00002JB13':;

SECTION_NUMBER 1
 '@T6G_MB_LIB.T6G(SCH_1):PAGE251_I75@PURE_QUANTA.Q_RES(CHIPS)':
 C_PATH='@t6g_mb_lib.t6g(sch_1):page251_i75@pure_quanta.q_res(chips)',
 P_PATH='@t6g_mb_lib.t6g(sch_1):page252_i75@pure_quanta.q_res(chips)',
 PATH='I75',
 DRAWING='@T6G_MB_LIB.T6G(SCH_1):PAGE251',
 WATTAGE='1/16W',
 TOLERANCE='5%',
 MATERIAL='CHIP',
 PHYS_PAGE='252',
 XY='(-2950,4200)',
 ROT='0',
 VER='1',
 PACK_TYPE='0402LF',
 LOCATION='R6228',
 CDS_LIB='pure_quanta',
 CDS_PART_NAME='Q_RES_0402LF-0,5%,1/16W,CHIP,CS00002JB13',
 PART_NUMBER='CS00002JB13',
 VALUE='0',
 PRIM_FILE='./archive_libs/logical/q_res/chips/chips.prt';

PART_NAME
 R6229 'Q_RES_0402LF-0,5%,1/16W,CHIP,CS00002JB13':;

SECTION_NUMBER 1
 '@T6G_MB_LIB.T6G(SCH_1):PAGE251_I76@PURE_QUANTA.Q_RES(CHIPS)':
 C_PATH='@t6g_mb_lib.t6g(sch_1):page251_i76@pure_quanta.q_res(chips)',
 P_PATH='@t6g_mb_lib.t6g(sch_1):page252_i76@pure_quanta.q_res(chips)',
 PATH='I76',
 DRAWING='@T6G_MB_LIB.T6G(SCH_1):PAGE251',
 WATTAGE='1/16W',
 TOLERANCE='5%',
 MATERIAL='CHIP',
 PHYS_PAGE='252',
 XY='(-2950,4150)',
 ROT='0',
 VER='1',
 PACK_TYPE='0402LF',
 LOCATION='R6229',
 CDS_LIB='pure_quanta',
 CDS_PART_NAME='Q_RES_0402LF-0,5%,1/16W,CHIP,CS00002JB13',
 PART_NUMBER='CS00002JB13',
 VALUE='0',
 PRIM_FILE='./archive_libs/logical/q_res/chips/chips.prt';

PART_NAME
 R6230 'Q_RES_0402LF-2.2K,5%,1/16W,CHIP,CS22202JB07':
 ROOM='HSC BOM2';

SECTION_NUMBER 1
 '@T6G_MB_LIB.T6G(SCH_1):PAGE371_I45@PURE_QUANTA.Q_RES(CHIPS)':
 C_PATH='@t6g_mb_lib.t6g(sch_1):page371_i45@pure_quanta.q_res(chips)',
 P_PATH='@t6g_mb_lib.t6g(sch_1):page267_i45@pure_quanta.q_res(chips)',
 PATH='I45',
 DRAWING='@T6G_MB_LIB.T6G(SCH_1):PAGE371',
 WATTAGE='1/16W',
 TOLERANCE='5%',
 MATERIAL='CHIP',
 PHYS_PAGE='267',
 XY='(-1450,2825)',
 ROT='2',
 VER='2',
 PACK_TYPE='0402LF',
 LOCATION='R6230',
 CDS_LIB='pure_quanta',
 CDS_PART_NAME='Q_RES_0402LF-2.2K,5%,1/16W,CHIP,CS22202JB07',
 ROOM='HSC BOM2',
 PART_NUMBER='CS22202JB07',
 VALUE='2.2K',
 PRIM_FILE='./archive_libs/logical/q_res/chips/chips.prt';

PART_NAME
 R6231 'Q_RES_0402LF-2.2K,5%,1/16W,CHIP,CS22202JB07':
 ROOM='HSC BOM2';

SECTION_NUMBER 1
 '@T6G_MB_LIB.T6G(SCH_1):PAGE371_I46@PURE_QUANTA.Q_RES(CHIPS)':
 C_PATH='@t6g_mb_lib.t6g(sch_1):page371_i46@pure_quanta.q_res(chips)',
 P_PATH='@t6g_mb_lib.t6g(sch_1):page267_i46@pure_quanta.q_res(chips)',
 PATH='I46',
 DRAWING='@T6G_MB_LIB.T6G(SCH_1):PAGE371',
 WATTAGE='1/16W',
 TOLERANCE='5%',
 MATERIAL='CHIP',
 PHYS_PAGE='267',
 XY='(-1325,2850)',
 ROT='0',
 VER='2',
 PACK_TYPE='0402LF',
 LOCATION='R6231',
 CDS_LIB='pure_quanta',
 CDS_PART_NAME='Q_RES_0402LF-2.2K,5%,1/16W,CHIP,CS22202JB07',
 ROOM='HSC BOM2',
 PART_NUMBER='CS22202JB07',
 VALUE='2.2K',
 PRIM_FILE='./archive_libs/logical/q_res/chips/chips.prt';

PART_NAME
 R6232 'Q_RES_0402LF-160K,1%,1/16W,EMPTY,CS41602FB05':
 ROOM='HSC BOM2';

SECTION_NUMBER 1
 '@T6G_MB_LIB.T6G(SCH_1):PAGE371_I56@PURE_QUANTA.Q_RES(CHIPS)':
 C_PATH='@t6g_mb_lib.t6g(sch_1):page371_i56@pure_quanta.q_res(chips)',
 P_PATH='@t6g_mb_lib.t6g(sch_1):page267_i56@pure_quanta.q_res(chips)',
 PATH='I56',
 DRAWING='@T6G_MB_LIB.T6G(SCH_1):PAGE371',
 WATTAGE='1/16W',
 TOLERANCE='1%',
 MATERIAL='EMPTY',
 PHYS_PAGE='267',
 XY='(-7775,6200)',
 ROT='0',
 VER='2',
 PACK_TYPE='0402LF',
 LOCATION='R6232',
 CDS_LIB='pure_quanta',
 CDS_PART_NAME='Q_RES_0402LF-160K,1%,1/16W,EMPTY,CS41602FB05',
 ROOM='HSC BOM2',
 PART_NUMBER='CS41602FB05',
 VALUE='160K',
 PRIM_FILE='./archive_libs/logical/q_res/chips/chips.prt';

PART_NAME
 R6233 'Q_RES_0402LF-10K,1%,1/16W,EMPTY,CS31002FB08':
 ROOM='HSC BOM2';

SECTION_NUMBER 1
 '@T6G_MB_LIB.T6G(SCH_1):PAGE371_I57@PURE_QUANTA.Q_RES(CHIPS)':
 C_PATH='@t6g_mb_lib.t6g(sch_1):page371_i57@pure_quanta.q_res(chips)',
 P_PATH='@t6g_mb_lib.t6g(sch_1):page267_i57@pure_quanta.q_res(chips)',
 PATH='I57',
 DRAWING='@T6G_MB_LIB.T6G(SCH_1):PAGE371',
 WATTAGE='1/16W',
 TOLERANCE='1%',
 MATERIAL='EMPTY',
 PHYS_PAGE='267',
 XY='(-7775,5475)',
 ROT='0',
 VER='2',
 PACK_TYPE='0402LF',
 LOCATION='R6233',
 CDS_LIB='pure_quanta',
 CDS_PART_NAME='Q_RES_0402LF-10K,1%,1/16W,EMPTY,CS31002FB08',
 ROOM='HSC BOM2',
 PART_NUMBER='CS31002FB08',
 VALUE='10K',
 PRIM_FILE='./archive_libs/logical/q_res/chips/chips.prt';

PART_NAME
 R6234 'Q_RES_0402LF-160K,1%,1/16W,EMPTY,CS41602FB05':
 ROOM='HSC BOM2';

SECTION_NUMBER 1
 '@T6G_MB_LIB.T6G(SCH_1):PAGE371_I55@PURE_QUANTA.Q_RES(CHIPS)':
 C_PATH='@t6g_mb_lib.t6g(sch_1):page371_i55@pure_quanta.q_res(chips)',
 P_PATH='@t6g_mb_lib.t6g(sch_1):page267_i55@pure_quanta.q_res(chips)',
 PATH='I55',
 DRAWING='@T6G_MB_LIB.T6G(SCH_1):PAGE371',
 WATTAGE='1/16W',
 TOLERANCE='1%',
 MATERIAL='EMPTY',
 PHYS_PAGE='267',
 XY='(-7300,6225)',
 ROT='0',
 VER='2',
 PACK_TYPE='0402LF',
 LOCATION='R6234',
 CDS_LIB='pure_quanta',
 CDS_PART_NAME='Q_RES_0402LF-160K,1%,1/16W,EMPTY,CS41602FB05',
 ROOM='HSC BOM2',
 PART_NUMBER='CS41602FB05',
 VALUE='160K',
 PRIM_FILE='./archive_libs/logical/q_res/chips/chips.prt';

PART_NAME
 R6235 'Q_RES_0402LF-10K,1%,1/16W,EMPTY,CS31002FB08':
 ROOM='HSC BOM2';

SECTION_NUMBER 1
 '@T6G_MB_LIB.T6G(SCH_1):PAGE371_I58@PURE_QUANTA.Q_RES(CHIPS)':
 C_PATH='@t6g_mb_lib.t6g(sch_1):page371_i58@pure_quanta.q_res(chips)',
 P_PATH='@t6g_mb_lib.t6g(sch_1):page267_i58@pure_quanta.q_res(chips)',
 PATH='I58',
 DRAWING='@T6G_MB_LIB.T6G(SCH_1):PAGE371',
 WATTAGE='1/16W',
 TOLERANCE='1%',
 MATERIAL='EMPTY',
 PHYS_PAGE='267',
 XY='(-7300,5425)',
 ROT='0',
 VER='2',
 PACK_TYPE='0402LF',
 LOCATION='R6235',
 CDS_LIB='pure_quanta',
 CDS_PART_NAME='Q_RES_0402LF-10K,1%,1/16W,EMPTY,CS31002FB08',
 ROOM='HSC BOM2',
 PART_NUMBER='CS31002FB08',
 VALUE='10K',
 PRIM_FILE='./archive_libs/logical/q_res/chips/chips.prt';

PART_NAME
 R6236 'Q_RES_0402LF-10K,1%,1/16W,EMPTY,CS31002FB08':
 ROOM='HSC BOM2';

SECTION_NUMBER 1
 '@T6G_MB_LIB.T6G(SCH_1):PAGE371_I63@PURE_QUANTA.Q_RES(CHIPS)':
 C_PATH='@t6g_mb_lib.t6g(sch_1):page371_i63@pure_quanta.q_res(chips)',
 P_PATH='@t6g_mb_lib.t6g(sch_1):page267_i63@pure_quanta.q_res(chips)',
 PATH='I63',
 DRAWING='@T6G_MB_LIB.T6G(SCH_1):PAGE371',
 WATTAGE='1/16W',
 TOLERANCE='1%',
 MATERIAL='EMPTY',
 PHYS_PAGE='267',
 XY='(-4450,6225)',
 ROT='0',
 VER='2',
 PACK_TYPE='0402LF',
 LOCATION='R6236',
 CDS_LIB='pure_quanta',
 CDS_PART_NAME='Q_RES_0402LF-10K,1%,1/16W,EMPTY,CS31002FB08',
 ROOM='HSC BOM2',
 PART_NUMBER='CS31002FB08',
 VALUE='10K',
 PRIM_FILE='./archive_libs/logical/q_res/chips/chips.prt';

PART_NAME
 R6237 'Q_RES_0402LF-0,5%,1/16W,EMPTY,CS00002JB13':
 ROOM='HSC BOM2';

SECTION_NUMBER 1
 '@T6G_MB_LIB.T6G(SCH_1):PAGE371_I66@PURE_QUANTA.Q_RES(CHIPS)':
 C_PATH='@t6g_mb_lib.t6g(sch_1):page371_i66@pure_quanta.q_res(chips)',
 P_PATH='@t6g_mb_lib.t6g(sch_1):page267_i66@pure_quanta.q_res(chips)',
 PATH='I66',
 DRAWING='@T6G_MB_LIB.T6G(SCH_1):PAGE371',
 WATTAGE='1/16W',
 TOLERANCE='5%',
 MATERIAL='EMPTY',
 PHYS_PAGE='267',
 XY='(-4450,5525)',
 ROT='0',
 VER='2',
 PACK_TYPE='0402LF',
 LOCATION='R6237',
 CDS_LIB='pure_quanta',
 CDS_PART_NAME='Q_RES_0402LF-0,5%,1/16W,EMPTY,CS00002JB13',
 ROOM='HSC BOM2',
 PART_NUMBER='CS00002JB13',
 VALUE='0',
 PRIM_FILE='./archive_libs/logical/q_res/chips/chips.prt';

PART_NAME
 R6238 'Q_RES_0402LF-0,5%,1/16W,EMPTY,CS00002JB13':
 ROOM='HSC BOM2';

SECTION_NUMBER 1
 '@T6G_MB_LIB.T6G(SCH_1):PAGE371_I72@PURE_QUANTA.Q_RES(CHIPS)':
 C_PATH='@t6g_mb_lib.t6g(sch_1):page371_i72@pure_quanta.q_res(chips)',
 P_PATH='@t6g_mb_lib.t6g(sch_1):page267_i72@pure_quanta.q_res(chips)',
 PATH='I72',
 DRAWING='@T6G_MB_LIB.T6G(SCH_1):PAGE371',
 WATTAGE='1/16W',
 TOLERANCE='5%',
 MATERIAL='EMPTY',
 PHYS_PAGE='267',
 XY='(-2775,6225)',
 ROT='0',
 VER='2',
 PACK_TYPE='0402LF',
 LOCATION='R6238',
 CDS_LIB='pure_quanta',
 CDS_PART_NAME='Q_RES_0402LF-0,5%,1/16W,EMPTY,CS00002JB13',
 ROOM='HSC BOM2',
 PART_NUMBER='CS00002JB13',
 VALUE='0',
 PRIM_FILE='./archive_libs/logical/q_res/chips/chips.prt';

PART_NAME
 R6239 'Q_RES_0402LF-10K,1%,1/16W,CHIP,CS31002FB08':
 ROOM='HSC BOM2';

SECTION_NUMBER 1
 '@T6G_MB_LIB.T6G(SCH_1):PAGE371_I70@PURE_QUANTA.Q_RES(CHIPS)':
 C_PATH='@t6g_mb_lib.t6g(sch_1):page371_i70@pure_quanta.q_res(chips)',
 P_PATH='@t6g_mb_lib.t6g(sch_1):page267_i70@pure_quanta.q_res(chips)',
 PATH='I70',
 DRAWING='@T6G_MB_LIB.T6G(SCH_1):PAGE371',
 WATTAGE='1/16W',
 TOLERANCE='1%',
 MATERIAL='CHIP',
 PHYS_PAGE='267',
 XY='(-2300,6175)',
 ROT='0',
 VER='2',
 PACK_TYPE='0402LF',
 LOCATION='R6239',
 CDS_LIB='pure_quanta',
 CDS_PART_NAME='Q_RES_0402LF-10K,1%,1/16W,CHIP,CS31002FB08',
 ROOM='HSC BOM2',
 PART_NUMBER='CS31002FB08',
 VALUE='10K',
 PRIM_FILE='./archive_libs/logical/q_res/chips/chips.prt';

PART_NAME
 R6240 'Q_RES_0402LF-0,5%,1/16W,CHIP,CS00002JB13':;

SECTION_NUMBER 1
 '@T6G_MB_LIB.T6G(SCH_1):PAGE380_I40@PURE_QUANTA.Q_RES(CHIPS)':
 C_PATH='@t6g_mb_lib.t6g(sch_1):page380_i40@pure_quanta.q_res(chips)',
 P_PATH='@t6g_mb_lib.t6g(sch_1):page270_i40@pure_quanta.q_res(chips)',
 PATH='I40',
 DRAWING='@T6G_MB_LIB.T6G(SCH_1):PAGE380',
 WATTAGE='1/16W',
 TOLERANCE='5%',
 MATERIAL='CHIP',
 PHYS_PAGE='270',
 XY='(-6475,2000)',
 ROT='0',
 VER='1',
 PACK_TYPE='0402LF',
 LOCATION='R6240',
 CDS_LIB='pure_quanta',
 CDS_PART_NAME='Q_RES_0402LF-0,5%,1/16W,CHIP,CS00002JB13',
 PART_NUMBER='CS00002JB13',
 VALUE='0',
 PRIM_FILE='./archive_libs/logical/q_res/chips/chips.prt';

PART_NAME
 R6241 'Q_RES_0402LF-0,5%,1/16W,CHIP,CS00002JB13':;

SECTION_NUMBER 1
 '@T6G_MB_LIB.T6G(SCH_1):PAGE380_I44@PURE_QUANTA.Q_RES(CHIPS)':
 C_PATH='@t6g_mb_lib.t6g(sch_1):page380_i44@pure_quanta.q_res(chips)',
 P_PATH='@t6g_mb_lib.t6g(sch_1):page270_i44@pure_quanta.q_res(chips)',
 PATH='I44',
 DRAWING='@T6G_MB_LIB.T6G(SCH_1):PAGE380',
 WATTAGE='1/16W',
 TOLERANCE='5%',
 MATERIAL='CHIP',
 PHYS_PAGE='270',
 XY='(-2875,2500)',
 ROT='0',
 VER='1',
 PACK_TYPE='0402LF',
 LOCATION='R6241',
 CDS_LIB='pure_quanta',
 CDS_PART_NAME='Q_RES_0402LF-0,5%,1/16W,CHIP,CS00002JB13',
 PART_NUMBER='CS00002JB13',
 VALUE='0',
 PRIM_FILE='./archive_libs/logical/q_res/chips/chips.prt';

PART_NAME
 R6242 'Q_RES_0402LF-0,5%,1/16W,CHIP,CS00002JB13':;

SECTION_NUMBER 1
 '@T6G_MB_LIB.T6G(SCH_1):PAGE315_I2@PURE_QUANTA.Q_RES(CHIPS)':
 C_PATH='@t6g_mb_lib.t6g(sch_1):page315_i2@pure_quanta.q_res(chips)',
 P_PATH='@t6g_mb_lib.t6g(sch_1):page269_i2@pure_quanta.q_res(chips)',
 PATH='I2',
 DRAWING='@T6G_MB_LIB.T6G(SCH_1):PAGE315',
 WATTAGE='1/16W',
 TOLERANCE='5%',
 MATERIAL='CHIP',
 PHYS_PAGE='269',
 XY='(-2825,1575)',
 ROT='3',
 VER='2',
 PACK_TYPE='0402LF',
 LOCATION='R6242',
 CDS_LIB='pure_quanta',
 CDS_PART_NAME='Q_RES_0402LF-0,5%,1/16W,CHIP,CS00002JB13',
 PART_NUMBER='CS00002JB13',
 VALUE='0',
 PRIM_FILE='./archive_libs/logical/q_res/chips/chips.prt';

PART_NAME
 R6243 'Q_RES_0402LF-10K,1%,1/16W,CHIP,CS31002FB08':;

SECTION_NUMBER 1
 '@T6G_MB_LIB.T6G(SCH_1):PAGE315_I32@PURE_QUANTA.Q_RES(CHIPS)':
 C_PATH='@t6g_mb_lib.t6g(sch_1):page315_i32@pure_quanta.q_res(chips)',
 P_PATH='@t6g_mb_lib.t6g(sch_1):page269_i32@pure_quanta.q_res(chips)',
 PATH='I32',
 DRAWING='@T6G_MB_LIB.T6G(SCH_1):PAGE315',
 WATTAGE='1/16W',
 TOLERANCE='1%',
 MATERIAL='CHIP',
 PHYS_PAGE='269',
 XY='(25,2825)',
 ROT='0',
 VER='2',
 PACK_TYPE='0402LF',
 LOCATION='R6243',
 CDS_LIB='pure_quanta',
 CDS_PART_NAME='Q_RES_0402LF-10K,1%,1/16W,CHIP,CS31002FB08',
 PART_NUMBER='CS31002FB08',
 VALUE='10K',
 PRIM_FILE='./archive_libs/logical/q_res/chips/chips.prt';

PART_NAME
 R6244 'Q_RES_0402LF-10K,1%,1/16W,CHIP,CS31002FB08':;

SECTION_NUMBER 1
 '@T6G_MB_LIB.T6G(SCH_1):PAGE380_I19@PURE_QUANTA.Q_RES(CHIPS)':
 C_PATH='@t6g_mb_lib.t6g(sch_1):page380_i19@pure_quanta.q_res(chips)',
 P_PATH='@t6g_mb_lib.t6g(sch_1):page270_i19@pure_quanta.q_res(chips)',
 PATH='I19',
 DRAWING='@T6G_MB_LIB.T6G(SCH_1):PAGE380',
 WATTAGE='1/16W',
 TOLERANCE='1%',
 MATERIAL='CHIP',
 PHYS_PAGE='270',
 XY='(-3550,2800)',
 ROT='0',
 VER='2',
 PACK_TYPE='0402LF',
 LOCATION='R6244',
 CDS_LIB='pure_quanta',
 CDS_PART_NAME='Q_RES_0402LF-10K,1%,1/16W,CHIP,CS31002FB08',
 PART_NUMBER='CS31002FB08',
 VALUE='10K',
 PRIM_FILE='./archive_libs/logical/q_res/chips/chips.prt';

PART_NAME
 R6245 'Q_RES_0402LF-0,5%,1/16W,CHIP,CS00002JB13':;

SECTION_NUMBER 1
 '@T6G_MB_LIB.T6G(SCH_1):PAGE380_I38@PURE_QUANTA.Q_RES(CHIPS)':
 C_PATH='@t6g_mb_lib.t6g(sch_1):page380_i38@pure_quanta.q_res(chips)',
 P_PATH='@t6g_mb_lib.t6g(sch_1):page270_i38@pure_quanta.q_res(chips)',
 PATH='I38',
 DRAWING='@T6G_MB_LIB.T6G(SCH_1):PAGE380',
 WATTAGE='1/16W',
 TOLERANCE='5%',
 MATERIAL='CHIP',
 PHYS_PAGE='270',
 XY='(-6400,1550)',
 ROT='3',
 VER='2',
 PACK_TYPE='0402LF',
 LOCATION='R6245',
 CDS_LIB='pure_quanta',
 CDS_PART_NAME='Q_RES_0402LF-0,5%,1/16W,CHIP,CS00002JB13',
 PART_NUMBER='CS00002JB13',
 VALUE='0',
 PRIM_FILE='./archive_libs/logical/q_res/chips/chips.prt';

PART_NAME
 R6246 'Q_RES_0402LF-130,1%,1/16W,CHIP,CS11302FB03':;

SECTION_NUMBER 1
 '@T6G_MB_LIB.T6G(SCH_1):PAGE254_I45@PURE_QUANTA.Q_RES(CHIPS)':
 C_PATH='@t6g_mb_lib.t6g(sch_1):page254_i45@pure_quanta.q_res(chips)',
 P_PATH='@t6g_mb_lib.t6g(sch_1):page254_i45@pure_quanta.q_res(chips)',
 PATH='I45',
 DRAWING='@T6G_MB_LIB.T6G(SCH_1):PAGE254',
 WATTAGE='1/16W',
 TOLERANCE='1%',
 MATERIAL='CHIP',
 PHYS_PAGE='254',
 XY='(-775,3950)',
 ROT='0',
 VER='1',
 PACK_TYPE='0402LF',
 LOCATION='R6246',
 CDS_LIB='pure_quanta',
 CDS_PART_NAME='Q_RES_0402LF-130,1%,1/16W,CHIP,CS11302FB03',
 PART_NUMBER='CS11302FB03',
 VALUE='130',
 PRIM_FILE='./archive_libs/logical/q_res/chips/chips.prt';

PART_NAME
 R6247 'Q_RES_0402LF-4.7K,1%,1/16W,CHIP,CS24702FB06':;

SECTION_NUMBER 1
 '@T6G_MB_LIB.T6G(SCH_1):PAGE271_I25@PURE_QUANTA.Q_RES(CHIPS)':
 C_PATH='@t6g_mb_lib.t6g(sch_1):page271_i25@pure_quanta.q_res(chips)',
 P_PATH='@t6g_mb_lib.t6g(sch_1):page271_i25@pure_quanta.q_res(chips)',
 PATH='I25',
 DRAWING='@T6G_MB_LIB.T6G(SCH_1):PAGE271',
 WATTAGE='1/16W',
 TOLERANCE='1%',
 MATERIAL='CHIP',
 PHYS_PAGE='271',
 XY='(-3375,6050)',
 ROT='0',
 VER='2',
 PACK_TYPE='0402LF',
 LOCATION='R6247',
 CDS_LIB='pure_quanta',
 CDS_PART_NAME='Q_RES_0402LF-4.7K,1%,1/16W,CHIP,CS24702FB06',
 PART_NUMBER='CS24702FB06',
 VALUE='4.7K',
 PRIM_FILE='./archive_libs/logical/q_res/chips/chips.prt';

PART_NAME
 R6250 'Q_RES_0402LF-4.7K,1%,1/16W,CHIP,CS24702FB06':;

SECTION_NUMBER 1
 '@T6G_MB_LIB.T6G(SCH_1):PAGE271_I30@PURE_QUANTA.Q_RES(CHIPS)':
 C_PATH='@t6g_mb_lib.t6g(sch_1):page271_i30@pure_quanta.q_res(chips)',
 P_PATH='@t6g_mb_lib.t6g(sch_1):page271_i30@pure_quanta.q_res(chips)',
 PATH='I30',
 DRAWING='@T6G_MB_LIB.T6G(SCH_1):PAGE271',
 WATTAGE='1/16W',
 TOLERANCE='1%',
 MATERIAL='CHIP',
 PHYS_PAGE='271',
 XY='(-7025,5675)',
 ROT='0',
 VER='1',
 PACK_TYPE='0402LF',
 LOCATION='R6250',
 CDS_LIB='pure_quanta',
 CDS_PART_NAME='Q_RES_0402LF-4.7K,1%,1/16W,CHIP,CS24702FB06',
 PART_NUMBER='CS24702FB06',
 VALUE='4.7K',
 PRIM_FILE='./archive_libs/logical/q_res/chips/chips.prt';

PART_NAME
 R6251 'Q_RES_0402LF-4.7K,1%,1/16W,EMPTY,CS24702FB06':;

SECTION_NUMBER 1
 '@T6G_MB_LIB.T6G(SCH_1):PAGE271_I14@PURE_QUANTA.Q_RES(CHIPS)':
 C_PATH='@t6g_mb_lib.t6g(sch_1):page271_i14@pure_quanta.q_res(chips)',
 P_PATH='@t6g_mb_lib.t6g(sch_1):page271_i14@pure_quanta.q_res(chips)',
 PATH='I14',
 DRAWING='@T6G_MB_LIB.T6G(SCH_1):PAGE271',
 WATTAGE='1/16W',
 TOLERANCE='1%',
 MATERIAL='EMPTY',
 PHYS_PAGE='271',
 XY='(-7025,5625)',
 ROT='0',
 VER='1',
 PACK_TYPE='0402LF',
 LOCATION='R6251',
 CDS_LIB='pure_quanta',
 CDS_PART_NAME='Q_RES_0402LF-4.7K,1%,1/16W,EMPTY,CS24702FB06',
 PART_NUMBER='CS24702FB06',
 VALUE='4.7K',
 PRIM_FILE='./archive_libs/logical/q_res/chips/chips.prt';

PART_NAME
 R6252 'Q_RES_0402LF-33.2,1%,1/16W,CHIP,CS03322FB03':;

SECTION_NUMBER 1
 '@T6G_MB_LIB.T6G(SCH_1):PAGE271_I9@PURE_QUANTA.Q_RES(CHIPS)':
 C_PATH='@t6g_mb_lib.t6g(sch_1):page271_i9@pure_quanta.q_res(chips)',
 P_PATH='@t6g_mb_lib.t6g(sch_1):page271_i9@pure_quanta.q_res(chips)',
 PATH='I9',
 DRAWING='@T6G_MB_LIB.T6G(SCH_1):PAGE271',
 WATTAGE='1/16W',
 TOLERANCE='1%',
 MATERIAL='CHIP',
 PHYS_PAGE='271',
 XY='(-6225,5350)',
 ROT='0',
 VER='1',
 PACK_TYPE='0402LF',
 LOCATION='R6252',
 CDS_LIB='pure_quanta',
 CDS_PART_NAME='Q_RES_0402LF-33.2,1%,1/16W,CHIP,CS03322FB03',
 PART_NUMBER='CS03322FB03',
 VALUE='33.2',
 PRIM_FILE='./archive_libs/logical/q_res/chips/chips.prt';

PART_NAME
 R6253 'Q_RES_0402LF-33.2,1%,1/16W,CHIP,CS03322FB03':;

SECTION_NUMBER 1
 '@T6G_MB_LIB.T6G(SCH_1):PAGE271_I10@PURE_QUANTA.Q_RES(CHIPS)':
 C_PATH='@t6g_mb_lib.t6g(sch_1):page271_i10@pure_quanta.q_res(chips)',
 P_PATH='@t6g_mb_lib.t6g(sch_1):page271_i10@pure_quanta.q_res(chips)',
 PATH='I10',
 DRAWING='@T6G_MB_LIB.T6G(SCH_1):PAGE271',
 WATTAGE='1/16W',
 TOLERANCE='1%',
 MATERIAL='CHIP',
 PHYS_PAGE='271',
 XY='(-6225,5300)',
 ROT='0',
 VER='1',
 PACK_TYPE='0402LF',
 LOCATION='R6253',
 CDS_LIB='pure_quanta',
 CDS_PART_NAME='Q_RES_0402LF-33.2,1%,1/16W,CHIP,CS03322FB03',
 PART_NUMBER='CS03322FB03',
 VALUE='33.2',
 PRIM_FILE='./archive_libs/logical/q_res/chips/chips.prt';

PART_NAME
 R6254 'Q_RES_0402LF-0,5%,1/16W,CHIP,CS00002JB13':;

SECTION_NUMBER 1
 '@T6G_MB_LIB.T6G(SCH_1):PAGE271_I29@PURE_QUANTA.Q_RES(CHIPS)':
 C_PATH='@t6g_mb_lib.t6g(sch_1):page271_i29@pure_quanta.q_res(chips)',
 P_PATH='@t6g_mb_lib.t6g(sch_1):page271_i29@pure_quanta.q_res(chips)',
 PATH='I29',
 DRAWING='@T6G_MB_LIB.T6G(SCH_1):PAGE271',
 WATTAGE='1/16W',
 TOLERANCE='5%',
 MATERIAL='CHIP',
 PHYS_PAGE='271',
 XY='(-5825,5500)',
 ROT='0',
 VER='2',
 PACK_TYPE='0402LF',
 LOCATION='R6254',
 CDS_LIB='pure_quanta',
 CDS_PART_NAME='Q_RES_0402LF-0,5%,1/16W,CHIP,CS00002JB13',
 PART_NUMBER='CS00002JB13',
 VALUE='0',
 PRIM_FILE='./archive_libs/logical/q_res/chips/chips.prt';

PART_NAME
 R6257 'Q_RES_0402LF-1M,1%,1/16W,CHIP,CS51002FB05':
 ROOM='USB3_HUB2';

SECTION_NUMBER 1
 '@T6G_MB_LIB.T6G(SCH_1):PAGE157_I160@PURE_QUANTA.Q_RES(CHIPS)':
 C_PATH='@t6g_mb_lib.t6g(sch_1):page157_i160@pure_quanta.q_res(chips)',
 P_PATH='@t6g_mb_lib.t6g(sch_1):page179_i160@pure_quanta.q_res(chips)',
 PATH='I160',
 DRAWING='@T6G_MB_LIB.T6G(SCH_1):PAGE157',
 WATTAGE='1/16W',
 TOLERANCE='1%',
 MATERIAL='CHIP',
 PHYS_PAGE='179',
 XY='(-6925,3475)',
 ROT='0',
 VER='1',
 PACK_TYPE='0402LF',
 LOCATION='R6257',
 CDS_LIB='pure_quanta',
 CDS_PART_NAME='Q_RES_0402LF-1M,1%,1/16W,CHIP,CS51002FB05',
 ROOM='USB3_HUB2',
 PART_NUMBER='CS51002FB05',
 VALUE='1M',
 PRIM_FILE='./archive_libs/logical/q_res/chips/chips.prt';

PART_NAME
 R6258 'Q_RES_0402LF-4.7K,5%,1/16W,EMPTY,CS24702JB10':
 GROUP='HUB_TI',
 ROOM='USB3_HUB2_TI';

SECTION_NUMBER 1
 '@T6G_MB_LIB.T6G(SCH_1):PAGE155_I164@PURE_QUANTA.Q_RES(CHIPS)':
 C_PATH='@t6g_mb_lib.t6g(sch_1):page155_i164@pure_quanta.q_res(chips)',
 P_PATH='@t6g_mb_lib.t6g(sch_1):page178_i164@pure_quanta.q_res(chips)',
 PATH='I164',
 DRAWING='@T6G_MB_LIB.T6G(SCH_1):PAGE155',
 WATTAGE='1/16W',
 TOLERANCE='5%',
 MATERIAL='EMPTY',
 PHYS_PAGE='178',
 XY='(-7075,4275)',
 ROT='0',
 VER='1',
 PACK_TYPE='0402LF',
 LOCATION='R6258',
 CDS_LIB='pure_quanta',
 CDS_PART_NAME='Q_RES_0402LF-4.7K,5%,1/16W,EMPTY,CS24702JB10',
 GROUP='HUB_TI',
 ROOM='USB3_HUB2_TI',
 PART_NUMBER='CS24702JB10',
 VALUE='4.7K',
 PRIM_FILE='./archive_libs/logical/q_res/chips/chips.prt';

PART_NAME
 R6259 'Q_RES_0402LF-0,5%,1/16W,CHIP,CS00002JB13':
 GROUP='HUB_MRP',
 ROOM='USB3_HUB2_MRP';

SECTION_NUMBER 1
 '@T6G_MB_LIB.T6G(SCH_1):PAGE155_I166@PURE_QUANTA.Q_RES(CHIPS)':
 C_PATH='@t6g_mb_lib.t6g(sch_1):page155_i166@pure_quanta.q_res(chips)',
 P_PATH='@t6g_mb_lib.t6g(sch_1):page178_i166@pure_quanta.q_res(chips)',
 PATH='I166',
 DRAWING='@T6G_MB_LIB.T6G(SCH_1):PAGE155',
 BOM_COST='VR_SYSTEM ',
 WATTAGE='1/16W',
 TOLERANCE='5%',
 MATERIAL='CHIP',
 PHYS_PAGE='178',
 XY='(-7050,4050)',
 ROT='0',
 VER='1',
 PACK_TYPE='0402LF',
 LOCATION='R6259',
 CDS_LIB='pure_quanta',
 CDS_PART_NAME='Q_RES_0402LF-0,5%,1/16W,CHIP,CS00002JB13',
 GROUP='HUB_MRP',
 ROOM='USB3_HUB2_MRP',
 PART_NUMBER='CS00002JB13',
 VALUE='0',
 PRIM_FILE='./archive_libs/logical/q_res/chips/chips.prt';

PART_NAME
 R6260 'Q_RES_0402LF-0,5%,1/16W,CHIP,CS00002JB13':
 GROUP='HUB_TI',
 ROOM='USB3_HUB2_TI';

SECTION_NUMBER 1
 '@T6G_MB_LIB.T6G(SCH_1):PAGE157_I170@PURE_QUANTA.Q_RES(CHIPS)':
 C_PATH='@t6g_mb_lib.t6g(sch_1):page157_i170@pure_quanta.q_res(chips)',
 P_PATH='@t6g_mb_lib.t6g(sch_1):page179_i170@pure_quanta.q_res(chips)',
 PATH='I170',
 DRAWING='@T6G_MB_LIB.T6G(SCH_1):PAGE157',
 BOM_COST='VR_SYSTEM ',
 WATTAGE='1/16W',
 TOLERANCE='5%',
 MATERIAL='CHIP',
 PHYS_PAGE='179',
 XY='(-2150,5675)',
 ROT='0',
 VER='1',
 PACK_TYPE='0402LF',
 LOCATION='R6260',
 CDS_LIB='pure_quanta',
 CDS_PART_NAME='Q_RES_0402LF-0,5%,1/16W,CHIP,CS00002JB13',
 GROUP='HUB_TI',
 ROOM='USB3_HUB2_TI',
 PART_NUMBER='CS00002JB13',
 VALUE='0',
 PRIM_FILE='./archive_libs/logical/q_res/chips/chips.prt';

PART_NAME
 R6261 'Q_RES_0402LF-0,5%,1/16W,CHIP,CS00002JB13':
 GROUP='HUB_MRP',
 ROOM='USB3_HUB2_MRP';

SECTION_NUMBER 1
 '@T6G_MB_LIB.T6G(SCH_1):PAGE155_I134@PURE_QUANTA.Q_RES(CHIPS)':
 C_PATH='@t6g_mb_lib.t6g(sch_1):page155_i134@pure_quanta.q_res(chips)',
 P_PATH='@t6g_mb_lib.t6g(sch_1):page178_i134@pure_quanta.q_res(chips)',
 PATH='I134',
 DRAWING='@T6G_MB_LIB.T6G(SCH_1):PAGE155',
 BOM_COST='VR_SYSTEM ',
 WATTAGE='1/16W',
 TOLERANCE='5%',
 MATERIAL='CHIP',
 PHYS_PAGE='178',
 XY='(-2500,5150)',
 ROT='0',
 VER='1',
 PACK_TYPE='0402LF',
 LOCATION='R6261',
 CDS_LIB='pure_quanta',
 CDS_PART_NAME='Q_RES_0402LF-0,5%,1/16W,CHIP,CS00002JB13',
 GROUP='HUB_MRP',
 ROOM='USB3_HUB2_MRP',
 PART_NUMBER='CS00002JB13',
 VALUE='0',
 PRIM_FILE='./archive_libs/logical/q_res/chips/chips.prt';

PART_NAME
 R6262 'Q_RES_0402LF-0,5%,1/16W,CHIP,CS00002JB13':
 GROUP='HUB_TI',
 ROOM='USB3_HUB2_TI';

SECTION_NUMBER 1
 '@T6G_MB_LIB.T6G(SCH_1):PAGE157_I134@PURE_QUANTA.Q_RES(CHIPS)':
 C_PATH='@t6g_mb_lib.t6g(sch_1):page157_i134@pure_quanta.q_res(chips)',
 P_PATH='@t6g_mb_lib.t6g(sch_1):page179_i134@pure_quanta.q_res(chips)',
 PATH='I134',
 DRAWING='@T6G_MB_LIB.T6G(SCH_1):PAGE157',
 BOM_COST='VR_SYSTEM ',
 WATTAGE='1/16W',
 TOLERANCE='5%',
 MATERIAL='CHIP',
 PHYS_PAGE='179',
 XY='(-2125,5525)',
 ROT='0',
 VER='1',
 PACK_TYPE='0402LF',
 LOCATION='R6262',
 CDS_LIB='pure_quanta',
 CDS_PART_NAME='Q_RES_0402LF-0,5%,1/16W,CHIP,CS00002JB13',
 GROUP='HUB_TI',
 ROOM='USB3_HUB2_TI',
 PART_NUMBER='CS00002JB13',
 VALUE='0',
 PRIM_FILE='./archive_libs/logical/q_res/chips/chips.prt';

PART_NAME
 R6263 'Q_RES_0402LF-0,5%,1/16W,CHIP,CS00002JB13':
 GROUP='HUB_MRP',
 ROOM='USB3_HUB2_MRP';

SECTION_NUMBER 1
 '@T6G_MB_LIB.T6G(SCH_1):PAGE155_I155@PURE_QUANTA.Q_RES(CHIPS)':
 C_PATH='@t6g_mb_lib.t6g(sch_1):page155_i155@pure_quanta.q_res(chips)',
 P_PATH='@t6g_mb_lib.t6g(sch_1):page178_i155@pure_quanta.q_res(chips)',
 PATH='I155',
 DRAWING='@T6G_MB_LIB.T6G(SCH_1):PAGE155',
 BOM_COST='VR_SYSTEM ',
 WATTAGE='1/16W',
 TOLERANCE='5%',
 MATERIAL='CHIP',
 PHYS_PAGE='178',
 XY='(-2450,3250)',
 ROT='0',
 VER='1',
 PACK_TYPE='0402LF',
 LOCATION='R6263',
 CDS_LIB='pure_quanta',
 CDS_PART_NAME='Q_RES_0402LF-0,5%,1/16W,CHIP,CS00002JB13',
 GROUP='HUB_MRP',
 ROOM='USB3_HUB2_MRP',
 PART_NUMBER='CS00002JB13',
 VALUE='0',
 PRIM_FILE='./archive_libs/logical/q_res/chips/chips.prt';

PART_NAME
 R6264 'Q_RES_0402LF-0,5%,1/16W,CHIP,CS00002JB13':
 GROUP='HUB_MRP',
 ROOM='USB3_HUB2_MRP';

SECTION_NUMBER 1
 '@T6G_MB_LIB.T6G(SCH_1):PAGE155_I151@PURE_QUANTA.Q_RES(CHIPS)':
 C_PATH='@t6g_mb_lib.t6g(sch_1):page155_i151@pure_quanta.q_res(chips)',
 P_PATH='@t6g_mb_lib.t6g(sch_1):page178_i151@pure_quanta.q_res(chips)',
 PATH='I151',
 DRAWING='@T6G_MB_LIB.T6G(SCH_1):PAGE155',
 BOM_COST='VR_SYSTEM ',
 WATTAGE='1/16W',
 TOLERANCE='5%',
 MATERIAL='CHIP',
 PHYS_PAGE='178',
 XY='(-2450,3200)',
 ROT='0',
 VER='1',
 PACK_TYPE='0402LF',
 LOCATION='R6264',
 CDS_LIB='pure_quanta',
 CDS_PART_NAME='Q_RES_0402LF-0,5%,1/16W,CHIP,CS00002JB13',
 GROUP='HUB_MRP',
 ROOM='USB3_HUB2_MRP',
 PART_NUMBER='CS00002JB13',
 VALUE='0',
 PRIM_FILE='./archive_libs/logical/q_res/chips/chips.prt';

PART_NAME
 R6265 'Q_RES_0402LF-0,5%,1/16W,CHIP,CS00002JB13':
 GROUP='HUB_TI',
 ROOM='USB3_HUB2_TI';

SECTION_NUMBER 1
 '@T6G_MB_LIB.T6G(SCH_1):PAGE157_I145@PURE_QUANTA.Q_RES(CHIPS)':
 C_PATH='@t6g_mb_lib.t6g(sch_1):page157_i145@pure_quanta.q_res(chips)',
 P_PATH='@t6g_mb_lib.t6g(sch_1):page179_i145@pure_quanta.q_res(chips)',
 PATH='I145',
 DRAWING='@T6G_MB_LIB.T6G(SCH_1):PAGE157',
 BOM_COST='VR_SYSTEM ',
 WATTAGE='1/16W',
 TOLERANCE='5%',
 MATERIAL='CHIP',
 PHYS_PAGE='179',
 XY='(-2125,5225)',
 ROT='0',
 VER='1',
 PACK_TYPE='0402LF',
 LOCATION='R6265',
 CDS_LIB='pure_quanta',
 CDS_PART_NAME='Q_RES_0402LF-0,5%,1/16W,CHIP,CS00002JB13',
 GROUP='HUB_TI',
 ROOM='USB3_HUB2_TI',
 PART_NUMBER='CS00002JB13',
 VALUE='0',
 PRIM_FILE='./archive_libs/logical/q_res/chips/chips.prt';

PART_NAME
 R6266 'Q_RES_0402LF-0,5%,1/16W,CHIP,CS00002JB13':
 GROUP='HUB_MRP',
 ROOM='USB3_HUB2_MRP';

SECTION_NUMBER 1
 '@T6G_MB_LIB.T6G(SCH_1):PAGE155_I136@PURE_QUANTA.Q_RES(CHIPS)':
 C_PATH='@t6g_mb_lib.t6g(sch_1):page155_i136@pure_quanta.q_res(chips)',
 P_PATH='@t6g_mb_lib.t6g(sch_1):page178_i136@pure_quanta.q_res(chips)',
 PATH='I136',
 DRAWING='@T6G_MB_LIB.T6G(SCH_1):PAGE155',
 BOM_COST='VR_SYSTEM ',
 WATTAGE='1/16W',
 TOLERANCE='5%',
 MATERIAL='CHIP',
 PHYS_PAGE='178',
 XY='(-2450,3000)',
 ROT='0',
 VER='1',
 PACK_TYPE='0402LF',
 LOCATION='R6266',
 CDS_LIB='pure_quanta',
 CDS_PART_NAME='Q_RES_0402LF-0,5%,1/16W,CHIP,CS00002JB13',
 GROUP='HUB_MRP',
 ROOM='USB3_HUB2_MRP',
 PART_NUMBER='CS00002JB13',
 VALUE='0',
 PRIM_FILE='./archive_libs/logical/q_res/chips/chips.prt';

PART_NAME
 R6267 'Q_RES_0402LF-0,5%,1/16W,CHIP,CS00002JB13':
 GROUP='HUB_TI',
 ROOM='USB3_HUB2_TI';

SECTION_NUMBER 1
 '@T6G_MB_LIB.T6G(SCH_1):PAGE157_I122@PURE_QUANTA.Q_RES(CHIPS)':
 C_PATH='@t6g_mb_lib.t6g(sch_1):page157_i122@pure_quanta.q_res(chips)',
 P_PATH='@t6g_mb_lib.t6g(sch_1):page179_i122@pure_quanta.q_res(chips)',
 PATH='I122',
 DRAWING='@T6G_MB_LIB.T6G(SCH_1):PAGE157',
 BOM_COST='VR_SYSTEM ',
 WATTAGE='1/16W',
 TOLERANCE='5%',
 MATERIAL='CHIP',
 PHYS_PAGE='179',
 XY='(-2150,5075)',
 ROT='0',
 VER='1',
 PACK_TYPE='0402LF',
 LOCATION='R6267',
 CDS_LIB='pure_quanta',
 CDS_PART_NAME='Q_RES_0402LF-0,5%,1/16W,CHIP,CS00002JB13',
 GROUP='HUB_TI',
 ROOM='USB3_HUB2_TI',
 PART_NUMBER='CS00002JB13',
 VALUE='0',
 PRIM_FILE='./archive_libs/logical/q_res/chips/chips.prt';

PART_NAME
 R6268 'Q_RES_0402LF-0,5%,1/16W,CHIP,CS00002JB13':
 GROUP='HUB_MRP',
 ROOM='USB3_HUB2_MRP';

SECTION_NUMBER 1
 '@T6G_MB_LIB.T6G(SCH_1):PAGE155_I149@PURE_QUANTA.Q_RES(CHIPS)':
 C_PATH='@t6g_mb_lib.t6g(sch_1):page155_i149@pure_quanta.q_res(chips)',
 P_PATH='@t6g_mb_lib.t6g(sch_1):page178_i149@pure_quanta.q_res(chips)',
 PATH='I149',
 DRAWING='@T6G_MB_LIB.T6G(SCH_1):PAGE155',
 BOM_COST='VR_SYSTEM ',
 WATTAGE='1/16W',
 TOLERANCE='5%',
 MATERIAL='CHIP',
 PHYS_PAGE='178',
 XY='(-2300,2050)',
 ROT='0',
 VER='1',
 PACK_TYPE='0402LF',
 LOCATION='R6268',
 CDS_LIB='pure_quanta',
 CDS_PART_NAME='Q_RES_0402LF-0,5%,1/16W,CHIP,CS00002JB13',
 GROUP='HUB_MRP',
 ROOM='USB3_HUB2_MRP',
 PART_NUMBER='CS00002JB13',
 VALUE='0',
 PRIM_FILE='./archive_libs/logical/q_res/chips/chips.prt';

PART_NAME
 R6269 'Q_RES_0402LF-0,5%,1/16W,CHIP,CS00002JB13':
 GROUP='HUB_TI',
 ROOM='USB3_HUB2_TI';

SECTION_NUMBER 1
 '@T6G_MB_LIB.T6G(SCH_1):PAGE157_I136@PURE_QUANTA.Q_RES(CHIPS)':
 C_PATH='@t6g_mb_lib.t6g(sch_1):page157_i136@pure_quanta.q_res(chips)',
 P_PATH='@t6g_mb_lib.t6g(sch_1):page179_i136@pure_quanta.q_res(chips)',
 PATH='I136',
 DRAWING='@T6G_MB_LIB.T6G(SCH_1):PAGE157',
 BOM_COST='VR_SYSTEM ',
 WATTAGE='1/16W',
 TOLERANCE='5%',
 MATERIAL='CHIP',
 PHYS_PAGE='179',
 XY='(-2125,4925)',
 ROT='0',
 VER='1',
 PACK_TYPE='0402LF',
 LOCATION='R6269',
 CDS_LIB='pure_quanta',
 CDS_PART_NAME='Q_RES_0402LF-0,5%,1/16W,CHIP,CS00002JB13',
 GROUP='HUB_TI',
 ROOM='USB3_HUB2_TI',
 PART_NUMBER='CS00002JB13',
 VALUE='0',
 PRIM_FILE='./archive_libs/logical/q_res/chips/chips.prt';

PART_NAME
 R6270 'Q_RES_0402LF-0,5%,1/16W,CHIP,CS00002JB13':
 GROUP='HUB_MRP',
 ROOM='USB3_HUB2_MRP';

SECTION_NUMBER 1
 '@T6G_MB_LIB.T6G(SCH_1):PAGE155_I143@PURE_QUANTA.Q_RES(CHIPS)':
 C_PATH='@t6g_mb_lib.t6g(sch_1):page155_i143@pure_quanta.q_res(chips)',
 P_PATH='@t6g_mb_lib.t6g(sch_1):page178_i143@pure_quanta.q_res(chips)',
 PATH='I143',
 DRAWING='@T6G_MB_LIB.T6G(SCH_1):PAGE155',
 BOM_COST='VR_SYSTEM ',
 WATTAGE='1/16W',
 TOLERANCE='5%',
 MATERIAL='CHIP',
 PHYS_PAGE='178',
 XY='(-7200,3900)',
 ROT='0',
 VER='1',
 PACK_TYPE='0402LF',
 LOCATION='R6270',
 CDS_LIB='pure_quanta',
 CDS_PART_NAME='Q_RES_0402LF-0,5%,1/16W,CHIP,CS00002JB13',
 GROUP='HUB_MRP',
 ROOM='USB3_HUB2_MRP',
 PART_NUMBER='CS00002JB13',
 VALUE='0',
 PRIM_FILE='./archive_libs/logical/q_res/chips/chips.prt';

PART_NAME
 R6271 'Q_RES_0402LF-0,5%,1/16W,CHIP,CS00002JB13':
 GROUP='HUB_MRP',
 ROOM='USB3_HUB2_MRP';

SECTION_NUMBER 1
 '@T6G_MB_LIB.T6G(SCH_1):PAGE155_I102@PURE_QUANTA.Q_RES(CHIPS)':
 C_PATH='@t6g_mb_lib.t6g(sch_1):page155_i102@pure_quanta.q_res(chips)',
 P_PATH='@t6g_mb_lib.t6g(sch_1):page178_i102@pure_quanta.q_res(chips)',
 PATH='I102',
 DRAWING='@T6G_MB_LIB.T6G(SCH_1):PAGE155',
 BOM_COST='VR_SYSTEM ',
 WATTAGE='1/16W',
 TOLERANCE='5%',
 MATERIAL='CHIP',
 PHYS_PAGE='178',
 XY='(-2375,5350)',
 ROT='0',
 VER='1',
 PACK_TYPE='0402LF',
 LOCATION='R6271',
 CDS_LIB='pure_quanta',
 CDS_PART_NAME='Q_RES_0402LF-0,5%,1/16W,CHIP,CS00002JB13',
 GROUP='HUB_MRP',
 ROOM='USB3_HUB2_MRP',
 PART_NUMBER='CS00002JB13',
 VALUE='0',
 PRIM_FILE='./archive_libs/logical/q_res/chips/chips.prt';

PART_NAME
 R6272 'Q_RES_0402LF-200K,1%,1/16W,CHIP,CS42002FB05':
 GROUP='HUB_MRP',
 ROOM='USB3_HUB2_MRP';

SECTION_NUMBER 1
 '@T6G_MB_LIB.T6G(SCH_1):PAGE155_I105@PURE_QUANTA.Q_RES(CHIPS)':
 C_PATH='@t6g_mb_lib.t6g(sch_1):page155_i105@pure_quanta.q_res(chips)',
 P_PATH='@t6g_mb_lib.t6g(sch_1):page178_i105@pure_quanta.q_res(chips)',
 PATH='I105',
 DRAWING='@T6G_MB_LIB.T6G(SCH_1):PAGE155',
 WATTAGE='1/16W',
 TOLERANCE='1%',
 MATERIAL='CHIP',
 PHYS_PAGE='178',
 XY='(-1000,5100)',
 ROT='0',
 VER='2',
 PACK_TYPE='0402LF',
 LOCATION='R6272',
 CDS_LIB='pure_quanta',
 CDS_PART_NAME='Q_RES_0402LF-200K,1%,1/16W,CHIP,CS42002FB05',
 GROUP='HUB_MRP',
 ROOM='USB3_HUB2_MRP',
 PART_NUMBER='CS42002FB05',
 VALUE='200K',
 PRIM_FILE='./archive_libs/logical/q_res/chips/chips.prt';

PART_NAME
 R6273 'Q_RES_0402LF-200K,1%,1/16W,EMPTY,CS42002FB05':
 GROUP='HUB_MRP',
 ROOM='USB3_HUB2_MRP';

SECTION_NUMBER 1
 '@T6G_MB_LIB.T6G(SCH_1):PAGE155_I104@PURE_QUANTA.Q_RES(CHIPS)':
 C_PATH='@t6g_mb_lib.t6g(sch_1):page155_i104@pure_quanta.q_res(chips)',
 P_PATH='@t6g_mb_lib.t6g(sch_1):page178_i104@pure_quanta.q_res(chips)',
 PATH='I104',
 DRAWING='@T6G_MB_LIB.T6G(SCH_1):PAGE155',
 WATTAGE='1/16W',
 TOLERANCE='1%',
 MATERIAL='EMPTY',
 PHYS_PAGE='178',
 XY='(-1000,5650)',
 ROT='0',
 VER='2',
 PACK_TYPE='0402LF',
 LOCATION='R6273',
 CDS_LIB='pure_quanta',
 CDS_PART_NAME='Q_RES_0402LF-200K,1%,1/16W,EMPTY,CS42002FB05',
 GROUP='HUB_MRP',
 ROOM='USB3_HUB2_MRP',
 PART_NUMBER='CS42002FB05',
 VALUE='200K',
 PRIM_FILE='./archive_libs/logical/q_res/chips/chips.prt';

PART_NAME
 R6274 'Q_RES_0402LF-0,5%,1/16W,CHIP,CS00002JB13':
 GROUP='HUB_TI',
 ROOM='USB3_HUB2_TI';

SECTION_NUMBER 1
 '@T6G_MB_LIB.T6G(SCH_1):PAGE157_I142@PURE_QUANTA.Q_RES(CHIPS)':
 C_PATH='@t6g_mb_lib.t6g(sch_1):page157_i142@pure_quanta.q_res(chips)',
 P_PATH='@t6g_mb_lib.t6g(sch_1):page179_i142@pure_quanta.q_res(chips)',
 PATH='I142',
 DRAWING='@T6G_MB_LIB.T6G(SCH_1):PAGE157',
 BOM_COST='VR_SYSTEM ',
 WATTAGE='1/16W',
 TOLERANCE='5%',
 MATERIAL='CHIP',
 PHYS_PAGE='179',
 XY='(-2150,3875)',
 ROT='0',
 VER='1',
 PACK_TYPE='0402LF',
 LOCATION='R6274',
 CDS_LIB='pure_quanta',
 CDS_PART_NAME='Q_RES_0402LF-0,5%,1/16W,CHIP,CS00002JB13',
 GROUP='HUB_TI',
 ROOM='USB3_HUB2_TI',
 PART_NUMBER='CS00002JB13',
 VALUE='0',
 PRIM_FILE='./archive_libs/logical/q_res/chips/chips.prt';

PART_NAME
 R6275 'Q_RES_0402LF-0,5%,1/16W,CHIP,CS00002JB13':
 GROUP='HUB_TI',
 ROOM='USB3_HUB2_TI';

SECTION_NUMBER 1
 '@T6G_MB_LIB.T6G(SCH_1):PAGE157_I131@PURE_QUANTA.Q_RES(CHIPS)':
 C_PATH='@t6g_mb_lib.t6g(sch_1):page157_i131@pure_quanta.q_res(chips)',
 P_PATH='@t6g_mb_lib.t6g(sch_1):page179_i131@pure_quanta.q_res(chips)',
 PATH='I131',
 DRAWING='@T6G_MB_LIB.T6G(SCH_1):PAGE157',
 BOM_COST='VR_SYSTEM ',
 WATTAGE='1/16W',
 TOLERANCE='5%',
 MATERIAL='CHIP',
 PHYS_PAGE='179',
 XY='(-1800,3725)',
 ROT='0',
 VER='1',
 PACK_TYPE='0402LF',
 LOCATION='R6275',
 CDS_LIB='pure_quanta',
 CDS_PART_NAME='Q_RES_0402LF-0,5%,1/16W,CHIP,CS00002JB13',
 GROUP='HUB_TI',
 ROOM='USB3_HUB2_TI',
 PART_NUMBER='CS00002JB13',
 VALUE='0',
 PRIM_FILE='./archive_libs/logical/q_res/chips/chips.prt';

PART_NAME
 R6276 'Q_RES_0402LF-0,5%,1/16W,CHIP,CS00002JB13':
 GROUP='HUB_MRP',
 ROOM='USB3_HUB2_MRP';

SECTION_NUMBER 1
 '@T6G_MB_LIB.T6G(SCH_1):PAGE157_I125@PURE_QUANTA.Q_RES(CHIPS)':
 C_PATH='@t6g_mb_lib.t6g(sch_1):page157_i125@pure_quanta.q_res(chips)',
 P_PATH='@t6g_mb_lib.t6g(sch_1):page179_i125@pure_quanta.q_res(chips)',
 PATH='I125',
 DRAWING='@T6G_MB_LIB.T6G(SCH_1):PAGE157',
 BOM_COST='VR_SYSTEM ',
 WATTAGE='1/16W',
 TOLERANCE='5%',
 MATERIAL='CHIP',
 PHYS_PAGE='179',
 XY='(-1800,3650)',
 ROT='0',
 VER='1',
 PACK_TYPE='0402LF',
 LOCATION='R6276',
 CDS_LIB='pure_quanta',
 CDS_PART_NAME='Q_RES_0402LF-0,5%,1/16W,CHIP,CS00002JB13',
 GROUP='HUB_MRP',
 ROOM='USB3_HUB2_MRP',
 PART_NUMBER='CS00002JB13',
 VALUE='0',
 PRIM_FILE='./archive_libs/logical/q_res/chips/chips.prt';

PART_NAME
 R6277 'Q_RES_0402LF-10K,1%,1/16W,EMPTY,CS31002FB08':
 GROUP='HUB_MRP',
 ROOM='USB3_HUB2_MRP';

SECTION_NUMBER 1
 '@T6G_MB_LIB.T6G(SCH_1):PAGE157_I130@PURE_QUANTA.Q_RES(CHIPS)':
 C_PATH='@t6g_mb_lib.t6g(sch_1):page157_i130@pure_quanta.q_res(chips)',
 P_PATH='@t6g_mb_lib.t6g(sch_1):page179_i130@pure_quanta.q_res(chips)',
 PATH='I130',
 DRAWING='@T6G_MB_LIB.T6G(SCH_1):PAGE157',
 WATTAGE='1/16W',
 TOLERANCE='1%',
 MATERIAL='EMPTY',
 PHYS_PAGE='179',
 XY='(-525,3800)',
 ROT='0',
 VER='2',
 PACK_TYPE='0402LF',
 LOCATION='R6277',
 CDS_LIB='pure_quanta',
 CDS_PART_NAME='Q_RES_0402LF-10K,1%,1/16W,EMPTY,CS31002FB08',
 GROUP='HUB_MRP',
 ROOM='USB3_HUB2_MRP',
 PART_NUMBER='CS31002FB08',
 VALUE='10K',
 PRIM_FILE='./archive_libs/logical/q_res/chips/chips.prt';

PART_NAME
 R6278 'Q_RES_0402LF-10K,1%,1/16W,EMPTY,CS31002FB08':
 GROUP='HUB_MRP',
 ROOM='USB3_HUB2_MRP';

SECTION_NUMBER 1
 '@T6G_MB_LIB.T6G(SCH_1):PAGE157_I124@PURE_QUANTA.Q_RES(CHIPS)':
 C_PATH='@t6g_mb_lib.t6g(sch_1):page157_i124@pure_quanta.q_res(chips)',
 P_PATH='@t6g_mb_lib.t6g(sch_1):page179_i124@pure_quanta.q_res(chips)',
 PATH='I124',
 DRAWING='@T6G_MB_LIB.T6G(SCH_1):PAGE157',
 WATTAGE='1/16W',
 TOLERANCE='1%',
 MATERIAL='EMPTY',
 PHYS_PAGE='179',
 XY='(-525,3375)',
 ROT='0',
 VER='2',
 PACK_TYPE='0402LF',
 LOCATION='R6278',
 CDS_LIB='pure_quanta',
 CDS_PART_NAME='Q_RES_0402LF-10K,1%,1/16W,EMPTY,CS31002FB08',
 GROUP='HUB_MRP',
 ROOM='USB3_HUB2_MRP',
 PART_NUMBER='CS31002FB08',
 VALUE='10K',
 PRIM_FILE='./archive_libs/logical/q_res/chips/chips.prt';

PART_NAME
 R6279 'Q_RES_0402LF-0,5%,1/16W,CHIP,CS00002JB13':
 GROUP='HUB_TI',
 ROOM='USB3_HUB2_TI';

SECTION_NUMBER 1
 '@T6G_MB_LIB.T6G(SCH_1):PAGE157_I148@PURE_QUANTA.Q_RES(CHIPS)':
 C_PATH='@t6g_mb_lib.t6g(sch_1):page157_i148@pure_quanta.q_res(chips)',
 P_PATH='@t6g_mb_lib.t6g(sch_1):page179_i148@pure_quanta.q_res(chips)',
 PATH='I148',
 DRAWING='@T6G_MB_LIB.T6G(SCH_1):PAGE157',
 BOM_COST='VR_SYSTEM ',
 WATTAGE='1/16W',
 TOLERANCE='5%',
 MATERIAL='CHIP',
 PHYS_PAGE='179',
 XY='(-6775,5475)',
 ROT='0',
 VER='1',
 PACK_TYPE='0402LF',
 LOCATION='R6279',
 CDS_LIB='pure_quanta',
 CDS_PART_NAME='Q_RES_0402LF-0,5%,1/16W,CHIP,CS00002JB13',
 GROUP='HUB_TI',
 ROOM='USB3_HUB2_TI',
 PART_NUMBER='CS00002JB13',
 VALUE='0',
 PRIM_FILE='./archive_libs/logical/q_res/chips/chips.prt';

PART_NAME
 R6280 'Q_RES_0402LF-0,5%,1/16W,CHIP,CS00002JB13':
 GROUP='HUB_TI',
 ROOM='USB3_HUB2_TI';

SECTION_NUMBER 1
 '@T6G_MB_LIB.T6G(SCH_1):PAGE157_I146@PURE_QUANTA.Q_RES(CHIPS)':
 C_PATH='@t6g_mb_lib.t6g(sch_1):page157_i146@pure_quanta.q_res(chips)',
 P_PATH='@t6g_mb_lib.t6g(sch_1):page179_i146@pure_quanta.q_res(chips)',
 PATH='I146',
 DRAWING='@T6G_MB_LIB.T6G(SCH_1):PAGE157',
 BOM_COST='VR_SYSTEM ',
 WATTAGE='1/16W',
 TOLERANCE='5%',
 MATERIAL='CHIP',
 PHYS_PAGE='179',
 XY='(-6800,5275)',
 ROT='0',
 VER='1',
 PACK_TYPE='0402LF',
 LOCATION='R6280',
 CDS_LIB='pure_quanta',
 CDS_PART_NAME='Q_RES_0402LF-0,5%,1/16W,CHIP,CS00002JB13',
 GROUP='HUB_TI',
 ROOM='USB3_HUB2_TI',
 PART_NUMBER='CS00002JB13',
 VALUE='0',
 PRIM_FILE='./archive_libs/logical/q_res/chips/chips.prt';

PART_NAME
 R6281 'Q_RES_0402LF-1K,1%,1/16W,EMPTY,CS21002FB06':
 ROOM='USB3_HUB2_TI';

SECTION_NUMBER 1
 '@T6G_MB_LIB.T6G(SCH_1):PAGE157_I139@PURE_QUANTA.Q_RES(CHIPS)':
 C_PATH='@t6g_mb_lib.t6g(sch_1):page157_i139@pure_quanta.q_res(chips)',
 P_PATH='@t6g_mb_lib.t6g(sch_1):page179_i139@pure_quanta.q_res(chips)',
 PATH='I139',
 DRAWING='@T6G_MB_LIB.T6G(SCH_1):PAGE157',
 WATTAGE='1/16W',
 TOLERANCE='1%',
 MATERIAL='EMPTY',
 PHYS_PAGE='179',
 XY='(-8850,5500)',
 ROT='0',
 VER='2',
 PACK_TYPE='0402LF',
 LOCATION='R6281',
 CDS_LIB='pure_quanta',
 CDS_PART_NAME='Q_RES_0402LF-1K,1%,1/16W,EMPTY,CS21002FB06',
 ROOM='USB3_HUB2_TI',
 PART_NUMBER='CS21002FB06',
 VALUE='1K',
 PRIM_FILE='./archive_libs/logical/q_res/chips/chips.prt';

PART_NAME
 R6282 'Q_RES_0402LF-1K,1%,1/16W,EMPTY,CS21002FB06':
 GROUP='HUB_TI',
 ROOM='USB3_HUB2_TI';

SECTION_NUMBER 1
 '@T6G_MB_LIB.T6G(SCH_1):PAGE157_I138@PURE_QUANTA.Q_RES(CHIPS)':
 C_PATH='@t6g_mb_lib.t6g(sch_1):page157_i138@pure_quanta.q_res(chips)',
 P_PATH='@t6g_mb_lib.t6g(sch_1):page179_i138@pure_quanta.q_res(chips)',
 PATH='I138',
 DRAWING='@T6G_MB_LIB.T6G(SCH_1):PAGE157',
 WATTAGE='1/16W',
 TOLERANCE='1%',
 MATERIAL='EMPTY',
 PHYS_PAGE='179',
 XY='(-8850,5975)',
 ROT='0',
 VER='2',
 PACK_TYPE='0402LF',
 LOCATION='R6282',
 CDS_LIB='pure_quanta',
 CDS_PART_NAME='Q_RES_0402LF-1K,1%,1/16W,EMPTY,CS21002FB06',
 GROUP='HUB_TI',
 ROOM='USB3_HUB2_TI',
 PART_NUMBER='CS21002FB06',
 VALUE='1K',
 PRIM_FILE='./archive_libs/logical/q_res/chips/chips.prt';

PART_NAME
 R6283 'Q_RES_0402LF-1K,1%,1/16W,EMPTY,CS21002FB06':
 GROUP='HUB_TI',
 ROOM='USB3_HUB2_TI';

SECTION_NUMBER 1
 '@T6G_MB_LIB.T6G(SCH_1):PAGE157_I63@PURE_QUANTA.Q_RES(CHIPS)':
 C_PATH='@t6g_mb_lib.t6g(sch_1):page157_i63@pure_quanta.q_res(chips)',
 P_PATH='@t6g_mb_lib.t6g(sch_1):page179_i63@pure_quanta.q_res(chips)',
 PATH='I63',
 DRAWING='@T6G_MB_LIB.T6G(SCH_1):PAGE157',
 WATTAGE='1/16W',
 TOLERANCE='1%',
 MATERIAL='EMPTY',
 PHYS_PAGE='179',
 XY='(-8200,3925)',
 ROT='0',
 VER='2',
 PACK_TYPE='0402LF',
 LOCATION='R6283',
 CDS_LIB='pure_quanta',
 CDS_PART_NAME='Q_RES_0402LF-1K,1%,1/16W,EMPTY,CS21002FB06',
 GROUP='HUB_TI',
 ROOM='USB3_HUB2_TI',
 PART_NUMBER='CS21002FB06',
 VALUE='1K',
 PRIM_FILE='./archive_libs/logical/q_res/chips/chips.prt';

PART_NAME
 R6284 'Q_RES_0402LF-10,1%,1/16W,CHIP,CS01002FB07':
 ROOM='USB3_HUB2_TI';

SECTION_NUMBER 1
 '@T6G_MB_LIB.T6G(SCH_1):PAGE157_I171@PURE_QUANTA.Q_RES(CHIPS)':
 C_PATH='@t6g_mb_lib.t6g(sch_1):page157_i171@pure_quanta.q_res(chips)',
 P_PATH='@t6g_mb_lib.t6g(sch_1):page179_i171@pure_quanta.q_res(chips)',
 PATH='I171',
 DRAWING='@T6G_MB_LIB.T6G(SCH_1):PAGE157',
 SEC_TYPE='0402LF',
 WATTAGE='1/16W',
 TOLERANCE='1%',
 MATERIAL='CHIP',
 PHYS_PAGE='179',
 XY='(-8200,3500)',
 ROT='0',
 VER='2',
 PACK_TYPE='0402LF',
 LOCATION='R6284',
 SEC='1',
 CDS_LIB='pure_quanta',
 CDS_PART_NAME='Q_RES_0402LF-10,1%,1/16W,CHIP,CS01002FB07',
 ROOM='USB3_HUB2_TI',
 PART_NUMBER='CS01002FB07',
 VALUE='10',
 PRIM_FILE='./archive_libs/logical/q_res/chips/chips.prt';

PART_NAME
 R6285 'Q_RES_0402LF-0,5%,1/16W,CHIP,CS00002JB13':
 GROUP='HUB_TI',
 ROOM='USB3_HUB2_TI';

SECTION_NUMBER 1
 '@T6G_MB_LIB.T6G(SCH_1):PAGE155_I192@PURE_QUANTA.Q_RES(CHIPS)':
 C_PATH='@t6g_mb_lib.t6g(sch_1):page155_i192@pure_quanta.q_res(chips)',
 P_PATH='@t6g_mb_lib.t6g(sch_1):page178_i192@pure_quanta.q_res(chips)',
 PATH='I192',
 DRAWING='@T6G_MB_LIB.T6G(SCH_1):PAGE155',
 BOM_COST='VR_SYSTEM ',
 WATTAGE='1/16W',
 TOLERANCE='5%',
 MATERIAL='CHIP',
 PHYS_PAGE='178',
 XY='(-7850,5100)',
 ROT='0',
 VER='1',
 PACK_TYPE='0402LF',
 LOCATION='R6285',
 CDS_LIB='pure_quanta',
 CDS_PART_NAME='Q_RES_0402LF-0,5%,1/16W,CHIP,CS00002JB13',
 GROUP='HUB_TI',
 ROOM='USB3_HUB2_TI',
 PART_NUMBER='CS00002JB13',
 VALUE='0',
 PRIM_FILE='./archive_libs/logical/q_res/chips/chips.prt';

PART_NAME
 R6286 'Q_RES_0402LF-0,5%,1/16W,CHIP,CS00002JB13':
 GROUP='HUB_MRP',
 ROOM='USB3_HUB2_MRP';

SECTION_NUMBER 1
 '@T6G_MB_LIB.T6G(SCH_1):PAGE155_I193@PURE_QUANTA.Q_RES(CHIPS)':
 C_PATH='@t6g_mb_lib.t6g(sch_1):page155_i193@pure_quanta.q_res(chips)',
 P_PATH='@t6g_mb_lib.t6g(sch_1):page178_i193@pure_quanta.q_res(chips)',
 PATH='I193',
 DRAWING='@T6G_MB_LIB.T6G(SCH_1):PAGE155',
 BOM_COST='VR_SYSTEM ',
 WATTAGE='1/16W',
 TOLERANCE='5%',
 MATERIAL='CHIP',
 PHYS_PAGE='178',
 XY='(-7825,4625)',
 ROT='0',
 VER='1',
 PACK_TYPE='0402LF',
 LOCATION='R6286',
 CDS_LIB='pure_quanta',
 CDS_PART_NAME='Q_RES_0402LF-0,5%,1/16W,CHIP,CS00002JB13',
 GROUP='HUB_MRP',
 ROOM='USB3_HUB2_MRP',
 PART_NUMBER='CS00002JB13',
 VALUE='0',
 PRIM_FILE='./archive_libs/logical/q_res/chips/chips.prt';

PART_NAME
 R6287 'Q_RES_0402LF-1K,1%,1/16W,CHIP,CS21002FB06':
 GROUP='HUB_TI',
 ROOM='USB3_HUB2_TI';

SECTION_NUMBER 1
 '@T6G_MB_LIB.T6G(SCH_1):PAGE155_I197@PURE_QUANTA.Q_RES(CHIPS)':
 C_PATH='@t6g_mb_lib.t6g(sch_1):page155_i197@pure_quanta.q_res(chips)',
 P_PATH='@t6g_mb_lib.t6g(sch_1):page178_i197@pure_quanta.q_res(chips)',
 PATH='I197',
 DRAWING='@T6G_MB_LIB.T6G(SCH_1):PAGE155',
 WATTAGE='1/16W',
 TOLERANCE='1%',
 MATERIAL='CHIP',
 PHYS_PAGE='178',
 XY='(-8675,5250)',
 ROT='0',
 VER='2',
 PACK_TYPE='0402LF',
 LOCATION='R6287',
 CDS_LIB='pure_quanta',
 CDS_PART_NAME='Q_RES_0402LF-1K,1%,1/16W,CHIP,CS21002FB06',
 GROUP='HUB_TI',
 ROOM='USB3_HUB2_TI',
 PART_NUMBER='CS21002FB06',
 VALUE='1K',
 PRIM_FILE='./archive_libs/logical/q_res/chips/chips.prt';

PART_NAME
 R6288 'Q_RES_0402LF-1K,1%,1/16W,EMPTY,CS21002FB06':
 GROUP='HUB_TI',
 ROOM='USB3_HUB2_TI';

SECTION_NUMBER 1
 '@T6G_MB_LIB.T6G(SCH_1):PAGE155_I198@PURE_QUANTA.Q_RES(CHIPS)':
 C_PATH='@t6g_mb_lib.t6g(sch_1):page155_i198@pure_quanta.q_res(chips)',
 P_PATH='@t6g_mb_lib.t6g(sch_1):page178_i198@pure_quanta.q_res(chips)',
 PATH='I198',
 DRAWING='@T6G_MB_LIB.T6G(SCH_1):PAGE155',
 WATTAGE='1/16W',
 TOLERANCE='1%',
 MATERIAL='EMPTY',
 PHYS_PAGE='178',
 XY='(-8675,4975)',
 ROT='0',
 VER='2',
 PACK_TYPE='0402LF',
 LOCATION='R6288',
 CDS_LIB='pure_quanta',
 CDS_PART_NAME='Q_RES_0402LF-1K,1%,1/16W,EMPTY,CS21002FB06',
 GROUP='HUB_TI',
 ROOM='USB3_HUB2_TI',
 PART_NUMBER='CS21002FB06',
 VALUE='1K',
 PRIM_FILE='./archive_libs/logical/q_res/chips/chips.prt';

PART_NAME
 R6289 'Q_RES_0402LF-10K,1%,1/16W,CHIP,CS31002FB08':
 GROUP='HUB_MRP',
 ROOM='USB3_HUB2_MRP';

SECTION_NUMBER 1
 '@T6G_MB_LIB.T6G(SCH_1):PAGE155_I195@PURE_QUANTA.Q_RES(CHIPS)':
 C_PATH='@t6g_mb_lib.t6g(sch_1):page155_i195@pure_quanta.q_res(chips)',
 P_PATH='@t6g_mb_lib.t6g(sch_1):page178_i195@pure_quanta.q_res(chips)',
 PATH='I195',
 DRAWING='@T6G_MB_LIB.T6G(SCH_1):PAGE155',
 WATTAGE='1/16W',
 TOLERANCE='1%',
 MATERIAL='CHIP',
 PHYS_PAGE='178',
 XY='(-9175,4850)',
 ROT='2',
 VER='2',
 PACK_TYPE='0402LF',
 LOCATION='R6289',
 CDS_LIB='pure_quanta',
 CDS_PART_NAME='Q_RES_0402LF-10K,1%,1/16W,CHIP,CS31002FB08',
 GROUP='HUB_MRP',
 ROOM='USB3_HUB2_MRP',
 PART_NUMBER='CS31002FB08',
 VALUE='10K',
 PRIM_FILE='./archive_libs/logical/q_res/chips/chips.prt';

PART_NAME
 R6290 'Q_RES_0402LF-0,5%,1/16W,CHIP,CS00002JB13':
 GROUP='HUB_TI',
 ROOM='USB3_HUB2_TI';

SECTION_NUMBER 1
 '@T6G_MB_LIB.T6G(SCH_1):PAGE157_I76@PURE_QUANTA.Q_RES(CHIPS)':
 C_PATH='@t6g_mb_lib.t6g(sch_1):page157_i76@pure_quanta.q_res(chips)',
 P_PATH='@t6g_mb_lib.t6g(sch_1):page179_i76@pure_quanta.q_res(chips)',
 PATH='I76',
 DRAWING='@T6G_MB_LIB.T6G(SCH_1):PAGE157',
 BOM_COST='VR_SYSTEM ',
 WATTAGE='1/16W',
 TOLERANCE='5%',
 MATERIAL='CHIP',
 PHYS_PAGE='179',
 XY='(-3575,2725)',
 ROT='0',
 VER='1',
 PACK_TYPE='0402LF',
 LOCATION='R6290',
 CDS_LIB='pure_quanta',
 CDS_PART_NAME='Q_RES_0402LF-0,5%,1/16W,CHIP,CS00002JB13',
 GROUP='HUB_TI',
 ROOM='USB3_HUB2_TI',
 PART_NUMBER='CS00002JB13',
 VALUE='0',
 PRIM_FILE='./archive_libs/logical/q_res/chips/chips.prt';

PART_NAME
 R6291 'Q_RES_0402LF-0,5%,1/16W,CHIP,CS00002JB13':
 GROUP='HUB_MRP',
 ROOM='USB3_HUB2_MRP';

SECTION_NUMBER 1
 '@T6G_MB_LIB.T6G(SCH_1):PAGE157_I75@PURE_QUANTA.Q_RES(CHIPS)':
 C_PATH='@t6g_mb_lib.t6g(sch_1):page157_i75@pure_quanta.q_res(chips)',
 P_PATH='@t6g_mb_lib.t6g(sch_1):page179_i75@pure_quanta.q_res(chips)',
 PATH='I75',
 DRAWING='@T6G_MB_LIB.T6G(SCH_1):PAGE157',
 BOM_COST='VR_SYSTEM ',
 WATTAGE='1/16W',
 TOLERANCE='5%',
 MATERIAL='CHIP',
 PHYS_PAGE='179',
 XY='(-3550,2300)',
 ROT='0',
 VER='1',
 PACK_TYPE='0402LF',
 LOCATION='R6291',
 CDS_LIB='pure_quanta',
 CDS_PART_NAME='Q_RES_0402LF-0,5%,1/16W,CHIP,CS00002JB13',
 GROUP='HUB_MRP',
 ROOM='USB3_HUB2_MRP',
 PART_NUMBER='CS00002JB13',
 VALUE='0',
 PRIM_FILE='./archive_libs/logical/q_res/chips/chips.prt';

PART_NAME
 R6292 'Q_RES_0402LF-1K,1%,1/16W,EMPTY,CS21002FB06':
 GROUP='HUB_TI',
 ROOM='USB3_HUB2_TI';

SECTION_NUMBER 1
 '@T6G_MB_LIB.T6G(SCH_1):PAGE157_I77@PURE_QUANTA.Q_RES(CHIPS)':
 C_PATH='@t6g_mb_lib.t6g(sch_1):page157_i77@pure_quanta.q_res(chips)',
 P_PATH='@t6g_mb_lib.t6g(sch_1):page179_i77@pure_quanta.q_res(chips)',
 PATH='I77',
 DRAWING='@T6G_MB_LIB.T6G(SCH_1):PAGE157',
 WATTAGE='1/16W',
 TOLERANCE='1%',
 MATERIAL='EMPTY',
 PHYS_PAGE='179',
 XY='(-1925,3000)',
 ROT='0',
 VER='2',
 PACK_TYPE='0402LF',
 LOCATION='R6292',
 CDS_LIB='pure_quanta',
 CDS_PART_NAME='Q_RES_0402LF-1K,1%,1/16W,EMPTY,CS21002FB06',
 GROUP='HUB_TI',
 ROOM='USB3_HUB2_TI',
 PART_NUMBER='CS21002FB06',
 VALUE='1K',
 PRIM_FILE='./archive_libs/logical/q_res/chips/chips.prt';

PART_NAME
 R6293 'Q_RES_0402LF-4.7K,1%,1/16W,CHIP,CS24702FB06':
 GROUP='HUB_TI',
 ROOM='USB3_HUB2_TI';

SECTION_NUMBER 1
 '@T6G_MB_LIB.T6G(SCH_1):PAGE157_I79@PURE_QUANTA.Q_RES(CHIPS)':
 C_PATH='@t6g_mb_lib.t6g(sch_1):page157_i79@pure_quanta.q_res(chips)',
 P_PATH='@t6g_mb_lib.t6g(sch_1):page179_i79@pure_quanta.q_res(chips)',
 PATH='I79',
 DRAWING='@T6G_MB_LIB.T6G(SCH_1):PAGE157',
 WATTAGE='1/16W',
 TOLERANCE='1%',
 MATERIAL='CHIP',
 PHYS_PAGE='179',
 XY='(-1925,2525)',
 ROT='0',
 VER='2',
 PACK_TYPE='0402LF',
 LOCATION='R6293',
 CDS_LIB='pure_quanta',
 CDS_PART_NAME='Q_RES_0402LF-4.7K,1%,1/16W,CHIP,CS24702FB06',
 GROUP='HUB_TI',
 ROOM='USB3_HUB2_TI',
 PART_NUMBER='CS24702FB06',
 VALUE='4.7K',
 PRIM_FILE='./archive_libs/logical/q_res/chips/chips.prt';

PART_NAME
 R6294 'Q_RES_0402LF-10K,1%,1/16W,CHIP,CS31002FB08':
 GROUP='HUB_MRP',
 ROOM='USB3_HUB2_MRP';

SECTION_NUMBER 1
 '@T6G_MB_LIB.T6G(SCH_1):PAGE157_I81@PURE_QUANTA.Q_RES(CHIPS)':
 C_PATH='@t6g_mb_lib.t6g(sch_1):page157_i81@pure_quanta.q_res(chips)',
 P_PATH='@t6g_mb_lib.t6g(sch_1):page179_i81@pure_quanta.q_res(chips)',
 PATH='I81',
 DRAWING='@T6G_MB_LIB.T6G(SCH_1):PAGE157',
 WATTAGE='1/16W',
 TOLERANCE='1%',
 MATERIAL='CHIP',
 PHYS_PAGE='179',
 XY='(-2400,2425)',
 ROT='0',
 VER='2',
 PACK_TYPE='0402LF',
 LOCATION='R6294',
 CDS_LIB='pure_quanta',
 CDS_PART_NAME='Q_RES_0402LF-10K,1%,1/16W,CHIP,CS31002FB08',
 GROUP='HUB_MRP',
 ROOM='USB3_HUB2_MRP',
 PART_NUMBER='CS31002FB08',
 VALUE='10K',
 PRIM_FILE='./archive_libs/logical/q_res/chips/chips.prt';

PART_NAME
 R6295 'Q_RES_0402LF-0,5%,1/16W,CHIP,CS00002JB13':
 GROUP='HUB_TI',
 ROOM='USB3_HUB2_TI';

SECTION_NUMBER 1
 '@T6G_MB_LIB.T6G(SCH_1):PAGE155_I182@PURE_QUANTA.Q_RES(CHIPS)':
 C_PATH='@t6g_mb_lib.t6g(sch_1):page155_i182@pure_quanta.q_res(chips)',
 P_PATH='@t6g_mb_lib.t6g(sch_1):page178_i182@pure_quanta.q_res(chips)',
 PATH='I182',
 DRAWING='@T6G_MB_LIB.T6G(SCH_1):PAGE155',
 BOM_COST='VR_SYSTEM ',
 WATTAGE='1/16W',
 TOLERANCE='5%',
 MATERIAL='CHIP',
 PHYS_PAGE='178',
 XY='(-6500,1725)',
 ROT='0',
 VER='1',
 PACK_TYPE='0402LF',
 LOCATION='R6295',
 CDS_LIB='pure_quanta',
 CDS_PART_NAME='Q_RES_0402LF-0,5%,1/16W,CHIP,CS00002JB13',
 GROUP='HUB_TI',
 ROOM='USB3_HUB2_TI',
 PART_NUMBER='CS00002JB13',
 VALUE='0',
 PRIM_FILE='./archive_libs/logical/q_res/chips/chips.prt';

PART_NAME
 R6296 'Q_RES_0402LF-0,5%,1/16W,CHIP,CS00002JB13':
 GROUP='HUB_MRP',
 ROOM='USB3_HUB2_MRP';

SECTION_NUMBER 1
 '@T6G_MB_LIB.T6G(SCH_1):PAGE155_I183@PURE_QUANTA.Q_RES(CHIPS)':
 C_PATH='@t6g_mb_lib.t6g(sch_1):page155_i183@pure_quanta.q_res(chips)',
 P_PATH='@t6g_mb_lib.t6g(sch_1):page178_i183@pure_quanta.q_res(chips)',
 PATH='I183',
 DRAWING='@T6G_MB_LIB.T6G(SCH_1):PAGE155',
 BOM_COST='VR_SYSTEM ',
 WATTAGE='1/16W',
 TOLERANCE='5%',
 MATERIAL='CHIP',
 PHYS_PAGE='178',
 XY='(-6475,1600)',
 ROT='0',
 VER='1',
 PACK_TYPE='0402LF',
 LOCATION='R6296',
 CDS_LIB='pure_quanta',
 CDS_PART_NAME='Q_RES_0402LF-0,5%,1/16W,CHIP,CS00002JB13',
 GROUP='HUB_MRP',
 ROOM='USB3_HUB2_MRP',
 PART_NUMBER='CS00002JB13',
 VALUE='0',
 PRIM_FILE='./archive_libs/logical/q_res/chips/chips.prt';

PART_NAME
 R6297 'Q_RES_0402LF-10K,1%,1/16W,CHIP,CS31002FB08':
 GROUP='HUB_TI',
 ROOM='USB3_HUB2_TI';

SECTION_NUMBER 1
 '@T6G_MB_LIB.T6G(SCH_1):PAGE155_I185@PURE_QUANTA.Q_RES(CHIPS)':
 C_PATH='@t6g_mb_lib.t6g(sch_1):page155_i185@pure_quanta.q_res(chips)',
 P_PATH='@t6g_mb_lib.t6g(sch_1):page178_i185@pure_quanta.q_res(chips)',
 PATH='I185',
 DRAWING='@T6G_MB_LIB.T6G(SCH_1):PAGE155',
 WATTAGE='1/16W',
 TOLERANCE='1%',
 MATERIAL='CHIP',
 PHYS_PAGE='178',
 XY='(-7575,1925)',
 ROT='2',
 VER='2',
 PACK_TYPE='0402LF',
 LOCATION='R6297',
 CDS_LIB='pure_quanta',
 CDS_PART_NAME='Q_RES_0402LF-10K,1%,1/16W,CHIP,CS31002FB08',
 GROUP='HUB_TI',
 ROOM='USB3_HUB2_TI',
 PART_NUMBER='CS31002FB08',
 VALUE='10K',
 PRIM_FILE='./archive_libs/logical/q_res/chips/chips.prt';

PART_NAME
 R6298 'Q_RES_0402LF-10K,1%,1/16W,CHIP,CS31002FB08':
 GROUP='HUB_MRP',
 ROOM='USB3_HUB2_MRP';

SECTION_NUMBER 1
 '@T6G_MB_LIB.T6G(SCH_1):PAGE155_I187@PURE_QUANTA.Q_RES(CHIPS)':
 C_PATH='@t6g_mb_lib.t6g(sch_1):page155_i187@pure_quanta.q_res(chips)',
 P_PATH='@t6g_mb_lib.t6g(sch_1):page178_i187@pure_quanta.q_res(chips)',
 PATH='I187',
 DRAWING='@T6G_MB_LIB.T6G(SCH_1):PAGE155',
 WATTAGE='1/16W',
 TOLERANCE='1%',
 MATERIAL='CHIP',
 PHYS_PAGE='178',
 XY='(-8025,1925)',
 ROT='0',
 VER='2',
 PACK_TYPE='0402LF',
 LOCATION='R6298',
 CDS_LIB='pure_quanta',
 CDS_PART_NAME='Q_RES_0402LF-10K,1%,1/16W,CHIP,CS31002FB08',
 GROUP='HUB_MRP',
 ROOM='USB3_HUB2_MRP',
 PART_NUMBER='CS31002FB08',
 VALUE='10K',
 PRIM_FILE='./archive_libs/logical/q_res/chips/chips.prt';

PART_NAME
 R6299 'Q_RES_0402LF-0,5%,1/16W,CHIP,CS00002JB13':
 GROUP='HUB_TI',
 ROOM='USB3_HUB2_TI';

SECTION_NUMBER 1
 '@T6G_MB_LIB.T6G(SCH_1):PAGE155_I180@PURE_QUANTA.Q_RES(CHIPS)':
 C_PATH='@t6g_mb_lib.t6g(sch_1):page155_i180@pure_quanta.q_res(chips)',
 P_PATH='@t6g_mb_lib.t6g(sch_1):page178_i180@pure_quanta.q_res(chips)',
 PATH='I180',
 DRAWING='@T6G_MB_LIB.T6G(SCH_1):PAGE155',
 BOM_COST='VR_SYSTEM ',
 WATTAGE='1/16W',
 TOLERANCE='5%',
 MATERIAL='CHIP',
 PHYS_PAGE='178',
 XY='(-6925,2450)',
 ROT='0',
 VER='1',
 PACK_TYPE='0402LF',
 LOCATION='R6299',
 CDS_LIB='pure_quanta',
 CDS_PART_NAME='Q_RES_0402LF-0,5%,1/16W,CHIP,CS00002JB13',
 GROUP='HUB_TI',
 ROOM='USB3_HUB2_TI',
 PART_NUMBER='CS00002JB13',
 VALUE='0',
 PRIM_FILE='./archive_libs/logical/q_res/chips/chips.prt';

PART_NAME
 R6300 'Q_RES_0402LF-0,5%,1/16W,CHIP,CS00002JB13':
 GROUP='HUB_MRP',
 ROOM='USB3_HUB2_MRP';

SECTION_NUMBER 1
 '@T6G_MB_LIB.T6G(SCH_1):PAGE155_I181@PURE_QUANTA.Q_RES(CHIPS)':
 C_PATH='@t6g_mb_lib.t6g(sch_1):page155_i181@pure_quanta.q_res(chips)',
 P_PATH='@t6g_mb_lib.t6g(sch_1):page178_i181@pure_quanta.q_res(chips)',
 PATH='I181',
 DRAWING='@T6G_MB_LIB.T6G(SCH_1):PAGE155',
 BOM_COST='VR_SYSTEM ',
 WATTAGE='1/16W',
 TOLERANCE='5%',
 MATERIAL='CHIP',
 PHYS_PAGE='178',
 XY='(-7000,2325)',
 ROT='0',
 VER='1',
 PACK_TYPE='0402LF',
 LOCATION='R6300',
 CDS_LIB='pure_quanta',
 CDS_PART_NAME='Q_RES_0402LF-0,5%,1/16W,CHIP,CS00002JB13',
 GROUP='HUB_MRP',
 ROOM='USB3_HUB2_MRP',
 PART_NUMBER='CS00002JB13',
 VALUE='0',
 PRIM_FILE='./archive_libs/logical/q_res/chips/chips.prt';

PART_NAME
 R6301 'Q_RES_0402LF-10K,1%,1/16W,CHIP,CS31002FB08':
 GROUP='HUB_TI',
 ROOM='USB3_HUB2_TI';

SECTION_NUMBER 1
 '@T6G_MB_LIB.T6G(SCH_1):PAGE155_I179@PURE_QUANTA.Q_RES(CHIPS)':
 C_PATH='@t6g_mb_lib.t6g(sch_1):page155_i179@pure_quanta.q_res(chips)',
 P_PATH='@t6g_mb_lib.t6g(sch_1):page178_i179@pure_quanta.q_res(chips)',
 PATH='I179',
 DRAWING='@T6G_MB_LIB.T6G(SCH_1):PAGE155',
 WATTAGE='1/16W',
 TOLERANCE='1%',
 MATERIAL='CHIP',
 PHYS_PAGE='178',
 XY='(-9200,3075)',
 ROT='2',
 VER='2',
 PACK_TYPE='0402LF',
 LOCATION='R6301',
 CDS_LIB='pure_quanta',
 CDS_PART_NAME='Q_RES_0402LF-10K,1%,1/16W,CHIP,CS31002FB08',
 GROUP='HUB_TI',
 ROOM='USB3_HUB2_TI',
 PART_NUMBER='CS31002FB08',
 VALUE='10K',
 PRIM_FILE='./archive_libs/logical/q_res/chips/chips.prt';

PART_NAME
 R6302 'Q_RES_0402LF-200K,1%,1/16W,CHIP,CS42002FB05':
 GROUP='HUB_MRP',
 ROOM='USB3_HUB2_MRP';

SECTION_NUMBER 1
 '@T6G_MB_LIB.T6G(SCH_1):PAGE155_I175@PURE_QUANTA.Q_RES(CHIPS)':
 C_PATH='@t6g_mb_lib.t6g(sch_1):page155_i175@pure_quanta.q_res(chips)',
 P_PATH='@t6g_mb_lib.t6g(sch_1):page178_i175@pure_quanta.q_res(chips)',
 PATH='I175',
 DRAWING='@T6G_MB_LIB.T6G(SCH_1):PAGE155',
 WATTAGE='1/16W',
 TOLERANCE='1%',
 MATERIAL='CHIP',
 PHYS_PAGE='178',
 XY='(-9075,1650)',
 ROT='0',
 VER='2',
 PACK_TYPE='0402LF',
 LOCATION='R6302',
 CDS_LIB='pure_quanta',
 CDS_PART_NAME='Q_RES_0402LF-200K,1%,1/16W,CHIP,CS42002FB05',
 GROUP='HUB_MRP',
 ROOM='USB3_HUB2_MRP',
 PART_NUMBER='CS42002FB05',
 VALUE='200K',
 PRIM_FILE='./archive_libs/logical/q_res/chips/chips.prt';

PART_NAME
 R6303 'Q_RES_0402LF-200K,1%,1/16W,EMPTY,CS42002FB05':
 GROUP='HUB_MRP',
 ROOM='USB3_HUB2_MRP';

SECTION_NUMBER 1
 '@T6G_MB_LIB.T6G(SCH_1):PAGE155_I169@PURE_QUANTA.Q_RES(CHIPS)':
 C_PATH='@t6g_mb_lib.t6g(sch_1):page155_i169@pure_quanta.q_res(chips)',
 P_PATH='@t6g_mb_lib.t6g(sch_1):page178_i169@pure_quanta.q_res(chips)',
 PATH='I169',
 DRAWING='@T6G_MB_LIB.T6G(SCH_1):PAGE155',
 WATTAGE='1/16W',
 TOLERANCE='1%',
 MATERIAL='EMPTY',
 PHYS_PAGE='178',
 XY='(-9075,2125)',
 ROT='0',
 VER='2',
 PACK_TYPE='0402LF',
 LOCATION='R6303',
 CDS_LIB='pure_quanta',
 CDS_PART_NAME='Q_RES_0402LF-200K,1%,1/16W,EMPTY,CS42002FB05',
 GROUP='HUB_MRP',
 ROOM='USB3_HUB2_MRP',
 PART_NUMBER='CS42002FB05',
 VALUE='200K',
 PRIM_FILE='./archive_libs/logical/q_res/chips/chips.prt';

PART_NAME
 R6304 'Q_RES_0402LF-0,5%,1/16W,CHIP,CS00002JB13':
 GROUP='HUB_TI',
 ROOM='USB3_HUB2_TI';

SECTION_NUMBER 1
 '@T6G_MB_LIB.T6G(SCH_1):PAGE157_I151@PURE_QUANTA.Q_RES(CHIPS)':
 C_PATH='@t6g_mb_lib.t6g(sch_1):page157_i151@pure_quanta.q_res(chips)',
 P_PATH='@t6g_mb_lib.t6g(sch_1):page179_i151@pure_quanta.q_res(chips)',
 PATH='I151',
 DRAWING='@T6G_MB_LIB.T6G(SCH_1):PAGE157',
 BOM_COST='VR_SYSTEM ',
 WATTAGE='1/16W',
 TOLERANCE='5%',
 MATERIAL='CHIP',
 PHYS_PAGE='179',
 XY='(-7450,4925)',
 ROT='0',
 VER='1',
 PACK_TYPE='0402LF',
 LOCATION='R6304',
 CDS_LIB='pure_quanta',
 CDS_PART_NAME='Q_RES_0402LF-0,5%,1/16W,CHIP,CS00002JB13',
 GROUP='HUB_TI',
 ROOM='USB3_HUB2_TI',
 PART_NUMBER='CS00002JB13',
 VALUE='0',
 PRIM_FILE='./archive_libs/logical/q_res/chips/chips.prt';

PART_NAME
 R6305 'Q_RES_0402LF-0,5%,1/16W,CHIP,CS00002JB13':
 GROUP='HUB_MRP',
 ROOM='USB3_HUB2_MRP';

SECTION_NUMBER 1
 '@T6G_MB_LIB.T6G(SCH_1):PAGE157_I150@PURE_QUANTA.Q_RES(CHIPS)':
 C_PATH='@t6g_mb_lib.t6g(sch_1):page157_i150@pure_quanta.q_res(chips)',
 P_PATH='@t6g_mb_lib.t6g(sch_1):page179_i150@pure_quanta.q_res(chips)',
 PATH='I150',
 DRAWING='@T6G_MB_LIB.T6G(SCH_1):PAGE157',
 BOM_COST='VR_SYSTEM ',
 WATTAGE='1/16W',
 TOLERANCE='5%',
 MATERIAL='CHIP',
 PHYS_PAGE='179',
 XY='(-7450,4750)',
 ROT='0',
 VER='1',
 PACK_TYPE='0402LF',
 LOCATION='R6305',
 CDS_LIB='pure_quanta',
 CDS_PART_NAME='Q_RES_0402LF-0,5%,1/16W,CHIP,CS00002JB13',
 GROUP='HUB_MRP',
 ROOM='USB3_HUB2_MRP',
 PART_NUMBER='CS00002JB13',
 VALUE='0',
 PRIM_FILE='./archive_libs/logical/q_res/chips/chips.prt';

PART_NAME
 R6306 'Q_RES_0402LF-4.7K,1%,1/16W,CHIP,CS24702FB06':
 GROUP='HUB_TI',
 ROOM='USB3_HUB2_TI';

SECTION_NUMBER 1
 '@T6G_MB_LIB.T6G(SCH_1):PAGE157_I155@PURE_QUANTA.Q_RES(CHIPS)':
 C_PATH='@t6g_mb_lib.t6g(sch_1):page157_i155@pure_quanta.q_res(chips)',
 P_PATH='@t6g_mb_lib.t6g(sch_1):page179_i155@pure_quanta.q_res(chips)',
 PATH='I155',
 DRAWING='@T6G_MB_LIB.T6G(SCH_1):PAGE157',
 WATTAGE='1/16W',
 TOLERANCE='1%',
 MATERIAL='CHIP',
 PHYS_PAGE='179',
 XY='(-9125,5150)',
 ROT='0',
 VER='2',
 PACK_TYPE='0402LF',
 LOCATION='R6306',
 CDS_LIB='pure_quanta',
 CDS_PART_NAME='Q_RES_0402LF-4.7K,1%,1/16W,CHIP,CS24702FB06',
 GROUP='HUB_TI',
 ROOM='USB3_HUB2_TI',
 PART_NUMBER='CS24702FB06',
 VALUE='4.7K',
 PRIM_FILE='./archive_libs/logical/q_res/chips/chips.prt';

PART_NAME
 R6307 'Q_RES_0402LF-4.7K,1%,1/16W,EMPTY,CS24702FB06':
 GROUP='HUB_TI',
 ROOM='USB3_HUB2_TI';

SECTION_NUMBER 1
 '@T6G_MB_LIB.T6G(SCH_1):PAGE157_I156@PURE_QUANTA.Q_RES(CHIPS)':
 C_PATH='@t6g_mb_lib.t6g(sch_1):page157_i156@pure_quanta.q_res(chips)',
 P_PATH='@t6g_mb_lib.t6g(sch_1):page179_i156@pure_quanta.q_res(chips)',
 PATH='I156',
 DRAWING='@T6G_MB_LIB.T6G(SCH_1):PAGE157',
 WATTAGE='1/16W',
 TOLERANCE='1%',
 MATERIAL='EMPTY',
 PHYS_PAGE='179',
 XY='(-9125,4725)',
 ROT='0',
 VER='2',
 PACK_TYPE='0402LF',
 LOCATION='R6307',
 CDS_LIB='pure_quanta',
 CDS_PART_NAME='Q_RES_0402LF-4.7K,1%,1/16W,EMPTY,CS24702FB06',
 GROUP='HUB_TI',
 ROOM='USB3_HUB2_TI',
 PART_NUMBER='CS24702FB06',
 VALUE='4.7K',
 PRIM_FILE='./archive_libs/logical/q_res/chips/chips.prt';

PART_NAME
 R6308 'Q_RES_0402LF-200K,1%,1/16W,EMPTY,CS42002FB05':
 GROUP='HUB_MRP',
 ROOM='USB3_HUB2_MRP';

SECTION_NUMBER 1
 '@T6G_MB_LIB.T6G(SCH_1):PAGE157_I153@PURE_QUANTA.Q_RES(CHIPS)':
 C_PATH='@t6g_mb_lib.t6g(sch_1):page157_i153@pure_quanta.q_res(chips)',
 P_PATH='@t6g_mb_lib.t6g(sch_1):page179_i153@pure_quanta.q_res(chips)',
 PATH='I153',
 DRAWING='@T6G_MB_LIB.T6G(SCH_1):PAGE157',
 WATTAGE='1/16W',
 TOLERANCE='1%',
 MATERIAL='EMPTY',
 PHYS_PAGE='179',
 XY='(-8700,4550)',
 ROT='0',
 VER='2',
 PACK_TYPE='0402LF',
 LOCATION='R6308',
 CDS_LIB='pure_quanta',
 CDS_PART_NAME='Q_RES_0402LF-200K,1%,1/16W,EMPTY,CS42002FB05',
 GROUP='HUB_MRP',
 ROOM='USB3_HUB2_MRP',
 PART_NUMBER='CS42002FB05',
 VALUE='200K',
 PRIM_FILE='./archive_libs/logical/q_res/chips/chips.prt';

PART_NAME
 R6309 'Q_RES_0402LF-200K,1%,1/16W,CHIP,CS42002FB05':
 GROUP='HUB_MRP',
 ROOM='USB3_HUB2_MRP';

SECTION_NUMBER 1
 '@T6G_MB_LIB.T6G(SCH_1):PAGE157_I158@PURE_QUANTA.Q_RES(CHIPS)':
 C_PATH='@t6g_mb_lib.t6g(sch_1):page157_i158@pure_quanta.q_res(chips)',
 P_PATH='@t6g_mb_lib.t6g(sch_1):page179_i158@pure_quanta.q_res(chips)',
 PATH='I158',
 DRAWING='@T6G_MB_LIB.T6G(SCH_1):PAGE157',
 WATTAGE='1/16W',
 TOLERANCE='1%',
 MATERIAL='CHIP',
 PHYS_PAGE='179',
 XY='(-8700,4050)',
 ROT='0',
 VER='2',
 PACK_TYPE='0402LF',
 LOCATION='R6309',
 CDS_LIB='pure_quanta',
 CDS_PART_NAME='Q_RES_0402LF-200K,1%,1/16W,CHIP,CS42002FB05',
 GROUP='HUB_MRP',
 ROOM='USB3_HUB2_MRP',
 PART_NUMBER='CS42002FB05',
 VALUE='200K',
 PRIM_FILE='./archive_libs/logical/q_res/chips/chips.prt';

PART_NAME
 R6310 'Q_RES_0402LF-0,5%,1/16W,CHIP,CS00002JB13':
 GROUP='HUB_TI',
 ROOM='USB3_HUB2_TI';

SECTION_NUMBER 1
 '@T6G_MB_LIB.T6G(SCH_1):PAGE155_I202@PURE_QUANTA.Q_RES(CHIPS)':
 C_PATH='@t6g_mb_lib.t6g(sch_1):page155_i202@pure_quanta.q_res(chips)',
 P_PATH='@t6g_mb_lib.t6g(sch_1):page178_i202@pure_quanta.q_res(chips)',
 PATH='I202',
 DRAWING='@T6G_MB_LIB.T6G(SCH_1):PAGE155',
 BOM_COST='VR_SYSTEM ',
 WATTAGE='1/16W',
 TOLERANCE='5%',
 MATERIAL='CHIP',
 PHYS_PAGE='178',
 XY='(-6900,2950)',
 ROT='0',
 VER='1',
 PACK_TYPE='0402LF',
 LOCATION='R6310',
 CDS_LIB='pure_quanta',
 CDS_PART_NAME='Q_RES_0402LF-0,5%,1/16W,CHIP,CS00002JB13',
 GROUP='HUB_TI',
 ROOM='USB3_HUB2_TI',
 PART_NUMBER='CS00002JB13',
 VALUE='0',
 PRIM_FILE='./archive_libs/logical/q_res/chips/chips.prt';

PART_NAME
 R6311 'Q_RES_0402LF-0,5%,1/16W,CHIP,CS00002JB13':
 GROUP='HUB_MRP',
 ROOM='USB3_HUB2_MRP';

SECTION_NUMBER 1
 '@T6G_MB_LIB.T6G(SCH_1):PAGE155_I200@PURE_QUANTA.Q_RES(CHIPS)':
 C_PATH='@t6g_mb_lib.t6g(sch_1):page155_i200@pure_quanta.q_res(chips)',
 P_PATH='@t6g_mb_lib.t6g(sch_1):page178_i200@pure_quanta.q_res(chips)',
 PATH='I200',
 DRAWING='@T6G_MB_LIB.T6G(SCH_1):PAGE155',
 BOM_COST='VR_SYSTEM ',
 WATTAGE='1/16W',
 TOLERANCE='5%',
 MATERIAL='CHIP',
 PHYS_PAGE='178',
 XY='(-6925,2750)',
 ROT='0',
 VER='1',
 PACK_TYPE='0402LF',
 LOCATION='R6311',
 CDS_LIB='pure_quanta',
 CDS_PART_NAME='Q_RES_0402LF-0,5%,1/16W,CHIP,CS00002JB13',
 GROUP='HUB_MRP',
 ROOM='USB3_HUB2_MRP',
 PART_NUMBER='CS00002JB13',
 VALUE='0',
 PRIM_FILE='./archive_libs/logical/q_res/chips/chips.prt';

PART_NAME
 R6312 'Q_RES_0402LF-10K,1%,1/16W,CHIP,CS31002FB08':
 GROUP='HUB_TI',
 ROOM='USB3_HUB2_TI';

SECTION_NUMBER 1
 '@T6G_MB_LIB.T6G(SCH_1):PAGE155_I205@PURE_QUANTA.Q_RES(CHIPS)':
 C_PATH='@t6g_mb_lib.t6g(sch_1):page155_i205@pure_quanta.q_res(chips)',
 P_PATH='@t6g_mb_lib.t6g(sch_1):page178_i205@pure_quanta.q_res(chips)',
 PATH='I205',
 DRAWING='@T6G_MB_LIB.T6G(SCH_1):PAGE155',
 SEC_TYPE='0402LF',
 WATTAGE='1/16W',
 TOLERANCE='1%',
 MATERIAL='CHIP',
 PHYS_PAGE='178',
 XY='(-8125,2950)',
 ROT='0',
 VER='1',
 PACK_TYPE='0402LF',
 LOCATION='R6312',
 SEC='1',
 CDS_LIB='pure_quanta',
 CDS_PART_NAME='Q_RES_0402LF-10K,1%,1/16W,CHIP,CS31002FB08',
 GROUP='HUB_TI',
 ROOM='USB3_HUB2_TI',
 PART_NUMBER='CS31002FB08',
 VALUE='10K',
 PRIM_FILE='./archive_libs/logical/q_res/chips/chips.prt';

PART_NAME
 R6313 'Q_RES_0402LF-0,5%,1/16W,CHIP,CS00002JB13':
 GROUP='HUB_TI',
 ROOM='USB3_HUB2_TI';

SECTION_NUMBER 1
 '@T6G_MB_LIB.T6G(SCH_1):PAGE155_I138@PURE_QUANTA.Q_RES(CHIPS)':
 C_PATH='@t6g_mb_lib.t6g(sch_1):page155_i138@pure_quanta.q_res(chips)',
 P_PATH='@t6g_mb_lib.t6g(sch_1):page178_i138@pure_quanta.q_res(chips)',
 PATH='I138',
 DRAWING='@T6G_MB_LIB.T6G(SCH_1):PAGE155',
 BOM_COST='VR_SYSTEM ',
 WATTAGE='1/16W',
 TOLERANCE='5%',
 MATERIAL='CHIP',
 PHYS_PAGE='178',
 XY='(-7575,2600)',
 ROT='0',
 VER='1',
 PACK_TYPE='0402LF',
 LOCATION='R6313',
 CDS_LIB='pure_quanta',
 CDS_PART_NAME='Q_RES_0402LF-0,5%,1/16W,CHIP,CS00002JB13',
 GROUP='HUB_TI',
 ROOM='USB3_HUB2_TI',
 PART_NUMBER='CS00002JB13',
 VALUE='0',
 PRIM_FILE='./archive_libs/logical/q_res/chips/chips.prt';

PART_NAME
 R6314 'Q_RES_0402LF-0,5%,1/16W,CHIP,CS00002JB13':
 GROUP='HUB_MRP',
 ROOM='USB3_HUB2_MRP';

SECTION_NUMBER 1
 '@T6G_MB_LIB.T6G(SCH_1):PAGE155_I137@PURE_QUANTA.Q_RES(CHIPS)':
 C_PATH='@t6g_mb_lib.t6g(sch_1):page155_i137@pure_quanta.q_res(chips)',
 P_PATH='@t6g_mb_lib.t6g(sch_1):page178_i137@pure_quanta.q_res(chips)',
 PATH='I137',
 DRAWING='@T6G_MB_LIB.T6G(SCH_1):PAGE155',
 BOM_COST='VR_SYSTEM ',
 WATTAGE='1/16W',
 TOLERANCE='5%',
 MATERIAL='CHIP',
 PHYS_PAGE='178',
 XY='(-7550,2525)',
 ROT='0',
 VER='1',
 PACK_TYPE='0402LF',
 LOCATION='R6314',
 CDS_LIB='pure_quanta',
 CDS_PART_NAME='Q_RES_0402LF-0,5%,1/16W,CHIP,CS00002JB13',
 GROUP='HUB_MRP',
 ROOM='USB3_HUB2_MRP',
 PART_NUMBER='CS00002JB13',
 VALUE='0',
 PRIM_FILE='./archive_libs/logical/q_res/chips/chips.prt';

PART_NAME
 R6315 'Q_RES_0402LF-10K,1%,1/16W,CHIP,CS31002FB08':
 GROUP='HUB_TI',
 ROOM='USB3_HUB2_TI';

SECTION_NUMBER 1
 '@T6G_MB_LIB.T6G(SCH_1):PAGE155_I140@PURE_QUANTA.Q_RES(CHIPS)':
 C_PATH='@t6g_mb_lib.t6g(sch_1):page155_i140@pure_quanta.q_res(chips)',
 P_PATH='@t6g_mb_lib.t6g(sch_1):page178_i140@pure_quanta.q_res(chips)',
 PATH='I140',
 DRAWING='@T6G_MB_LIB.T6G(SCH_1):PAGE155',
 WATTAGE='1/16W',
 TOLERANCE='1%',
 MATERIAL='CHIP',
 PHYS_PAGE='178',
 XY='(-8750,2950)',
 ROT='2',
 VER='2',
 PACK_TYPE='0402LF',
 LOCATION='R6315',
 CDS_LIB='pure_quanta',
 CDS_PART_NAME='Q_RES_0402LF-10K,1%,1/16W,CHIP,CS31002FB08',
 GROUP='HUB_TI',
 ROOM='USB3_HUB2_TI',
 PART_NUMBER='CS31002FB08',
 VALUE='10K',
 PRIM_FILE='./archive_libs/logical/q_res/chips/chips.prt';

PART_NAME
 R6316 'Q_RES_0402LF-0,5%,1/16W,CHIP,CS00002JB13':
 GROUP='HUB_TI',
 ROOM='USB3_HUB2_TI';

SECTION_NUMBER 1
 '@T6G_MB_LIB.T6G(SCH_1):PAGE155_I119@PURE_QUANTA.Q_RES(CHIPS)':
 C_PATH='@t6g_mb_lib.t6g(sch_1):page155_i119@pure_quanta.q_res(chips)',
 P_PATH='@t6g_mb_lib.t6g(sch_1):page178_i119@pure_quanta.q_res(chips)',
 PATH='I119',
 DRAWING='@T6G_MB_LIB.T6G(SCH_1):PAGE155',
 BOM_COST='VR_SYSTEM ',
 WATTAGE='1/16W',
 TOLERANCE='5%',
 MATERIAL='CHIP',
 PHYS_PAGE='178',
 XY='(-6975,5550)',
 ROT='0',
 VER='1',
 PACK_TYPE='0402LF',
 LOCATION='R6316',
 CDS_LIB='pure_quanta',
 CDS_PART_NAME='Q_RES_0402LF-0,5%,1/16W,CHIP,CS00002JB13',
 GROUP='HUB_TI',
 ROOM='USB3_HUB2_TI',
 PART_NUMBER='CS00002JB13',
 VALUE='0',
 PRIM_FILE='./archive_libs/logical/q_res/chips/chips.prt';

PART_NAME
 R6317 'Q_RES_0402LF-0,5%,1/16W,CHIP,CS00002JB13':
 GROUP='HUB_MRP',
 ROOM='USB3_HUB2_MRP';

SECTION_NUMBER 1
 '@T6G_MB_LIB.T6G(SCH_1):PAGE155_I124@PURE_QUANTA.Q_RES(CHIPS)':
 C_PATH='@t6g_mb_lib.t6g(sch_1):page155_i124@pure_quanta.q_res(chips)',
 P_PATH='@t6g_mb_lib.t6g(sch_1):page178_i124@pure_quanta.q_res(chips)',
 PATH='I124',
 DRAWING='@T6G_MB_LIB.T6G(SCH_1):PAGE155',
 BOM_COST='VR_SYSTEM ',
 WATTAGE='1/16W',
 TOLERANCE='5%',
 MATERIAL='CHIP',
 PHYS_PAGE='178',
 XY='(-6975,6025)',
 ROT='0',
 VER='1',
 PACK_TYPE='0402LF',
 LOCATION='R6317',
 CDS_LIB='pure_quanta',
 CDS_PART_NAME='Q_RES_0402LF-0,5%,1/16W,CHIP,CS00002JB13',
 GROUP='HUB_MRP',
 ROOM='USB3_HUB2_MRP',
 PART_NUMBER='CS00002JB13',
 VALUE='0',
 PRIM_FILE='./archive_libs/logical/q_res/chips/chips.prt';

PART_NAME
 R6318 'Q_RES_0402LF-90.9K,1%,1/16W,CHIP,CS39092FB04':
 GROUP='HUB_TI',
 ROOM='USB3_HUB2_TI';

SECTION_NUMBER 1
 '@T6G_MB_LIB.T6G(SCH_1):PAGE155_I123@PURE_QUANTA.Q_RES(CHIPS)':
 C_PATH='@t6g_mb_lib.t6g(sch_1):page155_i123@pure_quanta.q_res(chips)',
 P_PATH='@t6g_mb_lib.t6g(sch_1):page178_i123@pure_quanta.q_res(chips)',
 PATH='I123',
 DRAWING='@T6G_MB_LIB.T6G(SCH_1):PAGE155',
 WATTAGE='1/16W',
 TOLERANCE='1%',
 MATERIAL='CHIP',
 PHYS_PAGE='178',
 XY='(-9100,5750)',
 ROT='2',
 VER='2',
 PACK_TYPE='0402LF',
 LOCATION='R6318',
 CDS_LIB='pure_quanta',
 CDS_PART_NAME='Q_RES_0402LF-90.9K,1%,1/16W,CHIP,CS39092FB04',
 GROUP='HUB_TI',
 ROOM='USB3_HUB2_TI',
 PART_NUMBER='CS39092FB04',
 VALUE='90.9K',
 PRIM_FILE='./archive_libs/logical/q_res/chips/chips.prt';

PART_NAME
 R6319 'Q_RES_0402LF-10K,1%,1/16W,CHIP,CS31002FB08':
 GROUP='HUB_TI',
 ROOM='USB3_HUB2_TI';

SECTION_NUMBER 1
 '@T6G_MB_LIB.T6G(SCH_1):PAGE155_I121@PURE_QUANTA.Q_RES(CHIPS)':
 C_PATH='@t6g_mb_lib.t6g(sch_1):page155_i121@pure_quanta.q_res(chips)',
 P_PATH='@t6g_mb_lib.t6g(sch_1):page178_i121@pure_quanta.q_res(chips)',
 PATH='I121',
 DRAWING='@T6G_MB_LIB.T6G(SCH_1):PAGE155',
 WATTAGE='1/16W',
 TOLERANCE='1%',
 MATERIAL='CHIP',
 PHYS_PAGE='178',
 XY='(-9100,5400)',
 ROT='2',
 VER='2',
 PACK_TYPE='0402LF',
 LOCATION='R6319',
 CDS_LIB='pure_quanta',
 CDS_PART_NAME='Q_RES_0402LF-10K,1%,1/16W,CHIP,CS31002FB08',
 GROUP='HUB_TI',
 ROOM='USB3_HUB2_TI',
 PART_NUMBER='CS31002FB08',
 VALUE='10K',
 PRIM_FILE='./archive_libs/logical/q_res/chips/chips.prt';

PART_NAME
 R6320 'Q_RES_0402LF-10K,1%,1/16W,EMPTY,CS31002FB08':
 GROUP='HUB_MRP',
 ROOM='USB3_HUB2_MRP';

SECTION_NUMBER 1
 '@T6G_MB_LIB.T6G(SCH_1):PAGE155_I212@PURE_QUANTA.Q_RES(CHIPS)':
 C_PATH='@t6g_mb_lib.t6g(sch_1):page155_i212@pure_quanta.q_res(chips)',
 P_PATH='@t6g_mb_lib.t6g(sch_1):page178_i212@pure_quanta.q_res(chips)',
 PATH='I212',
 DRAWING='@T6G_MB_LIB.T6G(SCH_1):PAGE155',
 WATTAGE='1/16W',
 TOLERANCE='1%',
 MATERIAL='EMPTY',
 PHYS_PAGE='178',
 XY='(-8025,6300)',
 ROT='0',
 VER='2',
 PACK_TYPE='0402LF',
 LOCATION='R6320',
 CDS_LIB='pure_quanta',
 CDS_PART_NAME='Q_RES_0402LF-10K,1%,1/16W,EMPTY,CS31002FB08',
 GROUP='HUB_MRP',
 ROOM='USB3_HUB2_MRP',
 PART_NUMBER='CS31002FB08',
 VALUE='10K',
 PRIM_FILE='./archive_libs/logical/q_res/chips/chips.prt';

PART_NAME
 R6321 'Q_RES_0402LF-47K,0.1%,1/16W,EMPTY,CS34702BB05':
 GROUP='HUB_MRP',
 ROOM='USB3_HUB2_MRP';

SECTION_NUMBER 1
 '@T6G_MB_LIB.T6G(SCH_1):PAGE155_I129@PURE_QUANTA.Q_RES(CHIPS)':
 C_PATH='@t6g_mb_lib.t6g(sch_1):page155_i129@pure_quanta.q_res(chips)',
 P_PATH='@t6g_mb_lib.t6g(sch_1):page178_i129@pure_quanta.q_res(chips)',
 PATH='I129',
 DRAWING='@T6G_MB_LIB.T6G(SCH_1):PAGE155',
 WATTAGE='1/16W',
 TOLERANCE='0.1%',
 MATERIAL='EMPTY',
 PHYS_PAGE='178',
 XY='(-8350,5900)',
 ROT='0',
 VER='2',
 PACK_TYPE='0402LF',
 LOCATION='R6321',
 CDS_LIB='pure_quanta',
 CDS_PART_NAME='Q_RES_0402LF-47K,0.1%,1/16W,EMPTY,CS34702BB05',
 GROUP='HUB_MRP',
 ROOM='USB3_HUB2_MRP',
 PART_NUMBER='CS34702BB05',
 VALUE='47K',
 PRIM_FILE='./archive_libs/logical/q_res/chips/chips.prt';

PART_NAME
 R6322 'Q_RES_0402LF-0,5%,1/16W,CHIP,CS00002JB13':
 GROUP='HUB_MRP',
 ROOM='USB3_HUB2_MRP';

SECTION_NUMBER 1
 '@T6G_MB_LIB.T6G(SCH_1):PAGE155_I131@PURE_QUANTA.Q_RES(CHIPS)':
 C_PATH='@t6g_mb_lib.t6g(sch_1):page155_i131@pure_quanta.q_res(chips)',
 P_PATH='@t6g_mb_lib.t6g(sch_1):page178_i131@pure_quanta.q_res(chips)',
 PATH='I131',
 DRAWING='@T6G_MB_LIB.T6G(SCH_1):PAGE155',
 BOM_COST='VR_SYSTEM ',
 WATTAGE='1/16W',
 TOLERANCE='5%',
 MATERIAL='CHIP',
 PHYS_PAGE='178',
 XY='(-8600,6275)',
 ROT='0',
 VER='1',
 PACK_TYPE='0402LF',
 LOCATION='R6322',
 CDS_LIB='pure_quanta',
 CDS_PART_NAME='Q_RES_0402LF-0,5%,1/16W,CHIP,CS00002JB13',
 GROUP='HUB_MRP',
 ROOM='USB3_HUB2_MRP',
 PART_NUMBER='CS00002JB13',
 VALUE='0',
 PRIM_FILE='./archive_libs/logical/q_res/chips/chips.prt';

PART_NAME
 R6323 'Q_RES_0402LF-0,5%,1/16W,CHIP,CS00002JB13':
 GROUP='HUB_TI',
 ROOM='USB3_HUB2_TI';

SECTION_NUMBER 1
 '@T6G_MB_LIB.T6G(SCH_1):PAGE155_I115@PURE_QUANTA.Q_RES(CHIPS)':
 C_PATH='@t6g_mb_lib.t6g(sch_1):page155_i115@pure_quanta.q_res(chips)',
 P_PATH='@t6g_mb_lib.t6g(sch_1):page178_i115@pure_quanta.q_res(chips)',
 PATH='I115',
 DRAWING='@T6G_MB_LIB.T6G(SCH_1):PAGE155',
 BOM_COST='VR_SYSTEM ',
 WATTAGE='1/16W',
 TOLERANCE='5%',
 MATERIAL='CHIP',
 PHYS_PAGE='178',
 XY='(-6825,975)',
 ROT='0',
 VER='1',
 PACK_TYPE='0402LF',
 LOCATION='R6323',
 CDS_LIB='pure_quanta',
 CDS_PART_NAME='Q_RES_0402LF-0,5%,1/16W,CHIP,CS00002JB13',
 GROUP='HUB_TI',
 ROOM='USB3_HUB2_TI',
 PART_NUMBER='CS00002JB13',
 VALUE='0',
 PRIM_FILE='./archive_libs/logical/q_res/chips/chips.prt';

PART_NAME
 R6324 'Q_RES_0402LF-0,5%,1/16W,CHIP,CS00002JB13':
 GROUP='HUB_MRP',
 ROOM='USB3_HUB2_MRP';

SECTION_NUMBER 1
 '@T6G_MB_LIB.T6G(SCH_1):PAGE155_I118@PURE_QUANTA.Q_RES(CHIPS)':
 C_PATH='@t6g_mb_lib.t6g(sch_1):page155_i118@pure_quanta.q_res(chips)',
 P_PATH='@t6g_mb_lib.t6g(sch_1):page178_i118@pure_quanta.q_res(chips)',
 PATH='I118',
 DRAWING='@T6G_MB_LIB.T6G(SCH_1):PAGE155',
 BOM_COST='VR_SYSTEM ',
 WATTAGE='1/16W',
 TOLERANCE='5%',
 MATERIAL='CHIP',
 PHYS_PAGE='178',
 XY='(-6875,1300)',
 ROT='0',
 VER='1',
 PACK_TYPE='0402LF',
 LOCATION='R6324',
 CDS_LIB='pure_quanta',
 CDS_PART_NAME='Q_RES_0402LF-0,5%,1/16W,CHIP,CS00002JB13',
 GROUP='HUB_MRP',
 ROOM='USB3_HUB2_MRP',
 PART_NUMBER='CS00002JB13',
 VALUE='0',
 PRIM_FILE='./archive_libs/logical/q_res/chips/chips.prt';

PART_NAME
 R6325 'Q_RES_0402LF-10K,1%,1/16W,CHIP,CS31002FB08':
 GROUP='HUB_TI',
 ROOM='USB3_HUB2_TI';

SECTION_NUMBER 1
 '@T6G_MB_LIB.T6G(SCH_1):PAGE155_I116@PURE_QUANTA.Q_RES(CHIPS)':
 C_PATH='@t6g_mb_lib.t6g(sch_1):page155_i116@pure_quanta.q_res(chips)',
 P_PATH='@t6g_mb_lib.t6g(sch_1):page178_i116@pure_quanta.q_res(chips)',
 PATH='I116',
 DRAWING='@T6G_MB_LIB.T6G(SCH_1):PAGE155',
 WATTAGE='1/16W',
 TOLERANCE='1%',
 MATERIAL='CHIP',
 PHYS_PAGE='178',
 XY='(-7925,775)',
 ROT='2',
 VER='2',
 PACK_TYPE='0402LF',
 LOCATION='R6325',
 CDS_LIB='pure_quanta',
 CDS_PART_NAME='Q_RES_0402LF-10K,1%,1/16W,CHIP,CS31002FB08',
 GROUP='HUB_TI',
 ROOM='USB3_HUB2_TI',
 PART_NUMBER='CS31002FB08',
 VALUE='10K',
 PRIM_FILE='./archive_libs/logical/q_res/chips/chips.prt';

PART_NAME
 R6326 'Q_RES_0402LF-4.7K,1%,1/16W,CHIP,CS24702FB06':
 GROUP='HUB_MRP',
 ROOM='USB3_HUB2_MRP';

SECTION_NUMBER 1
 '@T6G_MB_LIB.T6G(SCH_1):PAGE155_I89@PURE_QUANTA.Q_RES(CHIPS)':
 C_PATH='@t6g_mb_lib.t6g(sch_1):page155_i89@pure_quanta.q_res(chips)',
 P_PATH='@t6g_mb_lib.t6g(sch_1):page178_i89@pure_quanta.q_res(chips)',
 PATH='I89',
 DRAWING='@T6G_MB_LIB.T6G(SCH_1):PAGE155',
 WATTAGE='1/16W',
 TOLERANCE='1%',
 MATERIAL='CHIP',
 PHYS_PAGE='178',
 XY='(-8500,1100)',
 ROT='0',
 VER='2',
 PACK_TYPE='0402LF',
 LOCATION='R6326',
 CDS_LIB='pure_quanta',
 CDS_PART_NAME='Q_RES_0402LF-4.7K,1%,1/16W,CHIP,CS24702FB06',
 GROUP='HUB_MRP',
 ROOM='USB3_HUB2_MRP',
 PART_NUMBER='CS24702FB06',
 VALUE='4.7K',
 PRIM_FILE='./archive_libs/logical/q_res/chips/chips.prt';

PART_NAME
 R6327 'Q_RES_0402LF-4.7K,1%,1/16W,EMPTY,CS24702FB06':
 GROUP='HUB_MRP',
 ROOM='USB3_HUB2_MRP';

SECTION_NUMBER 1
 '@T6G_MB_LIB.T6G(SCH_1):PAGE155_I91@PURE_QUANTA.Q_RES(CHIPS)':
 C_PATH='@t6g_mb_lib.t6g(sch_1):page155_i91@pure_quanta.q_res(chips)',
 P_PATH='@t6g_mb_lib.t6g(sch_1):page178_i91@pure_quanta.q_res(chips)',
 PATH='I91',
 DRAWING='@T6G_MB_LIB.T6G(SCH_1):PAGE155',
 WATTAGE='1/16W',
 TOLERANCE='1%',
 MATERIAL='EMPTY',
 PHYS_PAGE='178',
 XY='(-8500,1475)',
 ROT='0',
 VER='2',
 PACK_TYPE='0402LF',
 LOCATION='R6327',
 CDS_LIB='pure_quanta',
 CDS_PART_NAME='Q_RES_0402LF-4.7K,1%,1/16W,EMPTY,CS24702FB06',
 GROUP='HUB_MRP',
 ROOM='USB3_HUB2_MRP',
 PART_NUMBER='CS24702FB06',
 VALUE='4.7K',
 PRIM_FILE='./archive_libs/logical/q_res/chips/chips.prt';

PART_NAME
 R6328 'Q_RES_0402LF-0,5%,1/16W,CHIP,CS00002JB13':
 GROUP='HUB_TI',
 ROOM='USB3_HUB2_TI';

SECTION_NUMBER 1
 '@T6G_MB_LIB.T6G(SCH_1):PAGE155_I114@PURE_QUANTA.Q_RES(CHIPS)':
 C_PATH='@t6g_mb_lib.t6g(sch_1):page155_i114@pure_quanta.q_res(chips)',
 P_PATH='@t6g_mb_lib.t6g(sch_1):page178_i114@pure_quanta.q_res(chips)',
 PATH='I114',
 DRAWING='@T6G_MB_LIB.T6G(SCH_1):PAGE155',
 BOM_COST='VR_SYSTEM ',
 WATTAGE='1/16W',
 TOLERANCE='5%',
 MATERIAL='CHIP',
 PHYS_PAGE='178',
 XY='(-8350,3600)',
 ROT='0',
 VER='1',
 PACK_TYPE='0402LF',
 LOCATION='R6328',
 CDS_LIB='pure_quanta',
 CDS_PART_NAME='Q_RES_0402LF-0,5%,1/16W,CHIP,CS00002JB13',
 GROUP='HUB_TI',
 ROOM='USB3_HUB2_TI',
 PART_NUMBER='CS00002JB13',
 VALUE='0',
 PRIM_FILE='./archive_libs/logical/q_res/chips/chips.prt';

PART_NAME
 R6329 'Q_RES_0402LF-10K,1%,1/16W,EMPTY,CS31002FB08':
 GROUP='HUB_TI',
 ROOM='USB3_HUB2_TI';

SECTION_NUMBER 1
 '@T6G_MB_LIB.T6G(SCH_1):PAGE155_I213@PURE_QUANTA.Q_RES(CHIPS)':
 C_PATH='@t6g_mb_lib.t6g(sch_1):page155_i213@pure_quanta.q_res(chips)',
 P_PATH='@t6g_mb_lib.t6g(sch_1):page178_i213@pure_quanta.q_res(chips)',
 PATH='I213',
 DRAWING='@T6G_MB_LIB.T6G(SCH_1):PAGE155',
 WATTAGE='1/16W',
 TOLERANCE='1%',
 MATERIAL='EMPTY',
 PHYS_PAGE='178',
 XY='(-8175,3825)',
 ROT='0',
 VER='2',
 PACK_TYPE='0402LF',
 LOCATION='R6329',
 CDS_LIB='pure_quanta',
 CDS_PART_NAME='Q_RES_0402LF-10K,1%,1/16W,EMPTY,CS31002FB08',
 GROUP='HUB_TI',
 ROOM='USB3_HUB2_TI',
 PART_NUMBER='CS31002FB08',
 VALUE='10K',
 PRIM_FILE='./archive_libs/logical/q_res/chips/chips.prt';

PART_NAME
 R6330 'Q_RES_0402LF-4.7K,1%,1/16W,CHIP,CS24702FB06':
 GROUP='HUB_MRP',
 ROOM='USB3_HUB2_MRP';

SECTION_NUMBER 1
 '@T6G_MB_LIB.T6G(SCH_1):PAGE155_I188@PURE_QUANTA.Q_RES(CHIPS)':
 C_PATH='@t6g_mb_lib.t6g(sch_1):page155_i188@pure_quanta.q_res(chips)',
 P_PATH='@t6g_mb_lib.t6g(sch_1):page178_i188@pure_quanta.q_res(chips)',
 PATH='I188',
 DRAWING='@T6G_MB_LIB.T6G(SCH_1):PAGE155',
 WATTAGE='1/16W',
 TOLERANCE='1%',
 MATERIAL='CHIP',
 PHYS_PAGE='178',
 XY='(-6200,800)',
 ROT='0',
 VER='1',
 PACK_TYPE='0402LF',
 LOCATION='R6330',
 CDS_LIB='pure_quanta',
 CDS_PART_NAME='Q_RES_0402LF-4.7K,1%,1/16W,CHIP,CS24702FB06',
 GROUP='HUB_MRP',
 ROOM='USB3_HUB2_MRP',
 PART_NUMBER='CS24702FB06',
 VALUE='4.7K',
 PRIM_FILE='./archive_libs/logical/q_res/chips/chips.prt';

PART_NAME
 R6331 'Q_RES_0402LF-9.53K,1%,1/16W,CHIP,CS29532FB06':
 GROUP='HUB_TI',
 ROOM='USB3_HUB2_TI';

SECTION_NUMBER 1
 '@T6G_MB_LIB.T6G(SCH_1):PAGE155_I207@PURE_QUANTA.Q_RES(CHIPS)':
 C_PATH='@t6g_mb_lib.t6g(sch_1):page155_i207@pure_quanta.q_res(chips)',
 P_PATH='@t6g_mb_lib.t6g(sch_1):page178_i207@pure_quanta.q_res(chips)',
 PATH='I207',
 DRAWING='@T6G_MB_LIB.T6G(SCH_1):PAGE155',
 WATTAGE='1/16W',
 TOLERANCE='1%',
 MATERIAL='CHIP',
 PHYS_PAGE='178',
 XY='(-2900,1275)',
 ROT='0',
 VER='2',
 PACK_TYPE='0402LF',
 LOCATION='R6331',
 CDS_LIB='pure_quanta',
 CDS_PART_NAME='Q_RES_0402LF-9.53K,1%,1/16W,CHIP,CS29532FB06',
 GROUP='HUB_TI',
 ROOM='USB3_HUB2_TI',
 PART_NUMBER='CS29532FB06',
 VALUE='9.53K',
 PRIM_FILE='./archive_libs/logical/q_res/chips/chips.prt';

PART_NAME
 R6332 'Q_RES_0402LF-12K,1%,1/16W,CHIP,CS31202FB04':
 GROUP='HUB_MRP',
 ROOM='USB3_HUB2_MRP';

SECTION_NUMBER 1
 '@T6G_MB_LIB.T6G(SCH_1):PAGE155_I208@PURE_QUANTA.Q_RES(CHIPS)':
 C_PATH='@t6g_mb_lib.t6g(sch_1):page155_i208@pure_quanta.q_res(chips)',
 P_PATH='@t6g_mb_lib.t6g(sch_1):page178_i208@pure_quanta.q_res(chips)',
 PATH='I208',
 DRAWING='@T6G_MB_LIB.T6G(SCH_1):PAGE155',
 WATTAGE='1/16W',
 TOLERANCE='1%',
 MATERIAL='CHIP',
 PHYS_PAGE='178',
 XY='(-3000,1275)',
 ROT='2',
 VER='2',
 PACK_TYPE='0402LF',
 LOCATION='R6332',
 CDS_LIB='pure_quanta',
 CDS_PART_NAME='Q_RES_0402LF-12K,1%,1/16W,CHIP,CS31202FB04',
 GROUP='HUB_MRP',
 ROOM='USB3_HUB2_MRP',
 PART_NUMBER='CS31202FB04',
 VALUE='12K',
 PRIM_FILE='./archive_libs/logical/q_res/chips/chips.prt';

PART_NAME
 R6333 'Q_RES_0402LF-47K,0.1%,1/16W,EMPTY,CS34702BB05':
 GROUP='HUB_TI',
 ROOM='USB3_HUB2_TI';

SECTION_NUMBER 1
 '@T6G_MB_LIB.T6G(SCH_1):PAGE155_I111@PURE_QUANTA.Q_RES(CHIPS)':
 C_PATH='@t6g_mb_lib.t6g(sch_1):page155_i111@pure_quanta.q_res(chips)',
 P_PATH='@t6g_mb_lib.t6g(sch_1):page178_i111@pure_quanta.q_res(chips)',
 PATH='I111',
 DRAWING='@T6G_MB_LIB.T6G(SCH_1):PAGE155',
 WATTAGE='1/16W',
 TOLERANCE='0.1%',
 MATERIAL='EMPTY',
 PHYS_PAGE='178',
 XY='(-7575,3450)',
 ROT='2',
 VER='2',
 PACK_TYPE='0402LF',
 LOCATION='R6333',
 CDS_LIB='pure_quanta',
 CDS_PART_NAME='Q_RES_0402LF-47K,0.1%,1/16W,EMPTY,CS34702BB05',
 GROUP='HUB_TI',
 ROOM='USB3_HUB2_TI',
 PART_NUMBER='CS34702BB05',
 VALUE='47K',
 PRIM_FILE='./archive_libs/logical/q_res/chips/chips.prt';

PART_NAME
 R6500 'Q_RES_0402LF-0,5%,1/16W,CHIP,CS00002JB13':;

SECTION_NUMBER 1
 '@T6G_MB_LIB.T6G(SCH_1):PAGE273_I136@PURE_QUANTA.Q_RES(CHIPS)':
 C_PATH='@t6g_mb_lib.t6g(sch_1):page273_i136@pure_quanta.q_res(chips)',
 P_PATH='@t6g_mb_lib.t6g(sch_1):page188_i136@pure_quanta.q_res(chips)',
 PATH='I136',
 DRAWING='@T6G_MB_LIB.T6G(SCH_1):PAGE273',
 SEC_TYPE='0402LF',
 WATTAGE='1/16W',
 TOLERANCE='5%',
 MATERIAL='CHIP',
 PHYS_PAGE='188',
 XY='(-5950,2225)',
 ROT='0',
 VER='1',
 PACK_TYPE='0402LF',
 LOCATION='R6500',
 SEC='1',
 CDS_LIB='pure_quanta',
 CDS_PART_NAME='Q_RES_0402LF-0,5%,1/16W,CHIP,CS00002JB13',
 PART_NUMBER='CS00002JB13',
 VALUE='0',
 PRIM_FILE='./archive_libs/logical/q_res/chips/chips.prt';

PART_NAME
 R6501 'Q_RES_0402LF-100K,1%,1/16W,CHIP,CS41002FB09':;

SECTION_NUMBER 1
 '@T6G_MB_LIB.T6G(SCH_1):PAGE273_I139@PURE_QUANTA.Q_RES(CHIPS)':
 C_PATH='@t6g_mb_lib.t6g(sch_1):page273_i139@pure_quanta.q_res(chips)',
 P_PATH='@t6g_mb_lib.t6g(sch_1):page188_i139@pure_quanta.q_res(chips)',
 PATH='I139',
 DRAWING='@T6G_MB_LIB.T6G(SCH_1):PAGE273',
 SEC_TYPE='0402LF',
 WATTAGE='1/16W',
 TOLERANCE='1%',
 MATERIAL='CHIP',
 PHYS_PAGE='188',
 XY='(-6175,2050)',
 ROT='2',
 VER='2',
 PACK_TYPE='0402LF',
 LOCATION='R6501',
 SEC='1',
 CDS_LIB='pure_quanta',
 CDS_PART_NAME='Q_RES_0402LF-100K,1%,1/16W,CHIP,CS41002FB09',
 PART_NUMBER='CS41002FB09',
 VALUE='100K',
 PRIM_FILE='./archive_libs/logical/q_res/chips/chips.prt';

PART_NAME
 R6502 'Q_RES_0402LF-2.2K,5%,1/16W,CHIP,CS22202JB07':;

SECTION_NUMBER 1
 '@T6G_MB_LIB.T6G(SCH_1):PAGE28_I224@PURE_QUANTA.Q_RES(CHIPS)':
 C_PATH='@t6g_mb_lib.t6g(sch_1):page28_i224@pure_quanta.q_res(chips)',
 P_PATH='@t6g_mb_lib.t6g(sch_1):page28_i224@pure_quanta.q_res(chips)',
 PATH='I224',
 DRAWING='@T6G_MB_LIB.T6G(SCH_1):PAGE28',
 WATTAGE='1/16W',
 TOLERANCE='5%',
 MATERIAL='CHIP',
 PHYS_PAGE='28',
 XY='(-6350,8675)',
 ROT='2',
 VER='2',
 PACK_TYPE='0402LF',
 LOCATION='R6502',
 CDS_LIB='pure_quanta',
 CDS_PART_NAME='Q_RES_0402LF-2.2K,5%,1/16W,CHIP,CS22202JB07',
 PART_NUMBER='CS22202JB07',
 VALUE='2.2K',
 PRIM_FILE='./archive_libs/logical/q_res/chips/chips.prt';

PART_NAME
 R6503 'Q_RES_0402LF-2.2K,5%,1/16W,CHIP,CS22202JB07':;

SECTION_NUMBER 1
 '@T6G_MB_LIB.T6G(SCH_1):PAGE55_I392@PURE_QUANTA.Q_RES(CHIPS)':
 C_PATH='@t6g_mb_lib.t6g(sch_1):page55_i392@pure_quanta.q_res(chips)',
 P_PATH='@t6g_mb_lib.t6g(sch_1):page55_i392@pure_quanta.q_res(chips)',
 PATH='I392',
 DRAWING='@T6G_MB_LIB.T6G(SCH_1):PAGE55',
 WATTAGE='1/16W',
 TOLERANCE='5%',
 MATERIAL='CHIP',
 PHYS_PAGE='55',
 XY='(-8275,475)',
 ROT='0',
 VER='2',
 PACK_TYPE='0402LF',
 LOCATION='R6503',
 CDS_LIB='pure_quanta',
 CDS_PART_NAME='Q_RES_0402LF-2.2K,5%,1/16W,CHIP,CS22202JB07',
 PART_NUMBER='CS22202JB07',
 VALUE='2.2K',
 PRIM_FILE='./archive_libs/logical/q_res/chips/chips.prt';

PART_NAME
 R6504 'Q_RES_0402LF-10K,1%,1/16W,CHIP,CS31002FB08':;

SECTION_NUMBER 1
 '@T6G_MB_LIB.T6G(SCH_1):PAGE264_I51@PURE_QUANTA.Q_RES(CHIPS)':
 C_PATH='@t6g_mb_lib.t6g(sch_1):page264_i51@pure_quanta.q_res(chips)',
 P_PATH='@t6g_mb_lib.t6g(sch_1):page259_i51@pure_quanta.q_res(chips)',
 PATH='I51',
 DRAWING='@T6G_MB_LIB.T6G(SCH_1):PAGE264',
 WATTAGE='1/16W',
 TOLERANCE='1%',
 MATERIAL='CHIP',
 PHYS_PAGE='259',
 XY='(-6800,2225)',
 ROT='2',
 VER='2',
 PACK_TYPE='0402LF',
 LOCATION='R6504',
 CDS_LIB='pure_quanta',
 CDS_PART_NAME='Q_RES_0402LF-10K,1%,1/16W,CHIP,CS31002FB08',
 PART_NUMBER='CS31002FB08',
 VALUE='10K',
 PRIM_FILE='./archive_libs/logical/q_res/chips/chips.prt';

PART_NAME
 R6505 'Q_RES_0402LF-10K,5%,1/16W,CHIP,CS31002JB08':;

SECTION_NUMBER 1
 '@T6G_MB_LIB.T6G(SCH_1):PAGE469_I28@PURE_QUANTA.Q_RES(CHIPS)':
 C_PATH='@t6g_mb_lib.t6g(sch_1):page469_i28@pure_quanta.q_res(chips)',
 P_PATH='@t6g_mb_lib.t6g(sch_1):page360_i28@pure_quanta.q_res(chips)',
 PATH='I28',
 DRAWING='@T6G_MB_LIB.T6G(SCH_1):PAGE469',
 SEC_TYPE='0402LF',
 WATTAGE='1/16W',
 TOLERANCE='5%',
 MATERIAL='CHIP',
 PHYS_PAGE='360',
 XY='(-4575,4200)',
 ROT='0',
 VER='2',
 PACK_TYPE='0402LF',
 LOCATION='R6505',
 SEC='1',
 CDS_LIB='pure_quanta',
 CDS_PART_NAME='Q_RES_0402LF-10K,5%,1/16W,CHIP,CS31002JB08',
 PART_NUMBER='CS31002JB08',
 VALUE='10K',
 PRIM_FILE='./archive_libs/logical/q_res/chips/chips.prt';

PART_NAME
 R6506 'Q_RES_0402LF-33,5%,1/16W,CHIP,CS03302JB10':;

SECTION_NUMBER 1
 '@T6G_MB_LIB.T6G(SCH_1):PAGE469_I37@PURE_QUANTA.Q_RES(CHIPS)':
 C_PATH='@t6g_mb_lib.t6g(sch_1):page469_i37@pure_quanta.q_res(chips)',
 P_PATH='@t6g_mb_lib.t6g(sch_1):page360_i37@pure_quanta.q_res(chips)',
 PATH='I37',
 DRAWING='@T6G_MB_LIB.T6G(SCH_1):PAGE469',
 BOM_COST='MEM',
 WATTAGE='1/16W',
 TOLERANCE='5%',
 MATERIAL='CHIP',
 PHYS_PAGE='360',
 XY='(-3525,3900)',
 ROT='0',
 VER='1',
 PACK_TYPE='0402LF',
 LOCATION='R6506',
 CDS_LIB='pure_quanta',
 CDS_PART_NAME='Q_RES_0402LF-33,5%,1/16W,CHIP,CS03302JB10',
 PART_NUMBER='CS03302JB10',
 VALUE='33',
 PRIM_FILE='./archive_libs/logical/q_res/chips/chips.prt';

PART_NAME
 R6701 'Q_RES_0402LF-0,5%,1/16W,EMPTY,CS00002JB13':;

SECTION_NUMBER 1
 '@T6G_MB_LIB.T6G(SCH_1):PAGE398_I98@PURE_QUANTA.Q_RES(CHIPS)':
 C_PATH='@t6g_mb_lib.t6g(sch_1):page398_i98@pure_quanta.q_res(chips)',
 P_PATH='@t6g_mb_lib.t6g(sch_1):page323_i98@pure_quanta.q_res(chips)',
 PATH='I98',
 DRAWING='@T6G_MB_LIB.T6G(SCH_1):PAGE398',
 WATTAGE='1/16W',
 TOLERANCE='5%',
 MATERIAL='EMPTY',
 PHYS_PAGE='323',
 XY='(-8375,4375)',
 ROT='0',
 VER='2',
 PACK_TYPE='0402LF',
 LOCATION='R6701',
 CDS_LIB='pure_quanta',
 CDS_PART_NAME='Q_RES_0402LF-0,5%,1/16W,EMPTY,CS00002JB13',
 PART_NUMBER='CS00002JB13',
 VALUE='0',
 PRIM_FILE='./archive_libs/logical/q_res/chips/chips.prt';

PART_NAME
 R6702 'Q_RES_0402LF-0,5%,1/16W,EMPTY,CS00002JB13':;

SECTION_NUMBER 1
 '@T6G_MB_LIB.T6G(SCH_1):PAGE398_I32@PURE_QUANTA.Q_RES(CHIPS)':
 C_PATH='@t6g_mb_lib.t6g(sch_1):page398_i32@pure_quanta.q_res(chips)',
 P_PATH='@t6g_mb_lib.t6g(sch_1):page323_i32@pure_quanta.q_res(chips)',
 PATH='I32',
 DRAWING='@T6G_MB_LIB.T6G(SCH_1):PAGE398',
 SEC_TYPE='0402LF',
 WATTAGE='1/16W',
 TOLERANCE='5%',
 MATERIAL='EMPTY',
 PHYS_PAGE='323',
 XY='(-7975,4050)',
 ROT='0',
 VER='1',
 PACK_TYPE='0402LF',
 LOCATION='R6702',
 SEC='1',
 CDS_LIB='pure_quanta',
 CDS_PART_NAME='Q_RES_0402LF-0,5%,1/16W,EMPTY,CS00002JB13',
 PART_NUMBER='CS00002JB13',
 VALUE='0',
 PRIM_FILE='./archive_libs/logical/q_res/chips/chips.prt';

PART_NAME
 R6703 'Q_RES_0402LF-0,5%,1/16W,EMPTY,CS00002JB13':;

SECTION_NUMBER 1
 '@T6G_MB_LIB.T6G(SCH_1):PAGE398_I33@PURE_QUANTA.Q_RES(CHIPS)':
 C_PATH='@t6g_mb_lib.t6g(sch_1):page398_i33@pure_quanta.q_res(chips)',
 P_PATH='@t6g_mb_lib.t6g(sch_1):page323_i33@pure_quanta.q_res(chips)',
 PATH='I33',
 DRAWING='@T6G_MB_LIB.T6G(SCH_1):PAGE398',
 SEC_TYPE='0402LF',
 WATTAGE='1/16W',
 TOLERANCE='5%',
 MATERIAL='EMPTY',
 PHYS_PAGE='323',
 XY='(-7975,3850)',
 ROT='0',
 VER='1',
 PACK_TYPE='0402LF',
 LOCATION='R6703',
 SEC='1',
 CDS_LIB='pure_quanta',
 CDS_PART_NAME='Q_RES_0402LF-0,5%,1/16W,EMPTY,CS00002JB13',
 PART_NUMBER='CS00002JB13',
 VALUE='0',
 PRIM_FILE='./archive_libs/logical/q_res/chips/chips.prt';

PART_NAME
 R6704 'Q_RES_0603LF-0,5%,1/4W,EMPTY,CS00006J900':;

SECTION_NUMBER 1
 '@T6G_MB_LIB.T6G(SCH_1):PAGE398_I96@PURE_QUANTA.Q_RES(CHIPS)':
 C_PATH='@t6g_mb_lib.t6g(sch_1):page398_i96@pure_quanta.q_res(chips)',
 P_PATH='@t6g_mb_lib.t6g(sch_1):page323_i96@pure_quanta.q_res(chips)',
 PATH='I96',
 DRAWING='@T6G_MB_LIB.T6G(SCH_1):PAGE398',
 WATTAGE='1/4W',
 TOLERANCE='5%',
 MATERIAL='EMPTY',
 PHYS_PAGE='323',
 XY='(-4575,3050)',
 ROT='2',
 VER='2',
 PACK_TYPE='0603LF',
 LOCATION='R6704',
 CDS_LIB='pure_quanta',
 CDS_PART_NAME='Q_RES_0603LF-0,5%,1/4W,EMPTY,CS00006J900',
 PART_NUMBER='CS00006J900',
 VALUE='0',
 PRIM_FILE='./archive_libs/logical/q_res/chips/chips.prt';

PART_NAME
 R6705 'Q_RES_0603LF-0,5%,1/4W,CHIP,CS00006J900':;

SECTION_NUMBER 1
 '@T6G_MB_LIB.T6G(SCH_1):PAGE398_I95@PURE_QUANTA.Q_RES(CHIPS)':
 C_PATH='@t6g_mb_lib.t6g(sch_1):page398_i95@pure_quanta.q_res(chips)',
 P_PATH='@t6g_mb_lib.t6g(sch_1):page323_i95@pure_quanta.q_res(chips)',
 PATH='I95',
 DRAWING='@T6G_MB_LIB.T6G(SCH_1):PAGE398',
 WATTAGE='1/4W',
 TOLERANCE='5%',
 MATERIAL='CHIP',
 PHYS_PAGE='323',
 XY='(-4200,2775)',
 ROT='0',
 VER='1',
 PACK_TYPE='0603LF',
 LOCATION='R6705',
 CDS_LIB='pure_quanta',
 CDS_PART_NAME='Q_RES_0603LF-0,5%,1/4W,CHIP,CS00006J900',
 PART_NUMBER='CS00006J900',
 VALUE='0',
 PRIM_FILE='./archive_libs/logical/q_res/chips/chips.prt';

PART_NAME
 R6706 'Q_RES_0201LF-1K,1%,1/20W,CHIP,CS21001FE07':;

SECTION_NUMBER 1
 '@T6G_MB_LIB.T6G(SCH_1):PAGE377_I65@PURE_QUANTA.Q_RES(CHIPS)':
 C_PATH='@t6g_mb_lib.t6g(sch_1):page377_i65@pure_quanta.q_res(chips)',
 P_PATH='@t6g_mb_lib.t6g(sch_1):page185_i65@pure_quanta.q_res(chips)',
 PATH='I65',
 DRAWING='@T6G_MB_LIB.T6G(SCH_1):PAGE377',
 WATTAGE='1/20W',
 TOLERANCE='1%',
 MATERIAL='CHIP',
 PHYS_PAGE='185',
 XY='(-2550,1625)',
 ROT='0',
 VER='1',
 PACK_TYPE='0201LF',
 LOCATION='R6706',
 CDS_LIB='pure_quanta',
 CDS_PART_NAME='Q_RES_0201LF-1K,1%,1/20W,CHIP,CS21001FE07',
 PART_NUMBER='CS21001FE07',
 VALUE='1K',
 PRIM_FILE='./archive_libs/logical/q_res/chips/chips.prt';

PART_NAME
 R6707 'Q_RES_0201LF-1K,1%,1/20W,CHIP,CS21001FE07':;

SECTION_NUMBER 1
 '@T6G_MB_LIB.T6G(SCH_1):PAGE377_I64@PURE_QUANTA.Q_RES(CHIPS)':
 C_PATH='@t6g_mb_lib.t6g(sch_1):page377_i64@pure_quanta.q_res(chips)',
 P_PATH='@t6g_mb_lib.t6g(sch_1):page185_i64@pure_quanta.q_res(chips)',
 PATH='I64',
 DRAWING='@T6G_MB_LIB.T6G(SCH_1):PAGE377',
 WATTAGE='1/20W',
 TOLERANCE='1%',
 MATERIAL='CHIP',
 PHYS_PAGE='185',
 XY='(-2550,1725)',
 ROT='0',
 VER='1',
 PACK_TYPE='0201LF',
 LOCATION='R6707',
 CDS_LIB='pure_quanta',
 CDS_PART_NAME='Q_RES_0201LF-1K,1%,1/20W,CHIP,CS21001FE07',
 PART_NUMBER='CS21001FE07',
 VALUE='1K',
 PRIM_FILE='./archive_libs/logical/q_res/chips/chips.prt';

PART_NAME
 R6708 'Q_RES_0201LF-0,5%,1/20W,CHIP,CS00001JE10':;

SECTION_NUMBER 1
 '@T6G_MB_LIB.T6G(SCH_1):PAGE401_I62@PURE_QUANTA.Q_RES(CHIPS)':
 C_PATH='@t6g_mb_lib.t6g(sch_1):page401_i62@pure_quanta.q_res(chips)',
 P_PATH='@t6g_mb_lib.t6g(sch_1):page320_i62@pure_quanta.q_res(chips)',
 PATH='I62',
 DRAWING='@T6G_MB_LIB.T6G(SCH_1):PAGE401',
 SEC_TYPE='0201LF',
 WATTAGE='1/20W',
 TOLERANCE='5%',
 MATERIAL='CHIP',
 PHYS_PAGE='320',
 XY='(-2575,2300)',
 ROT='0',
 VER='1',
 PACK_TYPE='0201LF',
 LOCATION='R6708',
 SEC='1',
 CDS_LIB='pure_quanta',
 CDS_PART_NAME='Q_RES_0201LF-0,5%,1/20W,CHIP,CS00001JE10',
 PART_NUMBER='CS00001JE10',
 VALUE='0',
 PRIM_FILE='./archive_libs/logical/q_res/chips/chips.prt';

PART_NAME
 R6709 'Q_RES_0201LF-0,5%,1/20W,CHIP,CS00001JE10':;

SECTION_NUMBER 1
 '@T6G_MB_LIB.T6G(SCH_1):PAGE401_I65@PURE_QUANTA.Q_RES(CHIPS)':
 C_PATH='@t6g_mb_lib.t6g(sch_1):page401_i65@pure_quanta.q_res(chips)',
 P_PATH='@t6g_mb_lib.t6g(sch_1):page320_i65@pure_quanta.q_res(chips)',
 PATH='I65',
 DRAWING='@T6G_MB_LIB.T6G(SCH_1):PAGE401',
 WATTAGE='1/20W',
 TOLERANCE='5%',
 MATERIAL='CHIP',
 PHYS_PAGE='320',
 XY='(-2575,2200)',
 ROT='0',
 VER='1',
 PACK_TYPE='0201LF',
 LOCATION='R6709',
 CDS_LIB='pure_quanta',
 CDS_PART_NAME='Q_RES_0201LF-0,5%,1/20W,CHIP,CS00001JE10',
 PART_NUMBER='CS00001JE10',
 VALUE='0',
 PRIM_FILE='./archive_libs/logical/q_res/chips/chips.prt';

PART_NAME
 R6710 'Q_RES_0402LF-0,5%,1/16W,CHIP,CS00002JB13':;

SECTION_NUMBER 1
 '@T6G_MB_LIB.T6G(SCH_1):PAGE80_I322@PURE_QUANTA.Q_RES(CHIPS)':
 C_PATH='@t6g_mb_lib.t6g(sch_1):page80_i322@pure_quanta.q_res(chips)',
 P_PATH='@t6g_mb_lib.t6g(sch_1):page81_i322@pure_quanta.q_res(chips)',
 PATH='I322',
 DRAWING='@T6G_MB_LIB.T6G(SCH_1):PAGE80',
 BOM_COST='MEM',
 WATTAGE='1/16W',
 TOLERANCE='5%',
 MATERIAL='CHIP',
 PHYS_PAGE='81',
 XY='(-6425,5775)',
 ROT='0',
 VER='1',
 PACK_TYPE='0402LF',
 LOCATION='R6710',
 CDS_LIB='pure_quanta',
 CDS_PART_NAME='Q_RES_0402LF-0,5%,1/16W,CHIP,CS00002JB13',
 PART_NUMBER='CS00002JB13',
 VALUE='0',
 PRIM_FILE='./archive_libs/logical/q_res/chips/chips.prt';

PART_NAME
 R6711 'Q_RES_0402LF-0,5%,1/16W,CHIP,CS00002JB13':;

SECTION_NUMBER 1
 '@T6G_MB_LIB.T6G(SCH_1):PAGE80_I324@PURE_QUANTA.Q_RES(CHIPS)':
 C_PATH='@t6g_mb_lib.t6g(sch_1):page80_i324@pure_quanta.q_res(chips)',
 P_PATH='@t6g_mb_lib.t6g(sch_1):page81_i324@pure_quanta.q_res(chips)',
 PATH='I324',
 DRAWING='@T6G_MB_LIB.T6G(SCH_1):PAGE80',
 BOM_COST='MEM',
 WATTAGE='1/16W',
 TOLERANCE='5%',
 MATERIAL='CHIP',
 PHYS_PAGE='81',
 XY='(-6425,5725)',
 ROT='0',
 VER='1',
 PACK_TYPE='0402LF',
 LOCATION='R6711',
 CDS_LIB='pure_quanta',
 CDS_PART_NAME='Q_RES_0402LF-0,5%,1/16W,CHIP,CS00002JB13',
 PART_NUMBER='CS00002JB13',
 VALUE='0',
 PRIM_FILE='./archive_libs/logical/q_res/chips/chips.prt';

PART_NAME
 R6712 'Q_RES_0201LF-1K,1%,1/20W,CHIP,CS21001FE07':;

SECTION_NUMBER 1
 '@T6G_MB_LIB.T6G(SCH_1):PAGE401_I102@PURE_QUANTA.Q_RES(CHIPS)':
 C_PATH='@t6g_mb_lib.t6g(sch_1):page401_i102@pure_quanta.q_res(chips)',
 P_PATH='@t6g_mb_lib.t6g(sch_1):page320_i102@pure_quanta.q_res(chips)',
 PATH='I102',
 DRAWING='@T6G_MB_LIB.T6G(SCH_1):PAGE401',
 WATTAGE='1/20W',
 TOLERANCE='1%',
 MATERIAL='CHIP',
 PHYS_PAGE='320',
 XY='(-3475,6100)',
 ROT='0',
 VER='2',
 PACK_TYPE='0201LF',
 LOCATION='R6712',
 CDS_LIB='pure_quanta',
 CDS_PART_NAME='Q_RES_0201LF-1K,1%,1/20W,CHIP,CS21001FE07',
 PART_NUMBER='CS21001FE07',
 VALUE='1K',
 PRIM_FILE='./archive_libs/logical/q_res/chips/chips.prt';

PART_NAME
 R6713 'Q_RES_0201LF-1K,1%,1/20W,EMPTY,CS21001FE07':;

SECTION_NUMBER 1
 '@T6G_MB_LIB.T6G(SCH_1):PAGE401_I103@PURE_QUANTA.Q_RES(CHIPS)':
 C_PATH='@t6g_mb_lib.t6g(sch_1):page401_i103@pure_quanta.q_res(chips)',
 P_PATH='@t6g_mb_lib.t6g(sch_1):page320_i103@pure_quanta.q_res(chips)',
 PATH='I103',
 DRAWING='@T6G_MB_LIB.T6G(SCH_1):PAGE401',
 WATTAGE='1/20W',
 TOLERANCE='1%',
 MATERIAL='EMPTY',
 PHYS_PAGE='320',
 XY='(-3475,5325)',
 ROT='0',
 VER='2',
 PACK_TYPE='0201LF',
 LOCATION='R6713',
 CDS_LIB='pure_quanta',
 CDS_PART_NAME='Q_RES_0201LF-1K,1%,1/20W,EMPTY,CS21001FE07',
 PART_NUMBER='CS21001FE07',
 VALUE='1K',
 PRIM_FILE='./archive_libs/logical/q_res/chips/chips.prt';

PART_NAME
 R6714 'Q_RES_0201LF-1K,1%,1/20W,EMPTY,CS21001FE07':;

SECTION_NUMBER 1
 '@T6G_MB_LIB.T6G(SCH_1):PAGE401_I104@PURE_QUANTA.Q_RES(CHIPS)':
 C_PATH='@t6g_mb_lib.t6g(sch_1):page401_i104@pure_quanta.q_res(chips)',
 P_PATH='@t6g_mb_lib.t6g(sch_1):page320_i104@pure_quanta.q_res(chips)',
 PATH='I104',
 DRAWING='@T6G_MB_LIB.T6G(SCH_1):PAGE401',
 WATTAGE='1/20W',
 TOLERANCE='1%',
 MATERIAL='EMPTY',
 PHYS_PAGE='320',
 XY='(-3175,6100)',
 ROT='0',
 VER='2',
 PACK_TYPE='0201LF',
 LOCATION='R6714',
 CDS_LIB='pure_quanta',
 CDS_PART_NAME='Q_RES_0201LF-1K,1%,1/20W,EMPTY,CS21001FE07',
 PART_NUMBER='CS21001FE07',
 VALUE='1K',
 PRIM_FILE='./archive_libs/logical/q_res/chips/chips.prt';

PART_NAME
 R6715 'Q_RES_0201LF-20K,1%,1/20W,CHIP,CS32001FE00':;

SECTION_NUMBER 1
 '@T6G_MB_LIB.T6G(SCH_1):PAGE401_I105@PURE_QUANTA.Q_RES(CHIPS)':
 C_PATH='@t6g_mb_lib.t6g(sch_1):page401_i105@pure_quanta.q_res(chips)',
 P_PATH='@t6g_mb_lib.t6g(sch_1):page320_i105@pure_quanta.q_res(chips)',
 PATH='I105',
 DRAWING='@T6G_MB_LIB.T6G(SCH_1):PAGE401',
 WATTAGE='1/20W',
 TOLERANCE='1%',
 MATERIAL='CHIP',
 PHYS_PAGE='320',
 XY='(-3175,5325)',
 ROT='0',
 VER='2',
 PACK_TYPE='0201LF',
 LOCATION='R6715',
 CDS_LIB='pure_quanta',
 CDS_PART_NAME='Q_RES_0201LF-20K,1%,1/20W,CHIP,CS32001FE00',
 PART_NUMBER='CS32001FE00',
 VALUE='20K',
 PRIM_FILE='./archive_libs/logical/q_res/chips/chips.prt';

PART_NAME
 R6716 'Q_RES_0201LF-1K,1%,1/20W,EMPTY,CS21001FE07':;

SECTION_NUMBER 1
 '@T6G_MB_LIB.T6G(SCH_1):PAGE401_I107@PURE_QUANTA.Q_RES(CHIPS)':
 C_PATH='@t6g_mb_lib.t6g(sch_1):page401_i107@pure_quanta.q_res(chips)',
 P_PATH='@t6g_mb_lib.t6g(sch_1):page320_i107@pure_quanta.q_res(chips)',
 PATH='I107',
 DRAWING='@T6G_MB_LIB.T6G(SCH_1):PAGE401',
 WATTAGE='1/20W',
 TOLERANCE='1%',
 MATERIAL='EMPTY',
 PHYS_PAGE='320',
 XY='(-2825,6075)',
 ROT='0',
 VER='2',
 PACK_TYPE='0201LF',
 LOCATION='R6716',
 CDS_LIB='pure_quanta',
 CDS_PART_NAME='Q_RES_0201LF-1K,1%,1/20W,EMPTY,CS21001FE07',
 PART_NUMBER='CS21001FE07',
 VALUE='1K',
 PRIM_FILE='./archive_libs/logical/q_res/chips/chips.prt';

PART_NAME
 R6717 'Q_RES_0201LF-1K,1%,1/20W,CHIP,CS21001FE07':;

SECTION_NUMBER 1
 '@T6G_MB_LIB.T6G(SCH_1):PAGE401_I106@PURE_QUANTA.Q_RES(CHIPS)':
 C_PATH='@t6g_mb_lib.t6g(sch_1):page401_i106@pure_quanta.q_res(chips)',
 P_PATH='@t6g_mb_lib.t6g(sch_1):page320_i106@pure_quanta.q_res(chips)',
 PATH='I106',
 DRAWING='@T6G_MB_LIB.T6G(SCH_1):PAGE401',
 WATTAGE='1/20W',
 TOLERANCE='1%',
 MATERIAL='CHIP',
 PHYS_PAGE='320',
 XY='(-2825,5325)',
 ROT='0',
 VER='2',
 PACK_TYPE='0201LF',
 LOCATION='R6717',
 CDS_LIB='pure_quanta',
 CDS_PART_NAME='Q_RES_0201LF-1K,1%,1/20W,CHIP,CS21001FE07',
 PART_NUMBER='CS21001FE07',
 VALUE='1K',
 PRIM_FILE='./archive_libs/logical/q_res/chips/chips.prt';

PART_NAME
 R6718 'Q_RES_0201LF-1K,1%,1/20W,CHIP,CS21001FE07':;

SECTION_NUMBER 1
 '@T6G_MB_LIB.T6G(SCH_1):PAGE378_I9@PURE_QUANTA.Q_RES(CHIPS)':
 C_PATH='@t6g_mb_lib.t6g(sch_1):page378_i9@pure_quanta.q_res(chips)',
 P_PATH='@t6g_mb_lib.t6g(sch_1):page184_i9@pure_quanta.q_res(chips)',
 PATH='I9',
 DRAWING='@T6G_MB_LIB.T6G(SCH_1):PAGE378',
 WATTAGE='1/20W',
 TOLERANCE='1%',
 MATERIAL='CHIP',
 PHYS_PAGE='184',
 XY='(-2625,1450)',
 ROT='0',
 VER='1',
 PACK_TYPE='0201LF',
 LOCATION='R6718',
 CDS_LIB='pure_quanta',
 CDS_PART_NAME='Q_RES_0201LF-1K,1%,1/20W,CHIP,CS21001FE07',
 PART_NUMBER='CS21001FE07',
 VALUE='1K',
 PRIM_FILE='./archive_libs/logical/q_res/chips/chips.prt';

PART_NAME
 R6719 'Q_RES_0201LF-1K,1%,1/20W,CHIP,CS21001FE07':;

SECTION_NUMBER 1
 '@T6G_MB_LIB.T6G(SCH_1):PAGE378_I11@PURE_QUANTA.Q_RES(CHIPS)':
 C_PATH='@t6g_mb_lib.t6g(sch_1):page378_i11@pure_quanta.q_res(chips)',
 P_PATH='@t6g_mb_lib.t6g(sch_1):page184_i11@pure_quanta.q_res(chips)',
 PATH='I11',
 DRAWING='@T6G_MB_LIB.T6G(SCH_1):PAGE378',
 WATTAGE='1/20W',
 TOLERANCE='1%',
 MATERIAL='CHIP',
 PHYS_PAGE='184',
 XY='(-2625,1350)',
 ROT='0',
 VER='1',
 PACK_TYPE='0201LF',
 LOCATION='R6719',
 CDS_LIB='pure_quanta',
 CDS_PART_NAME='Q_RES_0201LF-1K,1%,1/20W,CHIP,CS21001FE07',
 PART_NUMBER='CS21001FE07',
 VALUE='1K',
 PRIM_FILE='./archive_libs/logical/q_res/chips/chips.prt';

PART_NAME
 R6720 'Q_RES_0201LF-10K,1%,1/20W,CHIP,CS31001FE17':;

SECTION_NUMBER 1
 '@T6G_MB_LIB.T6G(SCH_1):PAGE401_I97@PURE_QUANTA.Q_RES(CHIPS)':
 C_PATH='@t6g_mb_lib.t6g(sch_1):page401_i97@pure_quanta.q_res(chips)',
 P_PATH='@t6g_mb_lib.t6g(sch_1):page320_i97@pure_quanta.q_res(chips)',
 PATH='I97',
 DRAWING='@T6G_MB_LIB.T6G(SCH_1):PAGE401',
 WATTAGE='1/20W',
 TOLERANCE='1%',
 MATERIAL='CHIP',
 PHYS_PAGE='320',
 XY='(-1300,5325)',
 ROT='0',
 VER='2',
 PACK_TYPE='0201LF',
 LOCATION='R6720',
 CDS_LIB='pure_quanta',
 CDS_PART_NAME='Q_RES_0201LF-10K,1%,1/20W,CHIP,CS31001FE17',
 PART_NUMBER='CS31001FE17',
 VALUE='10K',
 PRIM_FILE='./archive_libs/logical/q_res/chips/chips.prt';

PART_NAME
 R6721 'Q_RES_0201LF-10K,1%,1/20W,CHIP,CS31001FE17':;

SECTION_NUMBER 1
 '@T6G_MB_LIB.T6G(SCH_1):PAGE401_I96@PURE_QUANTA.Q_RES(CHIPS)':
 C_PATH='@t6g_mb_lib.t6g(sch_1):page401_i96@pure_quanta.q_res(chips)',
 P_PATH='@t6g_mb_lib.t6g(sch_1):page320_i96@pure_quanta.q_res(chips)',
 PATH='I96',
 DRAWING='@T6G_MB_LIB.T6G(SCH_1):PAGE401',
 WATTAGE='1/20W',
 TOLERANCE='1%',
 MATERIAL='CHIP',
 PHYS_PAGE='320',
 XY='(-1475,5325)',
 ROT='2',
 VER='2',
 PACK_TYPE='0201LF',
 LOCATION='R6721',
 CDS_LIB='pure_quanta',
 CDS_PART_NAME='Q_RES_0201LF-10K,1%,1/20W,CHIP,CS31001FE17',
 PART_NUMBER='CS31001FE17',
 VALUE='10K',
 PRIM_FILE='./archive_libs/logical/q_res/chips/chips.prt';

PART_NAME
 R6722 'Q_RES_0201LF-4.7K,5%,1/20W,EMPTY,CS24701JE04':;

SECTION_NUMBER 1
 '@T6G_MB_LIB.T6G(SCH_1):PAGE401_I85@PURE_QUANTA.Q_RES(CHIPS)':
 C_PATH='@t6g_mb_lib.t6g(sch_1):page401_i85@pure_quanta.q_res(chips)',
 P_PATH='@t6g_mb_lib.t6g(sch_1):page320_i85@pure_quanta.q_res(chips)',
 PATH='I85',
 DRAWING='@T6G_MB_LIB.T6G(SCH_1):PAGE401',
 WATTAGE='1/20W',
 TOLERANCE='5%',
 MATERIAL='EMPTY',
 PHYS_PAGE='320',
 XY='(-8975,4225)',
 ROT='0',
 VER='2',
 PACK_TYPE='0201LF',
 LOCATION='R6722',
 CDS_LIB='pure_quanta',
 CDS_PART_NAME='Q_RES_0201LF-4.7K,5%,1/20W,EMPTY,CS24701JE04',
 PART_NUMBER='CS24701JE04',
 VALUE='4.7K',
 PRIM_FILE='./archive_libs/logical/q_res/chips/chips.prt';

PART_NAME
 R6723 'Q_RES_0201LF-200,1%,1/20W,CHIP,CS12001FE12':;

SECTION_NUMBER 1
 '@T6G_MB_LIB.T6G(SCH_1):PAGE401_I128@PURE_QUANTA.Q_RES(CHIPS)':
 C_PATH='@t6g_mb_lib.t6g(sch_1):page401_i128@pure_quanta.q_res(chips)',
 P_PATH='@t6g_mb_lib.t6g(sch_1):page320_i128@pure_quanta.q_res(chips)',
 PATH='I128',
 DRAWING='@T6G_MB_LIB.T6G(SCH_1):PAGE401',
 WATTAGE='1/20W',
 TOLERANCE='1%',
 MATERIAL='CHIP',
 PHYS_PAGE='320',
 XY='(-8975,3550)',
 ROT='0',
 VER='2',
 PACK_TYPE='0201LF',
 LOCATION='R6723',
 CDS_LIB='pure_quanta',
 CDS_PART_NAME='Q_RES_0201LF-200,1%,1/20W,CHIP,CS12001FE12',
 PART_NUMBER='CS12001FE12',
 VALUE='200',
 PRIM_FILE='./archive_libs/logical/q_res/chips/chips.prt';

PART_NAME
 R6724 'Q_RES_0201LF-4.7K,5%,1/20W,EMPTY,CS24701JE04':;

SECTION_NUMBER 1
 '@T6G_MB_LIB.T6G(SCH_1):PAGE401_I101@PURE_QUANTA.Q_RES(CHIPS)':
 C_PATH='@t6g_mb_lib.t6g(sch_1):page401_i101@pure_quanta.q_res(chips)',
 P_PATH='@t6g_mb_lib.t6g(sch_1):page320_i101@pure_quanta.q_res(chips)',
 PATH='I101',
 DRAWING='@T6G_MB_LIB.T6G(SCH_1):PAGE401',
 WATTAGE='1/20W',
 TOLERANCE='5%',
 MATERIAL='EMPTY',
 PHYS_PAGE='320',
 XY='(-1475,6150)',
 ROT='2',
 VER='2',
 PACK_TYPE='0201LF',
 LOCATION='R6724',
 CDS_LIB='pure_quanta',
 CDS_PART_NAME='Q_RES_0201LF-4.7K,5%,1/20W,EMPTY,CS24701JE04',
 PART_NUMBER='CS24701JE04',
 VALUE='4.7K',
 PRIM_FILE='./archive_libs/logical/q_res/chips/chips.prt';

PART_NAME
 R6725 'Q_RES_0201LF-4.7K,5%,1/20W,EMPTY,CS24701JE04':;

SECTION_NUMBER 1
 '@T6G_MB_LIB.T6G(SCH_1):PAGE401_I91@PURE_QUANTA.Q_RES(CHIPS)':
 C_PATH='@t6g_mb_lib.t6g(sch_1):page401_i91@pure_quanta.q_res(chips)',
 P_PATH='@t6g_mb_lib.t6g(sch_1):page320_i91@pure_quanta.q_res(chips)',
 PATH='I91',
 DRAWING='@T6G_MB_LIB.T6G(SCH_1):PAGE401',
 WATTAGE='1/20W',
 TOLERANCE='5%',
 MATERIAL='EMPTY',
 PHYS_PAGE='320',
 XY='(-7425,6100)',
 ROT='0',
 VER='2',
 PACK_TYPE='0201LF',
 LOCATION='R6725',
 CDS_LIB='pure_quanta',
 CDS_PART_NAME='Q_RES_0201LF-4.7K,5%,1/20W,EMPTY,CS24701JE04',
 PART_NUMBER='CS24701JE04',
 VALUE='4.7K',
 PRIM_FILE='./archive_libs/logical/q_res/chips/chips.prt';

PART_NAME
 R6730 'Q_RES_0201LF-1K,1%,1/20W,EMPTY,CS21001FE07':;

SECTION_NUMBER 1
 '@T6G_MB_LIB.T6G(SCH_1):PAGE391_I21@PURE_QUANTA.Q_RES(CHIPS)':
 C_PATH='@t6g_mb_lib.t6g(sch_1):page391_i21@pure_quanta.q_res(chips)',
 P_PATH='@t6g_mb_lib.t6g(sch_1):page332_i21@pure_quanta.q_res(chips)',
 PATH='I21',
 DRAWING='@T6G_MB_LIB.T6G(SCH_1):PAGE391',
 WATTAGE='1/20W',
 TOLERANCE='1%',
 MATERIAL='EMPTY',
 PHYS_PAGE='332',
 XY='(-8500,3925)',
 ROT='0',
 VER='2',
 PACK_TYPE='0201LF',
 LOCATION='R6730',
 CDS_LIB='pure_quanta',
 CDS_PART_NAME='Q_RES_0201LF-1K,1%,1/20W,EMPTY,CS21001FE07',
 PART_NUMBER='CS21001FE07',
 VALUE='1K',
 PRIM_FILE='./archive_libs/logical/q_res/chips/chips.prt';

PART_NAME
 R6731 'Q_RES_0201LF-200,1%,1/20W,CHIP,CS12001FE12':;

SECTION_NUMBER 1
 '@T6G_MB_LIB.T6G(SCH_1):PAGE391_I20@PURE_QUANTA.Q_RES(CHIPS)':
 C_PATH='@t6g_mb_lib.t6g(sch_1):page391_i20@pure_quanta.q_res(chips)',
 P_PATH='@t6g_mb_lib.t6g(sch_1):page332_i20@pure_quanta.q_res(chips)',
 PATH='I20',
 DRAWING='@T6G_MB_LIB.T6G(SCH_1):PAGE391',
 WATTAGE='1/20W',
 TOLERANCE='1%',
 MATERIAL='CHIP',
 PHYS_PAGE='332',
 XY='(-7475,3375)',
 ROT='0',
 VER='2',
 PACK_TYPE='0201LF',
 LOCATION='R6731',
 CDS_LIB='pure_quanta',
 CDS_PART_NAME='Q_RES_0201LF-200,1%,1/20W,CHIP,CS12001FE12',
 PART_NUMBER='CS12001FE12',
 VALUE='200',
 PRIM_FILE='./archive_libs/logical/q_res/chips/chips.prt';

PART_NAME
 R6732 'Q_RES_0201LF-0,5%,1/20W,CHIP,CS00001JE10':;

SECTION_NUMBER 1
 '@T6G_MB_LIB.T6G(SCH_1):PAGE391_I16@PURE_QUANTA.Q_RES(CHIPS)':
 C_PATH='@t6g_mb_lib.t6g(sch_1):page391_i16@pure_quanta.q_res(chips)',
 P_PATH='@t6g_mb_lib.t6g(sch_1):page332_i16@pure_quanta.q_res(chips)',
 PATH='I16',
 DRAWING='@T6G_MB_LIB.T6G(SCH_1):PAGE391',
 WATTAGE='1/20W',
 TOLERANCE='5%',
 MATERIAL='CHIP',
 PHYS_PAGE='332',
 XY='(-1125,1825)',
 ROT='0',
 VER='2',
 PACK_TYPE='0201LF',
 LOCATION='R6732',
 CDS_LIB='pure_quanta',
 CDS_PART_NAME='Q_RES_0201LF-0,5%,1/20W,CHIP,CS00001JE10',
 PART_NUMBER='CS00001JE10',
 VALUE='0',
 PRIM_FILE='./archive_libs/logical/q_res/chips/chips.prt';

PART_NAME
 R6733 'Q_RES_0201LF-0,5%,1/20W,CHIP,CS00001JE10':;

SECTION_NUMBER 1
 '@T6G_MB_LIB.T6G(SCH_1):PAGE391_I15@PURE_QUANTA.Q_RES(CHIPS)':
 C_PATH='@t6g_mb_lib.t6g(sch_1):page391_i15@pure_quanta.q_res(chips)',
 P_PATH='@t6g_mb_lib.t6g(sch_1):page332_i15@pure_quanta.q_res(chips)',
 PATH='I15',
 DRAWING='@T6G_MB_LIB.T6G(SCH_1):PAGE391',
 WATTAGE='1/20W',
 TOLERANCE='5%',
 MATERIAL='CHIP',
 PHYS_PAGE='332',
 XY='(-1275,1275)',
 ROT='0',
 VER='2',
 PACK_TYPE='0201LF',
 LOCATION='R6733',
 CDS_LIB='pure_quanta',
 CDS_PART_NAME='Q_RES_0201LF-0,5%,1/20W,CHIP,CS00001JE10',
 PART_NUMBER='CS00001JE10',
 VALUE='0',
 PRIM_FILE='./archive_libs/logical/q_res/chips/chips.prt';

PART_NAME
 R6734 'Q_RES_0201LF-1K,1%,1/20W,CHIP,CS21001FE07':;

SECTION_NUMBER 1
 '@T6G_MB_LIB.T6G(SCH_1):PAGE377_I62@PURE_QUANTA.Q_RES(CHIPS)':
 C_PATH='@t6g_mb_lib.t6g(sch_1):page377_i62@pure_quanta.q_res(chips)',
 P_PATH='@t6g_mb_lib.t6g(sch_1):page185_i62@pure_quanta.q_res(chips)',
 PATH='I62',
 DRAWING='@T6G_MB_LIB.T6G(SCH_1):PAGE377',
 WATTAGE='1/20W',
 TOLERANCE='1%',
 MATERIAL='CHIP',
 PHYS_PAGE='185',
 XY='(-2550,1475)',
 ROT='0',
 VER='1',
 PACK_TYPE='0201LF',
 LOCATION='R6734',
 CDS_LIB='pure_quanta',
 CDS_PART_NAME='Q_RES_0201LF-1K,1%,1/20W,CHIP,CS21001FE07',
 PART_NUMBER='CS21001FE07',
 VALUE='1K',
 PRIM_FILE='./archive_libs/logical/q_res/chips/chips.prt';

PART_NAME
 R6735 'Q_RES_0201LF-1K,1%,1/20W,CHIP,CS21001FE07':;

SECTION_NUMBER 1
 '@T6G_MB_LIB.T6G(SCH_1):PAGE377_I63@PURE_QUANTA.Q_RES(CHIPS)':
 C_PATH='@t6g_mb_lib.t6g(sch_1):page377_i63@pure_quanta.q_res(chips)',
 P_PATH='@t6g_mb_lib.t6g(sch_1):page185_i63@pure_quanta.q_res(chips)',
 PATH='I63',
 DRAWING='@T6G_MB_LIB.T6G(SCH_1):PAGE377',
 WATTAGE='1/20W',
 TOLERANCE='1%',
 MATERIAL='CHIP',
 PHYS_PAGE='185',
 XY='(-2550,1550)',
 ROT='0',
 VER='1',
 PACK_TYPE='0201LF',
 LOCATION='R6735',
 CDS_LIB='pure_quanta',
 CDS_PART_NAME='Q_RES_0201LF-1K,1%,1/20W,CHIP,CS21001FE07',
 PART_NUMBER='CS21001FE07',
 VALUE='1K',
 PRIM_FILE='./archive_libs/logical/q_res/chips/chips.prt';

PART_NAME
 R6736 'Q_RES_0201LF-0,5%,1/20W,CHIP,CS00001JE10':;

SECTION_NUMBER 1
 '@T6G_MB_LIB.T6G(SCH_1):PAGE378_I13@PURE_QUANTA.Q_RES(CHIPS)':
 C_PATH='@t6g_mb_lib.t6g(sch_1):page378_i13@pure_quanta.q_res(chips)',
 P_PATH='@t6g_mb_lib.t6g(sch_1):page184_i13@pure_quanta.q_res(chips)',
 PATH='I13',
 DRAWING='@T6G_MB_LIB.T6G(SCH_1):PAGE378',
 WATTAGE='1/20W',
 TOLERANCE='5%',
 MATERIAL='CHIP',
 PHYS_PAGE='184',
 XY='(-6350,4500)',
 ROT='0',
 VER='1',
 PACK_TYPE='0201LF',
 LOCATION='R6736',
 CDS_LIB='pure_quanta',
 CDS_PART_NAME='Q_RES_0201LF-0,5%,1/20W,CHIP,CS00001JE10',
 PART_NUMBER='CS00001JE10',
 VALUE='0',
 PRIM_FILE='./archive_libs/logical/q_res/chips/chips.prt';

PART_NAME
 R6737 'Q_RES_0201LF-0,5%,1/20W,CHIP,CS00001JE10':;

SECTION_NUMBER 1
 '@T6G_MB_LIB.T6G(SCH_1):PAGE378_I14@PURE_QUANTA.Q_RES(CHIPS)':
 C_PATH='@t6g_mb_lib.t6g(sch_1):page378_i14@pure_quanta.q_res(chips)',
 P_PATH='@t6g_mb_lib.t6g(sch_1):page184_i14@pure_quanta.q_res(chips)',
 PATH='I14',
 DRAWING='@T6G_MB_LIB.T6G(SCH_1):PAGE378',
 WATTAGE='1/20W',
 TOLERANCE='5%',
 MATERIAL='CHIP',
 PHYS_PAGE='184',
 XY='(-6350,4450)',
 ROT='0',
 VER='1',
 PACK_TYPE='0201LF',
 LOCATION='R6737',
 CDS_LIB='pure_quanta',
 CDS_PART_NAME='Q_RES_0201LF-0,5%,1/20W,CHIP,CS00001JE10',
 PART_NUMBER='CS00001JE10',
 VALUE='0',
 PRIM_FILE='./archive_libs/logical/q_res/chips/chips.prt';

PART_NAME
 R6738 'Q_RES_0201LF-1K,1%,1/20W,CHIP,CS21001FE07':;

SECTION_NUMBER 1
 '@T6G_MB_LIB.T6G(SCH_1):PAGE378_I17@PURE_QUANTA.Q_RES(CHIPS)':
 C_PATH='@t6g_mb_lib.t6g(sch_1):page378_i17@pure_quanta.q_res(chips)',
 P_PATH='@t6g_mb_lib.t6g(sch_1):page184_i17@pure_quanta.q_res(chips)',
 PATH='I17',
 DRAWING='@T6G_MB_LIB.T6G(SCH_1):PAGE378',
 WATTAGE='1/20W',
 TOLERANCE='1%',
 MATERIAL='CHIP',
 PHYS_PAGE='184',
 XY='(-2625,1275)',
 ROT='0',
 VER='1',
 PACK_TYPE='0201LF',
 LOCATION='R6738',
 CDS_LIB='pure_quanta',
 CDS_PART_NAME='Q_RES_0201LF-1K,1%,1/20W,CHIP,CS21001FE07',
 PART_NUMBER='CS21001FE07',
 VALUE='1K',
 PRIM_FILE='./archive_libs/logical/q_res/chips/chips.prt';

PART_NAME
 R6739 'Q_RES_0201LF-1K,1%,1/20W,CHIP,CS21001FE07':;

SECTION_NUMBER 1
 '@T6G_MB_LIB.T6G(SCH_1):PAGE378_I18@PURE_QUANTA.Q_RES(CHIPS)':
 C_PATH='@t6g_mb_lib.t6g(sch_1):page378_i18@pure_quanta.q_res(chips)',
 P_PATH='@t6g_mb_lib.t6g(sch_1):page184_i18@pure_quanta.q_res(chips)',
 PATH='I18',
 DRAWING='@T6G_MB_LIB.T6G(SCH_1):PAGE378',
 WATTAGE='1/20W',
 TOLERANCE='1%',
 MATERIAL='CHIP',
 PHYS_PAGE='184',
 XY='(-2625,1200)',
 ROT='0',
 VER='1',
 PACK_TYPE='0201LF',
 LOCATION='R6739',
 CDS_LIB='pure_quanta',
 CDS_PART_NAME='Q_RES_0201LF-1K,1%,1/20W,CHIP,CS21001FE07',
 PART_NUMBER='CS21001FE07',
 VALUE='1K',
 PRIM_FILE='./archive_libs/logical/q_res/chips/chips.prt';

PART_NAME
 R6740 'Q_RES_0402LF-0,5%,1/16W,CHIP,CS00002JB13':;

SECTION_NUMBER 1
 '@T6G_MB_LIB.T6G(SCH_1):PAGE80_I326@PURE_QUANTA.Q_RES(CHIPS)':
 C_PATH='@t6g_mb_lib.t6g(sch_1):page80_i326@pure_quanta.q_res(chips)',
 P_PATH='@t6g_mb_lib.t6g(sch_1):page81_i326@pure_quanta.q_res(chips)',
 PATH='I326',
 DRAWING='@T6G_MB_LIB.T6G(SCH_1):PAGE80',
 BOM_COST='MEM',
 WATTAGE='1/16W',
 TOLERANCE='5%',
 MATERIAL='CHIP',
 PHYS_PAGE='81',
 XY='(-6425,5275)',
 ROT='0',
 VER='1',
 PACK_TYPE='0402LF',
 LOCATION='R6740',
 CDS_LIB='pure_quanta',
 CDS_PART_NAME='Q_RES_0402LF-0,5%,1/16W,CHIP,CS00002JB13',
 PART_NUMBER='CS00002JB13',
 VALUE='0',
 PRIM_FILE='./archive_libs/logical/q_res/chips/chips.prt';

PART_NAME
 R6741 'Q_RES_0402LF-0,5%,1/16W,CHIP,CS00002JB13':;

SECTION_NUMBER 1
 '@T6G_MB_LIB.T6G(SCH_1):PAGE80_I327@PURE_QUANTA.Q_RES(CHIPS)':
 C_PATH='@t6g_mb_lib.t6g(sch_1):page80_i327@pure_quanta.q_res(chips)',
 P_PATH='@t6g_mb_lib.t6g(sch_1):page81_i327@pure_quanta.q_res(chips)',
 PATH='I327',
 DRAWING='@T6G_MB_LIB.T6G(SCH_1):PAGE80',
 BOM_COST='MEM',
 WATTAGE='1/16W',
 TOLERANCE='5%',
 MATERIAL='CHIP',
 PHYS_PAGE='81',
 XY='(-6425,5225)',
 ROT='0',
 VER='1',
 PACK_TYPE='0402LF',
 LOCATION='R6741',
 CDS_LIB='pure_quanta',
 CDS_PART_NAME='Q_RES_0402LF-0,5%,1/16W,CHIP,CS00002JB13',
 PART_NUMBER='CS00002JB13',
 VALUE='0',
 PRIM_FILE='./archive_libs/logical/q_res/chips/chips.prt';

PART_NAME
 R6742 'Q_RES_0402LF-1K,1%,1/16W,EMPTY,CS21002FB06':;

SECTION_NUMBER 1
 '@T6G_MB_LIB.T6G(SCH_1):PAGE467_I5@PURE_QUANTA.Q_RES(CHIPS)':
 C_PATH='@t6g_mb_lib.t6g(sch_1):page467_i5@pure_quanta.q_res(chips)',
 P_PATH='@t6g_mb_lib.t6g(sch_1):page358_i5@pure_quanta.q_res(chips)',
 PATH='I5',
 DRAWING='@T6G_MB_LIB.T6G(SCH_1):PAGE467',
 WATTAGE='1/16W',
 TOLERANCE='1%',
 MATERIAL='EMPTY',
 PHYS_PAGE='358',
 XY='(-6075,5200)',
 ROT='0',
 VER='2',
 PACK_TYPE='0402LF',
 LOCATION='R6742',
 CDS_LIB='pure_quanta',
 CDS_PART_NAME='Q_RES_0402LF-1K,1%,1/16W,EMPTY,CS21002FB06',
 PART_NUMBER='CS21002FB06',
 VALUE='1K',
 PRIM_FILE='./archive_libs/logical/q_res/chips/chips.prt';

PART_NAME
 R6743 'Q_RES_0402LF-1K,1%,1/16W,EMPTY,CS21002FB06':;

SECTION_NUMBER 1
 '@T6G_MB_LIB.T6G(SCH_1):PAGE467_I6@PURE_QUANTA.Q_RES(CHIPS)':
 C_PATH='@t6g_mb_lib.t6g(sch_1):page467_i6@pure_quanta.q_res(chips)',
 P_PATH='@t6g_mb_lib.t6g(sch_1):page358_i6@pure_quanta.q_res(chips)',
 PATH='I6',
 DRAWING='@T6G_MB_LIB.T6G(SCH_1):PAGE467',
 WATTAGE='1/16W',
 TOLERANCE='1%',
 MATERIAL='EMPTY',
 PHYS_PAGE='358',
 XY='(-5725,5200)',
 ROT='0',
 VER='2',
 PACK_TYPE='0402LF',
 LOCATION='R6743',
 CDS_LIB='pure_quanta',
 CDS_PART_NAME='Q_RES_0402LF-1K,1%,1/16W,EMPTY,CS21002FB06',
 PART_NUMBER='CS21002FB06',
 VALUE='1K',
 PRIM_FILE='./archive_libs/logical/q_res/chips/chips.prt';

PART_NAME
 R6744 'Q_RES_0402LF-1K,1%,1/16W,CHIP,CS21002FB06':;

SECTION_NUMBER 1
 '@T6G_MB_LIB.T6G(SCH_1):PAGE467_I2@PURE_QUANTA.Q_RES(CHIPS)':
 C_PATH='@t6g_mb_lib.t6g(sch_1):page467_i2@pure_quanta.q_res(chips)',
 P_PATH='@t6g_mb_lib.t6g(sch_1):page358_i2@pure_quanta.q_res(chips)',
 PATH='I2',
 DRAWING='@T6G_MB_LIB.T6G(SCH_1):PAGE467',
 WATTAGE='1/16W',
 TOLERANCE='1%',
 MATERIAL='CHIP',
 PHYS_PAGE='358',
 XY='(-6075,4250)',
 ROT='0',
 VER='2',
 PACK_TYPE='0402LF',
 LOCATION='R6744',
 CDS_LIB='pure_quanta',
 CDS_PART_NAME='Q_RES_0402LF-1K,1%,1/16W,CHIP,CS21002FB06',
 PART_NUMBER='CS21002FB06',
 VALUE='1K',
 PRIM_FILE='./archive_libs/logical/q_res/chips/chips.prt';

PART_NAME
 R6745 'Q_RES_0402LF-1K,1%,1/16W,CHIP,CS21002FB06':;

SECTION_NUMBER 1
 '@T6G_MB_LIB.T6G(SCH_1):PAGE467_I4@PURE_QUANTA.Q_RES(CHIPS)':
 C_PATH='@t6g_mb_lib.t6g(sch_1):page467_i4@pure_quanta.q_res(chips)',
 P_PATH='@t6g_mb_lib.t6g(sch_1):page358_i4@pure_quanta.q_res(chips)',
 PATH='I4',
 DRAWING='@T6G_MB_LIB.T6G(SCH_1):PAGE467',
 WATTAGE='1/16W',
 TOLERANCE='1%',
 MATERIAL='CHIP',
 PHYS_PAGE='358',
 XY='(-5725,4250)',
 ROT='0',
 VER='2',
 PACK_TYPE='0402LF',
 LOCATION='R6745',
 CDS_LIB='pure_quanta',
 CDS_PART_NAME='Q_RES_0402LF-1K,1%,1/16W,CHIP,CS21002FB06',
 PART_NUMBER='CS21002FB06',
 VALUE='1K',
 PRIM_FILE='./archive_libs/logical/q_res/chips/chips.prt';

PART_NAME
 R6746 'Q_RES_0201LF-0,5%,1/20W,CHIP,CS00001JE10':;

SECTION_NUMBER 1
 '@T6G_MB_LIB.T6G(SCH_1):PAGE378_I22@PURE_QUANTA.Q_RES(CHIPS)':
 C_PATH='@t6g_mb_lib.t6g(sch_1):page378_i22@pure_quanta.q_res(chips)',
 P_PATH='@t6g_mb_lib.t6g(sch_1):page184_i22@pure_quanta.q_res(chips)',
 PATH='I22',
 DRAWING='@T6G_MB_LIB.T6G(SCH_1):PAGE378',
 WATTAGE='1/20W',
 TOLERANCE='5%',
 MATERIAL='CHIP',
 PHYS_PAGE='184',
 XY='(-6350,4400)',
 ROT='0',
 VER='1',
 PACK_TYPE='0201LF',
 LOCATION='R6746',
 CDS_LIB='pure_quanta',
 CDS_PART_NAME='Q_RES_0201LF-0,5%,1/20W,CHIP,CS00001JE10',
 PART_NUMBER='CS00001JE10',
 VALUE='0',
 PRIM_FILE='./archive_libs/logical/q_res/chips/chips.prt';

PART_NAME
 R6747 'Q_RES_0201LF-0,5%,1/20W,CHIP,CS00001JE10':;

SECTION_NUMBER 1
 '@T6G_MB_LIB.T6G(SCH_1):PAGE378_I21@PURE_QUANTA.Q_RES(CHIPS)':
 C_PATH='@t6g_mb_lib.t6g(sch_1):page378_i21@pure_quanta.q_res(chips)',
 P_PATH='@t6g_mb_lib.t6g(sch_1):page184_i21@pure_quanta.q_res(chips)',
 PATH='I21',
 DRAWING='@T6G_MB_LIB.T6G(SCH_1):PAGE378',
 WATTAGE='1/20W',
 TOLERANCE='5%',
 MATERIAL='CHIP',
 PHYS_PAGE='184',
 XY='(-6350,4350)',
 ROT='0',
 VER='1',
 PACK_TYPE='0201LF',
 LOCATION='R6747',
 CDS_LIB='pure_quanta',
 CDS_PART_NAME='Q_RES_0201LF-0,5%,1/20W,CHIP,CS00001JE10',
 PART_NUMBER='CS00001JE10',
 VALUE='0',
 PRIM_FILE='./archive_libs/logical/q_res/chips/chips.prt';

PART_NAME
 R6748 'Q_RES_0201LF-0,5%,1/20W,CHIP,CS00001JE10':;

SECTION_NUMBER 1
 '@T6G_MB_LIB.T6G(SCH_1):PAGE378_I26@PURE_QUANTA.Q_RES(CHIPS)':
 C_PATH='@t6g_mb_lib.t6g(sch_1):page378_i26@pure_quanta.q_res(chips)',
 P_PATH='@t6g_mb_lib.t6g(sch_1):page184_i26@pure_quanta.q_res(chips)',
 PATH='I26',
 DRAWING='@T6G_MB_LIB.T6G(SCH_1):PAGE378',
 WATTAGE='1/20W',
 TOLERANCE='5%',
 MATERIAL='CHIP',
 PHYS_PAGE='184',
 XY='(-6350,4300)',
 ROT='0',
 VER='1',
 PACK_TYPE='0201LF',
 LOCATION='R6748',
 CDS_LIB='pure_quanta',
 CDS_PART_NAME='Q_RES_0201LF-0,5%,1/20W,CHIP,CS00001JE10',
 PART_NUMBER='CS00001JE10',
 VALUE='0',
 PRIM_FILE='./archive_libs/logical/q_res/chips/chips.prt';

PART_NAME
 R6749 'Q_RES_0201LF-0,5%,1/20W,CHIP,CS00001JE10':;

SECTION_NUMBER 1
 '@T6G_MB_LIB.T6G(SCH_1):PAGE378_I25@PURE_QUANTA.Q_RES(CHIPS)':
 C_PATH='@t6g_mb_lib.t6g(sch_1):page378_i25@pure_quanta.q_res(chips)',
 P_PATH='@t6g_mb_lib.t6g(sch_1):page184_i25@pure_quanta.q_res(chips)',
 PATH='I25',
 DRAWING='@T6G_MB_LIB.T6G(SCH_1):PAGE378',
 WATTAGE='1/20W',
 TOLERANCE='5%',
 MATERIAL='CHIP',
 PHYS_PAGE='184',
 XY='(-6350,4250)',
 ROT='0',
 VER='1',
 PACK_TYPE='0201LF',
 LOCATION='R6749',
 CDS_LIB='pure_quanta',
 CDS_PART_NAME='Q_RES_0201LF-0,5%,1/20W,CHIP,CS00001JE10',
 PART_NUMBER='CS00001JE10',
 VALUE='0',
 PRIM_FILE='./archive_libs/logical/q_res/chips/chips.prt';

PART_NAME
 R6750 'Q_RES_0201LF-1K,1%,1/20W,CHIP,CS21001FE07':;

SECTION_NUMBER 1
 '@T6G_MB_LIB.T6G(SCH_1):PAGE378_I31@PURE_QUANTA.Q_RES(CHIPS)':
 C_PATH='@t6g_mb_lib.t6g(sch_1):page378_i31@pure_quanta.q_res(chips)',
 P_PATH='@t6g_mb_lib.t6g(sch_1):page184_i31@pure_quanta.q_res(chips)',
 PATH='I31',
 DRAWING='@T6G_MB_LIB.T6G(SCH_1):PAGE378',
 WATTAGE='1/20W',
 TOLERANCE='1%',
 MATERIAL='CHIP',
 PHYS_PAGE='184',
 XY='(-2625,1100)',
 ROT='0',
 VER='1',
 PACK_TYPE='0201LF',
 LOCATION='R6750',
 CDS_LIB='pure_quanta',
 CDS_PART_NAME='Q_RES_0201LF-1K,1%,1/20W,CHIP,CS21001FE07',
 PART_NUMBER='CS21001FE07',
 VALUE='1K',
 PRIM_FILE='./archive_libs/logical/q_res/chips/chips.prt';

PART_NAME
 R6751 'Q_RES_0201LF-1K,1%,1/20W,CHIP,CS21001FE07':;

SECTION_NUMBER 1
 '@T6G_MB_LIB.T6G(SCH_1):PAGE378_I32@PURE_QUANTA.Q_RES(CHIPS)':
 C_PATH='@t6g_mb_lib.t6g(sch_1):page378_i32@pure_quanta.q_res(chips)',
 P_PATH='@t6g_mb_lib.t6g(sch_1):page184_i32@pure_quanta.q_res(chips)',
 PATH='I32',
 DRAWING='@T6G_MB_LIB.T6G(SCH_1):PAGE378',
 WATTAGE='1/20W',
 TOLERANCE='1%',
 MATERIAL='CHIP',
 PHYS_PAGE='184',
 XY='(-2625,1025)',
 ROT='0',
 VER='1',
 PACK_TYPE='0201LF',
 LOCATION='R6751',
 CDS_LIB='pure_quanta',
 CDS_PART_NAME='Q_RES_0201LF-1K,1%,1/20W,CHIP,CS21001FE07',
 PART_NUMBER='CS21001FE07',
 VALUE='1K',
 PRIM_FILE='./archive_libs/logical/q_res/chips/chips.prt';

PART_NAME
 R6752 'Q_RES_0201LF-1K,1%,1/20W,CHIP,CS21001FE07':;

SECTION_NUMBER 1
 '@T6G_MB_LIB.T6G(SCH_1):PAGE378_I35@PURE_QUANTA.Q_RES(CHIPS)':
 C_PATH='@t6g_mb_lib.t6g(sch_1):page378_i35@pure_quanta.q_res(chips)',
 P_PATH='@t6g_mb_lib.t6g(sch_1):page184_i35@pure_quanta.q_res(chips)',
 PATH='I35',
 DRAWING='@T6G_MB_LIB.T6G(SCH_1):PAGE378',
 WATTAGE='1/20W',
 TOLERANCE='1%',
 MATERIAL='CHIP',
 PHYS_PAGE='184',
 XY='(-2625,950)',
 ROT='0',
 VER='1',
 PACK_TYPE='0201LF',
 LOCATION='R6752',
 CDS_LIB='pure_quanta',
 CDS_PART_NAME='Q_RES_0201LF-1K,1%,1/20W,CHIP,CS21001FE07',
 PART_NUMBER='CS21001FE07',
 VALUE='1K',
 PRIM_FILE='./archive_libs/logical/q_res/chips/chips.prt';

PART_NAME
 R6753 'Q_RES_0201LF-1K,1%,1/20W,CHIP,CS21001FE07':;

SECTION_NUMBER 1
 '@T6G_MB_LIB.T6G(SCH_1):PAGE378_I36@PURE_QUANTA.Q_RES(CHIPS)':
 C_PATH='@t6g_mb_lib.t6g(sch_1):page378_i36@pure_quanta.q_res(chips)',
 P_PATH='@t6g_mb_lib.t6g(sch_1):page184_i36@pure_quanta.q_res(chips)',
 PATH='I36',
 DRAWING='@T6G_MB_LIB.T6G(SCH_1):PAGE378',
 WATTAGE='1/20W',
 TOLERANCE='1%',
 MATERIAL='CHIP',
 PHYS_PAGE='184',
 XY='(-2625,875)',
 ROT='0',
 VER='1',
 PACK_TYPE='0201LF',
 LOCATION='R6753',
 CDS_LIB='pure_quanta',
 CDS_PART_NAME='Q_RES_0201LF-1K,1%,1/20W,CHIP,CS21001FE07',
 PART_NUMBER='CS21001FE07',
 VALUE='1K',
 PRIM_FILE='./archive_libs/logical/q_res/chips/chips.prt';

PART_NAME
 R6754 'Q_RES_0201LF-0,5%,1/20W,CHIP,CS00001JE10':;

SECTION_NUMBER 1
 '@T6G_MB_LIB.T6G(SCH_1):PAGE378_I53@PURE_QUANTA.Q_RES(CHIPS)':
 C_PATH='@t6g_mb_lib.t6g(sch_1):page378_i53@pure_quanta.q_res(chips)',
 P_PATH='@t6g_mb_lib.t6g(sch_1):page184_i53@pure_quanta.q_res(chips)',
 PATH='I53',
 DRAWING='@T6G_MB_LIB.T6G(SCH_1):PAGE378',
 SEC_TYPE='0201LF',
 WATTAGE='1/20W',
 TOLERANCE='5%',
 MATERIAL='CHIP',
 PHYS_PAGE='184',
 XY='(-3100,4600)',
 ROT='0',
 VER='1',
 PACK_TYPE='0201LF',
 LOCATION='R6754',
 SEC='1',
 CDS_LIB='pure_quanta',
 CDS_PART_NAME='Q_RES_0201LF-0,5%,1/20W,CHIP,CS00001JE10',
 PART_NUMBER='CS00001JE10',
 VALUE='0',
 PRIM_FILE='./archive_libs/logical/q_res/chips/chips.prt';

PART_NAME
 R6755 'Q_RES_0201LF-0,5%,1/20W,CHIP,CS00001JE10':;

SECTION_NUMBER 1
 '@T6G_MB_LIB.T6G(SCH_1):PAGE378_I54@PURE_QUANTA.Q_RES(CHIPS)':
 C_PATH='@t6g_mb_lib.t6g(sch_1):page378_i54@pure_quanta.q_res(chips)',
 P_PATH='@t6g_mb_lib.t6g(sch_1):page184_i54@pure_quanta.q_res(chips)',
 PATH='I54',
 DRAWING='@T6G_MB_LIB.T6G(SCH_1):PAGE378',
 SEC_TYPE='0201LF',
 WATTAGE='1/20W',
 TOLERANCE='5%',
 MATERIAL='CHIP',
 PHYS_PAGE='184',
 XY='(-3100,4550)',
 ROT='0',
 VER='1',
 PACK_TYPE='0201LF',
 LOCATION='R6755',
 SEC='1',
 CDS_LIB='pure_quanta',
 CDS_PART_NAME='Q_RES_0201LF-0,5%,1/20W,CHIP,CS00001JE10',
 PART_NUMBER='CS00001JE10',
 VALUE='0',
 PRIM_FILE='./archive_libs/logical/q_res/chips/chips.prt';

PART_NAME
 R6756 'Q_RES_0201LF-0,5%,1/20W,CHIP,CS00001JE10':;

SECTION_NUMBER 1
 '@T6G_MB_LIB.T6G(SCH_1):PAGE378_I56@PURE_QUANTA.Q_RES(CHIPS)':
 C_PATH='@t6g_mb_lib.t6g(sch_1):page378_i56@pure_quanta.q_res(chips)',
 P_PATH='@t6g_mb_lib.t6g(sch_1):page184_i56@pure_quanta.q_res(chips)',
 PATH='I56',
 DRAWING='@T6G_MB_LIB.T6G(SCH_1):PAGE378',
 WATTAGE='1/20W',
 TOLERANCE='5%',
 MATERIAL='CHIP',
 PHYS_PAGE='184',
 XY='(-3100,4500)',
 ROT='0',
 VER='1',
 PACK_TYPE='0201LF',
 LOCATION='R6756',
 CDS_LIB='pure_quanta',
 CDS_PART_NAME='Q_RES_0201LF-0,5%,1/20W,CHIP,CS00001JE10',
 PART_NUMBER='CS00001JE10',
 VALUE='0',
 PRIM_FILE='./archive_libs/logical/q_res/chips/chips.prt';

PART_NAME
 R6757 'Q_RES_0201LF-0,5%,1/20W,CHIP,CS00001JE10':;

SECTION_NUMBER 1
 '@T6G_MB_LIB.T6G(SCH_1):PAGE378_I57@PURE_QUANTA.Q_RES(CHIPS)':
 C_PATH='@t6g_mb_lib.t6g(sch_1):page378_i57@pure_quanta.q_res(chips)',
 P_PATH='@t6g_mb_lib.t6g(sch_1):page184_i57@pure_quanta.q_res(chips)',
 PATH='I57',
 DRAWING='@T6G_MB_LIB.T6G(SCH_1):PAGE378',
 WATTAGE='1/20W',
 TOLERANCE='5%',
 MATERIAL='CHIP',
 PHYS_PAGE='184',
 XY='(-3100,4450)',
 ROT='0',
 VER='1',
 PACK_TYPE='0201LF',
 LOCATION='R6757',
 CDS_LIB='pure_quanta',
 CDS_PART_NAME='Q_RES_0201LF-0,5%,1/20W,CHIP,CS00001JE10',
 PART_NUMBER='CS00001JE10',
 VALUE='0',
 PRIM_FILE='./archive_libs/logical/q_res/chips/chips.prt';

PART_NAME
 R6758 'Q_RES_0201LF-0,5%,1/20W,CHIP,CS00001JE10':;

SECTION_NUMBER 1
 '@T6G_MB_LIB.T6G(SCH_1):PAGE378_I55@PURE_QUANTA.Q_RES(CHIPS)':
 C_PATH='@t6g_mb_lib.t6g(sch_1):page378_i55@pure_quanta.q_res(chips)',
 P_PATH='@t6g_mb_lib.t6g(sch_1):page184_i55@pure_quanta.q_res(chips)',
 PATH='I55',
 DRAWING='@T6G_MB_LIB.T6G(SCH_1):PAGE378',
 WATTAGE='1/20W',
 TOLERANCE='5%',
 MATERIAL='CHIP',
 PHYS_PAGE='184',
 XY='(-3100,4400)',
 ROT='0',
 VER='1',
 PACK_TYPE='0201LF',
 LOCATION='R6758',
 CDS_LIB='pure_quanta',
 CDS_PART_NAME='Q_RES_0201LF-0,5%,1/20W,CHIP,CS00001JE10',
 PART_NUMBER='CS00001JE10',
 VALUE='0',
 PRIM_FILE='./archive_libs/logical/q_res/chips/chips.prt';

PART_NAME
 R6759 'Q_RES_0201LF-0,5%,1/20W,CHIP,CS00001JE10':;

SECTION_NUMBER 1
 '@T6G_MB_LIB.T6G(SCH_1):PAGE378_I59@PURE_QUANTA.Q_RES(CHIPS)':
 C_PATH='@t6g_mb_lib.t6g(sch_1):page378_i59@pure_quanta.q_res(chips)',
 P_PATH='@t6g_mb_lib.t6g(sch_1):page184_i59@pure_quanta.q_res(chips)',
 PATH='I59',
 DRAWING='@T6G_MB_LIB.T6G(SCH_1):PAGE378',
 WATTAGE='1/20W',
 TOLERANCE='5%',
 MATERIAL='CHIP',
 PHYS_PAGE='184',
 XY='(-3100,4350)',
 ROT='0',
 VER='1',
 PACK_TYPE='0201LF',
 LOCATION='R6759',
 CDS_LIB='pure_quanta',
 CDS_PART_NAME='Q_RES_0201LF-0,5%,1/20W,CHIP,CS00001JE10',
 PART_NUMBER='CS00001JE10',
 VALUE='0',
 PRIM_FILE='./archive_libs/logical/q_res/chips/chips.prt';

PART_NAME
 R6760 'Q_RES_0201LF-0,5%,1/20W,CHIP,CS00001JE10':;

SECTION_NUMBER 1
 '@T6G_MB_LIB.T6G(SCH_1):PAGE378_I58@PURE_QUANTA.Q_RES(CHIPS)':
 C_PATH='@t6g_mb_lib.t6g(sch_1):page378_i58@pure_quanta.q_res(chips)',
 P_PATH='@t6g_mb_lib.t6g(sch_1):page184_i58@pure_quanta.q_res(chips)',
 PATH='I58',
 DRAWING='@T6G_MB_LIB.T6G(SCH_1):PAGE378',
 WATTAGE='1/20W',
 TOLERANCE='5%',
 MATERIAL='CHIP',
 PHYS_PAGE='184',
 XY='(-3100,4300)',
 ROT='0',
 VER='1',
 PACK_TYPE='0201LF',
 LOCATION='R6760',
 CDS_LIB='pure_quanta',
 CDS_PART_NAME='Q_RES_0201LF-0,5%,1/20W,CHIP,CS00001JE10',
 PART_NUMBER='CS00001JE10',
 VALUE='0',
 PRIM_FILE='./archive_libs/logical/q_res/chips/chips.prt';

PART_NAME
 R6761 'Q_RES_0201LF-0,5%,1/20W,CHIP,CS00001JE10':;

SECTION_NUMBER 1
 '@T6G_MB_LIB.T6G(SCH_1):PAGE378_I60@PURE_QUANTA.Q_RES(CHIPS)':
 C_PATH='@t6g_mb_lib.t6g(sch_1):page378_i60@pure_quanta.q_res(chips)',
 P_PATH='@t6g_mb_lib.t6g(sch_1):page184_i60@pure_quanta.q_res(chips)',
 PATH='I60',
 DRAWING='@T6G_MB_LIB.T6G(SCH_1):PAGE378',
 WATTAGE='1/20W',
 TOLERANCE='5%',
 MATERIAL='CHIP',
 PHYS_PAGE='184',
 XY='(-3100,4250)',
 ROT='0',
 VER='1',
 PACK_TYPE='0201LF',
 LOCATION='R6761',
 CDS_LIB='pure_quanta',
 CDS_PART_NAME='Q_RES_0201LF-0,5%,1/20W,CHIP,CS00001JE10',
 PART_NUMBER='CS00001JE10',
 VALUE='0',
 PRIM_FILE='./archive_libs/logical/q_res/chips/chips.prt';

PART_NAME
 R6762 'Q_RES_0201LF-1K,1%,1/20W,CHIP,CS21001FE07':;

SECTION_NUMBER 1
 '@T6G_MB_LIB.T6G(SCH_1):PAGE378_I77@PURE_QUANTA.Q_RES(CHIPS)':
 C_PATH='@t6g_mb_lib.t6g(sch_1):page378_i77@pure_quanta.q_res(chips)',
 P_PATH='@t6g_mb_lib.t6g(sch_1):page184_i77@pure_quanta.q_res(chips)',
 PATH='I77',
 DRAWING='@T6G_MB_LIB.T6G(SCH_1):PAGE378',
 WATTAGE='1/20W',
 TOLERANCE='1%',
 MATERIAL='CHIP',
 PHYS_PAGE='184',
 XY='(-5950,1525)',
 ROT='0',
 VER='1',
 PACK_TYPE='0201LF',
 LOCATION='R6762',
 CDS_LIB='pure_quanta',
 CDS_PART_NAME='Q_RES_0201LF-1K,1%,1/20W,CHIP,CS21001FE07',
 PART_NUMBER='CS21001FE07',
 VALUE='1K',
 PRIM_FILE='./archive_libs/logical/q_res/chips/chips.prt';

PART_NAME
 R6763 'Q_RES_0201LF-1K,1%,1/20W,CHIP,CS21001FE07':;

SECTION_NUMBER 1
 '@T6G_MB_LIB.T6G(SCH_1):PAGE378_I78@PURE_QUANTA.Q_RES(CHIPS)':
 C_PATH='@t6g_mb_lib.t6g(sch_1):page378_i78@pure_quanta.q_res(chips)',
 P_PATH='@t6g_mb_lib.t6g(sch_1):page184_i78@pure_quanta.q_res(chips)',
 PATH='I78',
 DRAWING='@T6G_MB_LIB.T6G(SCH_1):PAGE378',
 WATTAGE='1/20W',
 TOLERANCE='1%',
 MATERIAL='CHIP',
 PHYS_PAGE='184',
 XY='(-5950,1425)',
 ROT='0',
 VER='1',
 PACK_TYPE='0201LF',
 LOCATION='R6763',
 CDS_LIB='pure_quanta',
 CDS_PART_NAME='Q_RES_0201LF-1K,1%,1/20W,CHIP,CS21001FE07',
 PART_NUMBER='CS21001FE07',
 VALUE='1K',
 PRIM_FILE='./archive_libs/logical/q_res/chips/chips.prt';

PART_NAME
 R6764 'Q_RES_0201LF-1K,1%,1/20W,CHIP,CS21001FE07':;

SECTION_NUMBER 1
 '@T6G_MB_LIB.T6G(SCH_1):PAGE378_I79@PURE_QUANTA.Q_RES(CHIPS)':
 C_PATH='@t6g_mb_lib.t6g(sch_1):page378_i79@pure_quanta.q_res(chips)',
 P_PATH='@t6g_mb_lib.t6g(sch_1):page184_i79@pure_quanta.q_res(chips)',
 PATH='I79',
 DRAWING='@T6G_MB_LIB.T6G(SCH_1):PAGE378',
 WATTAGE='1/20W',
 TOLERANCE='1%',
 MATERIAL='CHIP',
 PHYS_PAGE='184',
 XY='(-5950,1350)',
 ROT='0',
 VER='1',
 PACK_TYPE='0201LF',
 LOCATION='R6764',
 CDS_LIB='pure_quanta',
 CDS_PART_NAME='Q_RES_0201LF-1K,1%,1/20W,CHIP,CS21001FE07',
 PART_NUMBER='CS21001FE07',
 VALUE='1K',
 PRIM_FILE='./archive_libs/logical/q_res/chips/chips.prt';

PART_NAME
 R6765 'Q_RES_0201LF-1K,1%,1/20W,CHIP,CS21001FE07':;

SECTION_NUMBER 1
 '@T6G_MB_LIB.T6G(SCH_1):PAGE378_I80@PURE_QUANTA.Q_RES(CHIPS)':
 C_PATH='@t6g_mb_lib.t6g(sch_1):page378_i80@pure_quanta.q_res(chips)',
 P_PATH='@t6g_mb_lib.t6g(sch_1):page184_i80@pure_quanta.q_res(chips)',
 PATH='I80',
 DRAWING='@T6G_MB_LIB.T6G(SCH_1):PAGE378',
 WATTAGE='1/20W',
 TOLERANCE='1%',
 MATERIAL='CHIP',
 PHYS_PAGE='184',
 XY='(-5950,1275)',
 ROT='0',
 VER='1',
 PACK_TYPE='0201LF',
 LOCATION='R6765',
 CDS_LIB='pure_quanta',
 CDS_PART_NAME='Q_RES_0201LF-1K,1%,1/20W,CHIP,CS21001FE07',
 PART_NUMBER='CS21001FE07',
 VALUE='1K',
 PRIM_FILE='./archive_libs/logical/q_res/chips/chips.prt';

PART_NAME
 R6766 'Q_RES_0201LF-1K,1%,1/20W,CHIP,CS21001FE07':;

SECTION_NUMBER 1
 '@T6G_MB_LIB.T6G(SCH_1):PAGE378_I83@PURE_QUANTA.Q_RES(CHIPS)':
 C_PATH='@t6g_mb_lib.t6g(sch_1):page378_i83@pure_quanta.q_res(chips)',
 P_PATH='@t6g_mb_lib.t6g(sch_1):page184_i83@pure_quanta.q_res(chips)',
 PATH='I83',
 DRAWING='@T6G_MB_LIB.T6G(SCH_1):PAGE378',
 WATTAGE='1/20W',
 TOLERANCE='1%',
 MATERIAL='CHIP',
 PHYS_PAGE='184',
 XY='(-5950,1175)',
 ROT='0',
 VER='1',
 PACK_TYPE='0201LF',
 LOCATION='R6766',
 CDS_LIB='pure_quanta',
 CDS_PART_NAME='Q_RES_0201LF-1K,1%,1/20W,CHIP,CS21001FE07',
 PART_NUMBER='CS21001FE07',
 VALUE='1K',
 PRIM_FILE='./archive_libs/logical/q_res/chips/chips.prt';

PART_NAME
 R6767 'Q_RES_0201LF-1K,1%,1/20W,CHIP,CS21001FE07':;

SECTION_NUMBER 1
 '@T6G_MB_LIB.T6G(SCH_1):PAGE378_I82@PURE_QUANTA.Q_RES(CHIPS)':
 C_PATH='@t6g_mb_lib.t6g(sch_1):page378_i82@pure_quanta.q_res(chips)',
 P_PATH='@t6g_mb_lib.t6g(sch_1):page184_i82@pure_quanta.q_res(chips)',
 PATH='I82',
 DRAWING='@T6G_MB_LIB.T6G(SCH_1):PAGE378',
 WATTAGE='1/20W',
 TOLERANCE='1%',
 MATERIAL='CHIP',
 PHYS_PAGE='184',
 XY='(-5950,1100)',
 ROT='0',
 VER='1',
 PACK_TYPE='0201LF',
 LOCATION='R6767',
 CDS_LIB='pure_quanta',
 CDS_PART_NAME='Q_RES_0201LF-1K,1%,1/20W,CHIP,CS21001FE07',
 PART_NUMBER='CS21001FE07',
 VALUE='1K',
 PRIM_FILE='./archive_libs/logical/q_res/chips/chips.prt';

PART_NAME
 R6768 'Q_RES_0201LF-1K,1%,1/20W,CHIP,CS21001FE07':;

SECTION_NUMBER 1
 '@T6G_MB_LIB.T6G(SCH_1):PAGE378_I84@PURE_QUANTA.Q_RES(CHIPS)':
 C_PATH='@t6g_mb_lib.t6g(sch_1):page378_i84@pure_quanta.q_res(chips)',
 P_PATH='@t6g_mb_lib.t6g(sch_1):page184_i84@pure_quanta.q_res(chips)',
 PATH='I84',
 DRAWING='@T6G_MB_LIB.T6G(SCH_1):PAGE378',
 WATTAGE='1/20W',
 TOLERANCE='1%',
 MATERIAL='CHIP',
 PHYS_PAGE='184',
 XY='(-5950,1025)',
 ROT='0',
 VER='1',
 PACK_TYPE='0201LF',
 LOCATION='R6768',
 CDS_LIB='pure_quanta',
 CDS_PART_NAME='Q_RES_0201LF-1K,1%,1/20W,CHIP,CS21001FE07',
 PART_NUMBER='CS21001FE07',
 VALUE='1K',
 PRIM_FILE='./archive_libs/logical/q_res/chips/chips.prt';

PART_NAME
 R6769 'Q_RES_0201LF-1K,1%,1/20W,CHIP,CS21001FE07':;

SECTION_NUMBER 1
 '@T6G_MB_LIB.T6G(SCH_1):PAGE378_I85@PURE_QUANTA.Q_RES(CHIPS)':
 C_PATH='@t6g_mb_lib.t6g(sch_1):page378_i85@pure_quanta.q_res(chips)',
 P_PATH='@t6g_mb_lib.t6g(sch_1):page184_i85@pure_quanta.q_res(chips)',
 PATH='I85',
 DRAWING='@T6G_MB_LIB.T6G(SCH_1):PAGE378',
 WATTAGE='1/20W',
 TOLERANCE='1%',
 MATERIAL='CHIP',
 PHYS_PAGE='184',
 XY='(-5950,950)',
 ROT='0',
 VER='1',
 PACK_TYPE='0201LF',
 LOCATION='R6769',
 CDS_LIB='pure_quanta',
 CDS_PART_NAME='Q_RES_0201LF-1K,1%,1/20W,CHIP,CS21001FE07',
 PART_NUMBER='CS21001FE07',
 VALUE='1K',
 PRIM_FILE='./archive_libs/logical/q_res/chips/chips.prt';

PART_NAME
 R6770 'Q_RES_0201LF-4.7K,5%,1/20W,EMPTY,CS24701JE04':;

SECTION_NUMBER 1
 '@T6G_MB_LIB.T6G(SCH_1):PAGE378_I96@PURE_QUANTA.Q_RES(CHIPS)':
 C_PATH='@t6g_mb_lib.t6g(sch_1):page378_i96@pure_quanta.q_res(chips)',
 P_PATH='@t6g_mb_lib.t6g(sch_1):page184_i96@pure_quanta.q_res(chips)',
 PATH='I96',
 DRAWING='@T6G_MB_LIB.T6G(SCH_1):PAGE378',
 WATTAGE='1/20W',
 TOLERANCE='5%',
 MATERIAL='EMPTY',
 PHYS_PAGE='184',
 XY='(-8600,1800)',
 ROT='0',
 VER='2',
 PACK_TYPE='0201LF',
 LOCATION='R6770',
 CDS_LIB='pure_quanta',
 CDS_PART_NAME='Q_RES_0201LF-4.7K,5%,1/20W,EMPTY,CS24701JE04',
 PART_NUMBER='CS24701JE04',
 VALUE='4.7K',
 PRIM_FILE='./archive_libs/logical/q_res/chips/chips.prt';

PART_NAME
 R6771 'Q_RES_0201LF-4.7K,5%,1/20W,EMPTY,CS24701JE04':;

SECTION_NUMBER 1
 '@T6G_MB_LIB.T6G(SCH_1):PAGE378_I100@PURE_QUANTA.Q_RES(CHIPS)':
 C_PATH='@t6g_mb_lib.t6g(sch_1):page378_i100@pure_quanta.q_res(chips)',
 P_PATH='@t6g_mb_lib.t6g(sch_1):page184_i100@pure_quanta.q_res(chips)',
 PATH='I100',
 DRAWING='@T6G_MB_LIB.T6G(SCH_1):PAGE378',
 WATTAGE='1/20W',
 TOLERANCE='5%',
 MATERIAL='EMPTY',
 PHYS_PAGE='184',
 XY='(-8300,1800)',
 ROT='0',
 VER='2',
 PACK_TYPE='0201LF',
 LOCATION='R6771',
 CDS_LIB='pure_quanta',
 CDS_PART_NAME='Q_RES_0201LF-4.7K,5%,1/20W,EMPTY,CS24701JE04',
 PART_NUMBER='CS24701JE04',
 VALUE='4.7K',
 PRIM_FILE='./archive_libs/logical/q_res/chips/chips.prt';

PART_NAME
 R6772 'Q_RES_0201LF-4.7K,5%,1/20W,EMPTY,CS24701JE04':;

SECTION_NUMBER 1
 '@T6G_MB_LIB.T6G(SCH_1):PAGE378_I98@PURE_QUANTA.Q_RES(CHIPS)':
 C_PATH='@t6g_mb_lib.t6g(sch_1):page378_i98@pure_quanta.q_res(chips)',
 P_PATH='@t6g_mb_lib.t6g(sch_1):page184_i98@pure_quanta.q_res(chips)',
 PATH='I98',
 DRAWING='@T6G_MB_LIB.T6G(SCH_1):PAGE378',
 WATTAGE='1/20W',
 TOLERANCE='5%',
 MATERIAL='EMPTY',
 PHYS_PAGE='184',
 XY='(-7950,1775)',
 ROT='0',
 VER='2',
 PACK_TYPE='0201LF',
 LOCATION='R6772',
 CDS_LIB='pure_quanta',
 CDS_PART_NAME='Q_RES_0201LF-4.7K,5%,1/20W,EMPTY,CS24701JE04',
 PART_NUMBER='CS24701JE04',
 VALUE='4.7K',
 PRIM_FILE='./archive_libs/logical/q_res/chips/chips.prt';

PART_NAME
 R6773 'Q_RES_0201LF-4.7K,5%,1/20W,CHIP,CS24701JE04':;

SECTION_NUMBER 1
 '@T6G_MB_LIB.T6G(SCH_1):PAGE378_I94@PURE_QUANTA.Q_RES(CHIPS)':
 C_PATH='@t6g_mb_lib.t6g(sch_1):page378_i94@pure_quanta.q_res(chips)',
 P_PATH='@t6g_mb_lib.t6g(sch_1):page184_i94@pure_quanta.q_res(chips)',
 PATH='I94',
 DRAWING='@T6G_MB_LIB.T6G(SCH_1):PAGE378',
 WATTAGE='1/20W',
 TOLERANCE='5%',
 MATERIAL='CHIP',
 PHYS_PAGE='184',
 XY='(-8600,1025)',
 ROT='0',
 VER='2',
 PACK_TYPE='0201LF',
 LOCATION='R6773',
 CDS_LIB='pure_quanta',
 CDS_PART_NAME='Q_RES_0201LF-4.7K,5%,1/20W,CHIP,CS24701JE04',
 PART_NUMBER='CS24701JE04',
 VALUE='4.7K',
 PRIM_FILE='./archive_libs/logical/q_res/chips/chips.prt';

PART_NAME
 R6774 'Q_RES_0201LF-4.7K,5%,1/20W,CHIP,CS24701JE04':;

SECTION_NUMBER 1
 '@T6G_MB_LIB.T6G(SCH_1):PAGE378_I95@PURE_QUANTA.Q_RES(CHIPS)':
 C_PATH='@t6g_mb_lib.t6g(sch_1):page378_i95@pure_quanta.q_res(chips)',
 P_PATH='@t6g_mb_lib.t6g(sch_1):page184_i95@pure_quanta.q_res(chips)',
 PATH='I95',
 DRAWING='@T6G_MB_LIB.T6G(SCH_1):PAGE378',
 WATTAGE='1/20W',
 TOLERANCE='5%',
 MATERIAL='CHIP',
 PHYS_PAGE='184',
 XY='(-8300,1025)',
 ROT='0',
 VER='2',
 PACK_TYPE='0201LF',
 LOCATION='R6774',
 CDS_LIB='pure_quanta',
 CDS_PART_NAME='Q_RES_0201LF-4.7K,5%,1/20W,CHIP,CS24701JE04',
 PART_NUMBER='CS24701JE04',
 VALUE='4.7K',
 PRIM_FILE='./archive_libs/logical/q_res/chips/chips.prt';

PART_NAME
 R6775 'Q_RES_0201LF-4.7K,5%,1/20W,CHIP,CS24701JE04':;

SECTION_NUMBER 1
 '@T6G_MB_LIB.T6G(SCH_1):PAGE378_I97@PURE_QUANTA.Q_RES(CHIPS)':
 C_PATH='@t6g_mb_lib.t6g(sch_1):page378_i97@pure_quanta.q_res(chips)',
 P_PATH='@t6g_mb_lib.t6g(sch_1):page184_i97@pure_quanta.q_res(chips)',
 PATH='I97',
 DRAWING='@T6G_MB_LIB.T6G(SCH_1):PAGE378',
 WATTAGE='1/20W',
 TOLERANCE='5%',
 MATERIAL='CHIP',
 PHYS_PAGE='184',
 XY='(-7950,1025)',
 ROT='0',
 VER='2',
 PACK_TYPE='0201LF',
 LOCATION='R6775',
 CDS_LIB='pure_quanta',
 CDS_PART_NAME='Q_RES_0201LF-4.7K,5%,1/20W,CHIP,CS24701JE04',
 PART_NUMBER='CS24701JE04',
 VALUE='4.7K',
 PRIM_FILE='./archive_libs/logical/q_res/chips/chips.prt';

PART_NAME
 R6776 'Q_RES_0201LF-0,5%,1/20W,CHIP,CS00001JE10':;

SECTION_NUMBER 1
 '@T6G_MB_LIB.T6G(SCH_1):PAGE378_I104@PURE_QUANTA.Q_RES(CHIPS)':
 C_PATH='@t6g_mb_lib.t6g(sch_1):page378_i104@pure_quanta.q_res(chips)',
 P_PATH='@t6g_mb_lib.t6g(sch_1):page184_i104@pure_quanta.q_res(chips)',
 PATH='I104',
 DRAWING='@T6G_MB_LIB.T6G(SCH_1):PAGE378',
 WATTAGE='1/20W',
 TOLERANCE='5%',
 MATERIAL='CHIP',
 PHYS_PAGE='184',
 XY='(-6700,4700)',
 ROT='0',
 VER='1',
 PACK_TYPE='0201LF',
 LOCATION='R6776',
 CDS_LIB='pure_quanta',
 CDS_PART_NAME='Q_RES_0201LF-0,5%,1/20W,CHIP,CS00001JE10',
 PART_NUMBER='CS00001JE10',
 VALUE='0',
 PRIM_FILE='./archive_libs/logical/q_res/chips/chips.prt';

PART_NAME
 R6777 'Q_RES_0402LF-0,5%,1/16W,CHIP,CS00002JB13':;

SECTION_NUMBER 1
 '@T6G_MB_LIB.T6G(SCH_1):PAGE80_I330@PURE_QUANTA.Q_RES(CHIPS)':
 C_PATH='@t6g_mb_lib.t6g(sch_1):page80_i330@pure_quanta.q_res(chips)',
 P_PATH='@t6g_mb_lib.t6g(sch_1):page81_i330@pure_quanta.q_res(chips)',
 PATH='I330',
 DRAWING='@T6G_MB_LIB.T6G(SCH_1):PAGE80',
 BOM_COST='MEM',
 WATTAGE='1/16W',
 TOLERANCE='5%',
 MATERIAL='CHIP',
 PHYS_PAGE='81',
 XY='(-3225,3775)',
 ROT='0',
 VER='1',
 PACK_TYPE='0402LF',
 LOCATION='R6777',
 CDS_LIB='pure_quanta',
 CDS_PART_NAME='Q_RES_0402LF-0,5%,1/16W,CHIP,CS00002JB13',
 PART_NUMBER='CS00002JB13',
 VALUE='0',
 PRIM_FILE='./archive_libs/logical/q_res/chips/chips.prt';

PART_NAME
 R6778 'Q_RES_0201LF-10K,1%,1/20W,CHIP,CS31001FE17':;

SECTION_NUMBER 1
 '@T6G_MB_LIB.T6G(SCH_1):PAGE378_I107@PURE_QUANTA.Q_RES(CHIPS)':
 C_PATH='@t6g_mb_lib.t6g(sch_1):page378_i107@pure_quanta.q_res(chips)',
 P_PATH='@t6g_mb_lib.t6g(sch_1):page184_i107@pure_quanta.q_res(chips)',
 PATH='I107',
 DRAWING='@T6G_MB_LIB.T6G(SCH_1):PAGE378',
 WATTAGE='1/20W',
 TOLERANCE='1%',
 MATERIAL='CHIP',
 PHYS_PAGE='184',
 XY='(-6975,3000)',
 ROT='0',
 VER='2',
 PACK_TYPE='0201LF',
 LOCATION='R6778',
 CDS_LIB='pure_quanta',
 CDS_PART_NAME='Q_RES_0201LF-10K,1%,1/20W,CHIP,CS31001FE17',
 PART_NUMBER='CS31001FE17',
 VALUE='10K',
 PRIM_FILE='./archive_libs/logical/q_res/chips/chips.prt';

PART_NAME
 R6779 'Q_RES_0201LF-33.2,1%,1/20W,CHIP,CS03321FE09':;

SECTION_NUMBER 1
 '@T6G_MB_LIB.T6G(SCH_1):PAGE378_I119@PURE_QUANTA.Q_RES(CHIPS)':
 C_PATH='@t6g_mb_lib.t6g(sch_1):page378_i119@pure_quanta.q_res(chips)',
 P_PATH='@t6g_mb_lib.t6g(sch_1):page184_i119@pure_quanta.q_res(chips)',
 PATH='I119',
 DRAWING='@T6G_MB_LIB.T6G(SCH_1):PAGE378',
 SEC_TYPE='0201LF',
 WATTAGE='1/20W',
 TOLERANCE='1%',
 MATERIAL='CHIP',
 PHYS_PAGE='184',
 XY='(-3050,4850)',
 ROT='0',
 VER='1',
 PACK_TYPE='0201LF',
 LOCATION='R6779',
 SEC='1',
 CDS_LIB='pure_quanta',
 CDS_PART_NAME='Q_RES_0201LF-33.2,1%,1/20W,CHIP,CS03321FE09',
 PART_NUMBER='CS03321FE09',
 VALUE='33.2',
 PRIM_FILE='./archive_libs/logical/q_res/chips/chips.prt';

PART_NAME
 R6780 'Q_RES_0201LF-33.2,1%,1/20W,CHIP,CS03321FE09':;

SECTION_NUMBER 1
 '@T6G_MB_LIB.T6G(SCH_1):PAGE378_I120@PURE_QUANTA.Q_RES(CHIPS)':
 C_PATH='@t6g_mb_lib.t6g(sch_1):page378_i120@pure_quanta.q_res(chips)',
 P_PATH='@t6g_mb_lib.t6g(sch_1):page184_i120@pure_quanta.q_res(chips)',
 PATH='I120',
 DRAWING='@T6G_MB_LIB.T6G(SCH_1):PAGE378',
 SEC_TYPE='0201LF',
 WATTAGE='1/20W',
 TOLERANCE='1%',
 MATERIAL='CHIP',
 PHYS_PAGE='184',
 XY='(-3050,4800)',
 ROT='0',
 VER='1',
 PACK_TYPE='0201LF',
 LOCATION='R6780',
 SEC='1',
 CDS_LIB='pure_quanta',
 CDS_PART_NAME='Q_RES_0201LF-33.2,1%,1/20W,CHIP,CS03321FE09',
 PART_NUMBER='CS03321FE09',
 VALUE='33.2',
 PRIM_FILE='./archive_libs/logical/q_res/chips/chips.prt';

PART_NAME
 R6781 'Q_RES_0402LF-0,5%,1/16W,CHIP,CS00002JB13':;

SECTION_NUMBER 1
 '@T6G_MB_LIB.T6G(SCH_1):PAGE80_I332@PURE_QUANTA.Q_RES(CHIPS)':
 C_PATH='@t6g_mb_lib.t6g(sch_1):page80_i332@pure_quanta.q_res(chips)',
 P_PATH='@t6g_mb_lib.t6g(sch_1):page81_i332@pure_quanta.q_res(chips)',
 PATH='I332',
 DRAWING='@T6G_MB_LIB.T6G(SCH_1):PAGE80',
 BOM_COST='MEM',
 WATTAGE='1/16W',
 TOLERANCE='5%',
 MATERIAL='CHIP',
 PHYS_PAGE='81',
 XY='(-3225,3925)',
 ROT='0',
 VER='1',
 PACK_TYPE='0402LF',
 LOCATION='R6781',
 CDS_LIB='pure_quanta',
 CDS_PART_NAME='Q_RES_0402LF-0,5%,1/16W,CHIP,CS00002JB13',
 PART_NUMBER='CS00002JB13',
 VALUE='0',
 PRIM_FILE='./archive_libs/logical/q_res/chips/chips.prt';

PART_NAME
 R6782 'Q_RES_0402LF-33,5%,1/16W,CHIP,CS03302JB10':;

SECTION_NUMBER 1
 '@T6G_MB_LIB.T6G(SCH_1):PAGE349_I228@PURE_QUANTA.Q_RES(CHIPS)':
 C_PATH='@t6g_mb_lib.t6g(sch_1):page349_i228@pure_quanta.q_res(chips)',
 P_PATH='@t6g_mb_lib.t6g(sch_1):page151_i228@pure_quanta.q_res(chips)',
 PATH='I228',
 DRAWING='@T6G_MB_LIB.T6G(SCH_1):PAGE349',
 SEC_TYPE='0402LF',
 WATTAGE='1/16W',
 TOLERANCE='5%',
 MATERIAL='CHIP',
 PHYS_PAGE='151',
 XY='(2550,5525)',
 ROT='2',
 VER='1',
 PACK_TYPE='0402LF',
 LOCATION='R6782',
 SEC='1',
 CDS_LIB='pure_quanta',
 CDS_PART_NAME='Q_RES_0402LF-33,5%,1/16W,CHIP,CS03302JB10',
 PART_NUMBER='CS03302JB10',
 VALUE='33',
 PRIM_FILE='./archive_libs/logical/q_res/chips/chips.prt';

PART_NAME
 R6783 'Q_RES_0402LF-33,5%,1/16W,CHIP,CS03302JB10':;

SECTION_NUMBER 1
 '@T6G_MB_LIB.T6G(SCH_1):PAGE349_I229@PURE_QUANTA.Q_RES(CHIPS)':
 C_PATH='@t6g_mb_lib.t6g(sch_1):page349_i229@pure_quanta.q_res(chips)',
 P_PATH='@t6g_mb_lib.t6g(sch_1):page151_i229@pure_quanta.q_res(chips)',
 PATH='I229',
 DRAWING='@T6G_MB_LIB.T6G(SCH_1):PAGE349',
 WATTAGE='1/16W',
 TOLERANCE='5%',
 MATERIAL='CHIP',
 PHYS_PAGE='151',
 XY='(2550,5475)',
 ROT='2',
 VER='1',
 PACK_TYPE='0402LF',
 LOCATION='R6783',
 CDS_LIB='pure_quanta',
 CDS_PART_NAME='Q_RES_0402LF-33,5%,1/16W,CHIP,CS03302JB10',
 PART_NUMBER='CS03302JB10',
 VALUE='33',
 PRIM_FILE='./archive_libs/logical/q_res/chips/chips.prt';

PART_NAME
 R6784 'Q_RES_0402LF-0,5%,1/16W,CHIP,CS00002JB13':;

SECTION_NUMBER 1
 '@T6G_MB_LIB.T6G(SCH_1):PAGE349_I198@PURE_QUANTA.Q_RES(CHIPS)':
 C_PATH='@t6g_mb_lib.t6g(sch_1):page349_i198@pure_quanta.q_res(chips)',
 P_PATH='@t6g_mb_lib.t6g(sch_1):page151_i198@pure_quanta.q_res(chips)',
 PATH='I198',
 DRAWING='@T6G_MB_LIB.T6G(SCH_1):PAGE349',
 WATTAGE='1/16W',
 TOLERANCE='5%',
 MATERIAL='CHIP',
 PHYS_PAGE='151',
 XY='(3375,6500)',
 ROT='2',
 VER='1',
 PACK_TYPE='0402LF',
 LOCATION='R6784',
 CDS_LIB='pure_quanta',
 CDS_PART_NAME='Q_RES_0402LF-0,5%,1/16W,CHIP,CS00002JB13',
 PART_NUMBER='CS00002JB13',
 VALUE='0',
 PRIM_FILE='./archive_libs/logical/q_res/chips/chips.prt';

PART_NAME
 R6785 'Q_RES_0402LF-0,5%,1/16W,CHIP,CS00002JB13':;

SECTION_NUMBER 1
 '@T6G_MB_LIB.T6G(SCH_1):PAGE349_I199@PURE_QUANTA.Q_RES(CHIPS)':
 C_PATH='@t6g_mb_lib.t6g(sch_1):page349_i199@pure_quanta.q_res(chips)',
 P_PATH='@t6g_mb_lib.t6g(sch_1):page151_i199@pure_quanta.q_res(chips)',
 PATH='I199',
 DRAWING='@T6G_MB_LIB.T6G(SCH_1):PAGE349',
 WATTAGE='1/16W',
 TOLERANCE='5%',
 MATERIAL='CHIP',
 PHYS_PAGE='151',
 XY='(3375,6450)',
 ROT='2',
 VER='1',
 PACK_TYPE='0402LF',
 LOCATION='R6785',
 CDS_LIB='pure_quanta',
 CDS_PART_NAME='Q_RES_0402LF-0,5%,1/16W,CHIP,CS00002JB13',
 PART_NUMBER='CS00002JB13',
 VALUE='0',
 PRIM_FILE='./archive_libs/logical/q_res/chips/chips.prt';

PART_NAME
 R6786 'Q_RES_0402LF-1K,1%,1/16W,CHIP,CS21002FB06':;

SECTION_NUMBER 1
 '@T6G_MB_LIB.T6G(SCH_1):PAGE475_I208@PURE_QUANTA.Q_RES(CHIPS)':
 C_PATH='@t6g_mb_lib.t6g(sch_1):page475_i208@pure_quanta.q_res(chips)',
 P_PATH='@t6g_mb_lib.t6g(sch_1):page362_i208@pure_quanta.q_res(chips)',
 PATH='I208',
 DRAWING='@T6G_MB_LIB.T6G(SCH_1):PAGE475',
 WATTAGE='1/16W',
 TOLERANCE='1%',
 MATERIAL='CHIP',
 PHYS_PAGE='362',
 XY='(-10475,7450)',
 ROT='2',
 VER='2',
 PACK_TYPE='0402LF',
 LOCATION='R6786',
 CDS_LIB='pure_quanta',
 CDS_PART_NAME='Q_RES_0402LF-1K,1%,1/16W,CHIP,CS21002FB06',
 PART_NUMBER='CS21002FB06',
 VALUE='1K',
 PRIM_FILE='./archive_libs/logical/q_res/chips/chips.prt';

PART_NAME
 R6787 'Q_RES_0402LF-1K,1%,1/16W,CHIP,CS21002FB06':;

SECTION_NUMBER 1
 '@T6G_MB_LIB.T6G(SCH_1):PAGE477_I90@PURE_QUANTA.Q_RES(CHIPS)':
 C_PATH='@t6g_mb_lib.t6g(sch_1):page477_i90@pure_quanta.q_res(chips)',
 P_PATH='@t6g_mb_lib.t6g(sch_1):page364_i90@pure_quanta.q_res(chips)',
 PATH='I90',
 DRAWING='@T6G_MB_LIB.T6G(SCH_1):PAGE477',
 WATTAGE='1/16W',
 TOLERANCE='1%',
 MATERIAL='CHIP',
 PHYS_PAGE='364',
 XY='(-7575,5750)',
 ROT='2',
 VER='2',
 PACK_TYPE='0402LF',
 LOCATION='R6787',
 CDS_LIB='pure_quanta',
 CDS_PART_NAME='Q_RES_0402LF-1K,1%,1/16W,CHIP,CS21002FB06',
 PART_NUMBER='CS21002FB06',
 VALUE='1K',
 PRIM_FILE='./archive_libs/logical/q_res/chips/chips.prt';

PART_NAME
 R6788 'Q_RES_0201LF-1K,1%,1/20W,CHIP,CS21001FE07':;

SECTION_NUMBER 1
 '@T6G_MB_LIB.T6G(SCH_1):PAGE399_I13@PURE_QUANTA.Q_RES(CHIPS)':
 C_PATH='@t6g_mb_lib.t6g(sch_1):page399_i13@pure_quanta.q_res(chips)',
 P_PATH='@t6g_mb_lib.t6g(sch_1):page322_i13@pure_quanta.q_res(chips)',
 PATH='I13',
 DRAWING='@T6G_MB_LIB.T6G(SCH_1):PAGE399',
 WATTAGE='1/20W',
 TOLERANCE='1%',
 MATERIAL='CHIP',
 PHYS_PAGE='322',
 XY='(-3350,4950)',
 ROT='0',
 VER='2',
 PACK_TYPE='0201LF',
 LOCATION='R6788',
 CDS_LIB='pure_quanta',
 CDS_PART_NAME='Q_RES_0201LF-1K,1%,1/20W,CHIP,CS21001FE07',
 PART_NUMBER='CS21001FE07',
 VALUE='1K',
 PRIM_FILE='./archive_libs/logical/q_res/chips/chips.prt';

PART_NAME
 R6789 'Q_RES_0201LF-1K,1%,1/20W,CHIP,CS21001FE07':;

SECTION_NUMBER 1
 '@T6G_MB_LIB.T6G(SCH_1):PAGE442_I19@PURE_QUANTA.Q_RES(CHIPS)':
 C_PATH='@t6g_mb_lib.t6g(sch_1):page442_i19@pure_quanta.q_res(chips)',
 P_PATH='@t6g_mb_lib.t6g(sch_1):page333_i19@pure_quanta.q_res(chips)',
 PATH='I19',
 DRAWING='@T6G_MB_LIB.T6G(SCH_1):PAGE442',
 WATTAGE='1/20W',
 TOLERANCE='1%',
 MATERIAL='CHIP',
 PHYS_PAGE='333',
 XY='(-2875,4900)',
 ROT='0',
 VER='2',
 PACK_TYPE='0201LF',
 LOCATION='R6789',
 CDS_LIB='pure_quanta',
 CDS_PART_NAME='Q_RES_0201LF-1K,1%,1/20W,CHIP,CS21001FE07',
 PART_NUMBER='CS21001FE07',
 VALUE='1K',
 PRIM_FILE='./archive_libs/logical/q_res/chips/chips.prt';

PART_NAME
 R6790 'Q_RES_0201LF-1K,1%,1/20W,CHIP,CS21001FE07':;

SECTION_NUMBER 1
 '@T6G_MB_LIB.T6G(SCH_1):PAGE453_I19@PURE_QUANTA.Q_RES(CHIPS)':
 C_PATH='@t6g_mb_lib.t6g(sch_1):page453_i19@pure_quanta.q_res(chips)',
 P_PATH='@t6g_mb_lib.t6g(sch_1):page344_i19@pure_quanta.q_res(chips)',
 PATH='I19',
 DRAWING='@T6G_MB_LIB.T6G(SCH_1):PAGE453',
 WATTAGE='1/20W',
 TOLERANCE='1%',
 MATERIAL='CHIP',
 PHYS_PAGE='344',
 XY='(-3900,5425)',
 ROT='0',
 VER='2',
 PACK_TYPE='0201LF',
 LOCATION='R6790',
 CDS_LIB='pure_quanta',
 CDS_PART_NAME='Q_RES_0201LF-1K,1%,1/20W,CHIP,CS21001FE07',
 PART_NUMBER='CS21001FE07',
 VALUE='1K',
 PRIM_FILE='./archive_libs/logical/q_res/chips/chips.prt';

PART_NAME
 R6791 'Q_RES_0201LF-1K,1%,1/20W,CHIP,CS21001FE07':;

SECTION_NUMBER 1
 '@T6G_MB_LIB.T6G(SCH_1):PAGE464_I22@PURE_QUANTA.Q_RES(CHIPS)':
 C_PATH='@t6g_mb_lib.t6g(sch_1):page464_i22@pure_quanta.q_res(chips)',
 P_PATH='@t6g_mb_lib.t6g(sch_1):page355_i22@pure_quanta.q_res(chips)',
 PATH='I22',
 DRAWING='@T6G_MB_LIB.T6G(SCH_1):PAGE464',
 WATTAGE='1/20W',
 TOLERANCE='1%',
 MATERIAL='CHIP',
 PHYS_PAGE='355',
 XY='(-3250,5250)',
 ROT='0',
 VER='2',
 PACK_TYPE='0201LF',
 LOCATION='R6791',
 CDS_LIB='pure_quanta',
 CDS_PART_NAME='Q_RES_0201LF-1K,1%,1/20W,CHIP,CS21001FE07',
 PART_NUMBER='CS21001FE07',
 VALUE='1K',
 PRIM_FILE='./archive_libs/logical/q_res/chips/chips.prt';

PART_NAME
 R6792 'Q_RES_0402LF-0,5%,1/16W,CHIP,CS00002JB13':;

SECTION_NUMBER 1
 '@T6G_MB_LIB.T6G(SCH_1):PAGE80_I334@PURE_QUANTA.Q_RES(CHIPS)':
 C_PATH='@t6g_mb_lib.t6g(sch_1):page80_i334@pure_quanta.q_res(chips)',
 P_PATH='@t6g_mb_lib.t6g(sch_1):page81_i334@pure_quanta.q_res(chips)',
 PATH='I334',
 DRAWING='@T6G_MB_LIB.T6G(SCH_1):PAGE80',
 BOM_COST='MEM',
 WATTAGE='1/16W',
 TOLERANCE='5%',
 MATERIAL='CHIP',
 PHYS_PAGE='81',
 XY='(-6425,4425)',
 ROT='0',
 VER='1',
 PACK_TYPE='0402LF',
 LOCATION='R6792',
 CDS_LIB='pure_quanta',
 CDS_PART_NAME='Q_RES_0402LF-0,5%,1/16W,CHIP,CS00002JB13',
 PART_NUMBER='CS00002JB13',
 VALUE='0',
 PRIM_FILE='./archive_libs/logical/q_res/chips/chips.prt';

PART_NAME
 R6793 'Q_RES_0402LF-0,5%,1/16W,CHIP,CS00002JB13':;

SECTION_NUMBER 1
 '@T6G_MB_LIB.T6G(SCH_1):PAGE80_I335@PURE_QUANTA.Q_RES(CHIPS)':
 C_PATH='@t6g_mb_lib.t6g(sch_1):page80_i335@pure_quanta.q_res(chips)',
 P_PATH='@t6g_mb_lib.t6g(sch_1):page81_i335@pure_quanta.q_res(chips)',
 PATH='I335',
 DRAWING='@T6G_MB_LIB.T6G(SCH_1):PAGE80',
 BOM_COST='MEM',
 WATTAGE='1/16W',
 TOLERANCE='5%',
 MATERIAL='CHIP',
 PHYS_PAGE='81',
 XY='(-6425,4375)',
 ROT='0',
 VER='1',
 PACK_TYPE='0402LF',
 LOCATION='R6793',
 CDS_LIB='pure_quanta',
 CDS_PART_NAME='Q_RES_0402LF-0,5%,1/16W,CHIP,CS00002JB13',
 PART_NUMBER='CS00002JB13',
 VALUE='0',
 PRIM_FILE='./archive_libs/logical/q_res/chips/chips.prt';

PART_NAME
 R6794 'Q_RES_0201LF-1K,1%,1/20W,EMPTY,CS21001FE07':;

SECTION_NUMBER 1
 '@T6G_MB_LIB.T6G(SCH_1):PAGE452_I21@PURE_QUANTA.Q_RES(CHIPS)':
 C_PATH='@t6g_mb_lib.t6g(sch_1):page452_i21@pure_quanta.q_res(chips)',
 P_PATH='@t6g_mb_lib.t6g(sch_1):page343_i21@pure_quanta.q_res(chips)',
 PATH='I21',
 DRAWING='@T6G_MB_LIB.T6G(SCH_1):PAGE452',
 WATTAGE='1/20W',
 TOLERANCE='1%',
 MATERIAL='EMPTY',
 PHYS_PAGE='343',
 XY='(-8425,4150)',
 ROT='0',
 VER='2',
 PACK_TYPE='0201LF',
 LOCATION='R6794',
 CDS_LIB='pure_quanta',
 CDS_PART_NAME='Q_RES_0201LF-1K,1%,1/20W,EMPTY,CS21001FE07',
 PART_NUMBER='CS21001FE07',
 VALUE='1K',
 PRIM_FILE='./archive_libs/logical/q_res/chips/chips.prt';

PART_NAME
 R6795 'Q_RES_0201LF-200,1%,1/20W,CHIP,CS12001FE12':;

SECTION_NUMBER 1
 '@T6G_MB_LIB.T6G(SCH_1):PAGE452_I20@PURE_QUANTA.Q_RES(CHIPS)':
 C_PATH='@t6g_mb_lib.t6g(sch_1):page452_i20@pure_quanta.q_res(chips)',
 P_PATH='@t6g_mb_lib.t6g(sch_1):page343_i20@pure_quanta.q_res(chips)',
 PATH='I20',
 DRAWING='@T6G_MB_LIB.T6G(SCH_1):PAGE452',
 WATTAGE='1/20W',
 TOLERANCE='1%',
 MATERIAL='CHIP',
 PHYS_PAGE='343',
 XY='(-7400,3600)',
 ROT='0',
 VER='2',
 PACK_TYPE='0201LF',
 LOCATION='R6795',
 CDS_LIB='pure_quanta',
 CDS_PART_NAME='Q_RES_0201LF-200,1%,1/20W,CHIP,CS12001FE12',
 PART_NUMBER='CS12001FE12',
 VALUE='200',
 PRIM_FILE='./archive_libs/logical/q_res/chips/chips.prt';

PART_NAME
 R6796 'Q_RES_0201LF-0,5%,1/20W,CHIP,CS00001JE10':;

SECTION_NUMBER 1
 '@T6G_MB_LIB.T6G(SCH_1):PAGE452_I18@PURE_QUANTA.Q_RES(CHIPS)':
 C_PATH='@t6g_mb_lib.t6g(sch_1):page452_i18@pure_quanta.q_res(chips)',
 P_PATH='@t6g_mb_lib.t6g(sch_1):page343_i18@pure_quanta.q_res(chips)',
 PATH='I18',
 DRAWING='@T6G_MB_LIB.T6G(SCH_1):PAGE452',
 WATTAGE='1/20W',
 TOLERANCE='5%',
 MATERIAL='CHIP',
 PHYS_PAGE='343',
 XY='(-1050,2050)',
 ROT='0',
 VER='2',
 PACK_TYPE='0201LF',
 LOCATION='R6796',
 CDS_LIB='pure_quanta',
 CDS_PART_NAME='Q_RES_0201LF-0,5%,1/20W,CHIP,CS00001JE10',
 PART_NUMBER='CS00001JE10',
 VALUE='0',
 PRIM_FILE='./archive_libs/logical/q_res/chips/chips.prt';

PART_NAME
 R6797 'Q_RES_0201LF-0,5%,1/20W,CHIP,CS00001JE10':;

SECTION_NUMBER 1
 '@T6G_MB_LIB.T6G(SCH_1):PAGE452_I15@PURE_QUANTA.Q_RES(CHIPS)':
 C_PATH='@t6g_mb_lib.t6g(sch_1):page452_i15@pure_quanta.q_res(chips)',
 P_PATH='@t6g_mb_lib.t6g(sch_1):page343_i15@pure_quanta.q_res(chips)',
 PATH='I15',
 DRAWING='@T6G_MB_LIB.T6G(SCH_1):PAGE452',
 WATTAGE='1/20W',
 TOLERANCE='5%',
 MATERIAL='CHIP',
 PHYS_PAGE='343',
 XY='(-1200,1500)',
 ROT='0',
 VER='2',
 PACK_TYPE='0201LF',
 LOCATION='R6797',
 CDS_LIB='pure_quanta',
 CDS_PART_NAME='Q_RES_0201LF-0,5%,1/20W,CHIP,CS00001JE10',
 PART_NUMBER='CS00001JE10',
 VALUE='0',
 PRIM_FILE='./archive_libs/logical/q_res/chips/chips.prt';

PART_NAME
 R6798 'Q_RES_0402LF-0,5%,1/16W,CHIP,CS00002JB13':;

SECTION_NUMBER 1
 '@T6G_MB_LIB.T6G(SCH_1):PAGE80_I338@PURE_QUANTA.Q_RES(CHIPS)':
 C_PATH='@t6g_mb_lib.t6g(sch_1):page80_i338@pure_quanta.q_res(chips)',
 P_PATH='@t6g_mb_lib.t6g(sch_1):page81_i338@pure_quanta.q_res(chips)',
 PATH='I338',
 DRAWING='@T6G_MB_LIB.T6G(SCH_1):PAGE80',
 BOM_COST='MEM',
 WATTAGE='1/16W',
 TOLERANCE='5%',
 MATERIAL='CHIP',
 PHYS_PAGE='81',
 XY='(-6425,4075)',
 ROT='0',
 VER='1',
 PACK_TYPE='0402LF',
 LOCATION='R6798',
 CDS_LIB='pure_quanta',
 CDS_PART_NAME='Q_RES_0402LF-0,5%,1/16W,CHIP,CS00002JB13',
 PART_NUMBER='CS00002JB13',
 VALUE='0',
 PRIM_FILE='./archive_libs/logical/q_res/chips/chips.prt';

PART_NAME
 R6799 'Q_RES_0402LF-0,5%,1/16W,CHIP,CS00002JB13':;

SECTION_NUMBER 1
 '@T6G_MB_LIB.T6G(SCH_1):PAGE80_I339@PURE_QUANTA.Q_RES(CHIPS)':
 C_PATH='@t6g_mb_lib.t6g(sch_1):page80_i339@pure_quanta.q_res(chips)',
 P_PATH='@t6g_mb_lib.t6g(sch_1):page81_i339@pure_quanta.q_res(chips)',
 PATH='I339',
 DRAWING='@T6G_MB_LIB.T6G(SCH_1):PAGE80',
 BOM_COST='MEM',
 WATTAGE='1/16W',
 TOLERANCE='5%',
 MATERIAL='CHIP',
 PHYS_PAGE='81',
 XY='(-6425,4025)',
 ROT='0',
 VER='1',
 PACK_TYPE='0402LF',
 LOCATION='R6799',
 CDS_LIB='pure_quanta',
 CDS_PART_NAME='Q_RES_0402LF-0,5%,1/16W,CHIP,CS00002JB13',
 PART_NUMBER='CS00002JB13',
 VALUE='0',
 PRIM_FILE='./archive_libs/logical/q_res/chips/chips.prt';

PART_NAME
 R6800 'Q_RES_0402LF-0,5%,1/16W,CHIP,CS00002JB13':;

SECTION_NUMBER 1
 '@T6G_MB_LIB.T6G(SCH_1):PAGE477_I2@PURE_QUANTA.Q_RES(CHIPS)':
 C_PATH='@t6g_mb_lib.t6g(sch_1):page477_i2@pure_quanta.q_res(chips)',
 P_PATH='@t6g_mb_lib.t6g(sch_1):page364_i2@pure_quanta.q_res(chips)',
 PATH='I2',
 DRAWING='@T6G_MB_LIB.T6G(SCH_1):PAGE477',
 WATTAGE='1/16W',
 TOLERANCE='5%',
 MATERIAL='CHIP',
 PHYS_PAGE='364',
 XY='(-7350,1775)',
 ROT='0',
 VER='1',
 PACK_TYPE='0402LF',
 LOCATION='R6800',
 CDS_LIB='pure_quanta',
 CDS_PART_NAME='Q_RES_0402LF-0,5%,1/16W,CHIP,CS00002JB13',
 PART_NUMBER='CS00002JB13',
 VALUE='0',
 PRIM_FILE='./archive_libs/logical/q_res/chips/chips.prt';

PART_NAME
 R6801 'Q_RES_0402LF-0,5%,1/16W,CHIP,CS00002JB13':;

SECTION_NUMBER 1
 '@T6G_MB_LIB.T6G(SCH_1):PAGE475_I161@PURE_QUANTA.Q_RES(CHIPS)':
 C_PATH='@t6g_mb_lib.t6g(sch_1):page475_i161@pure_quanta.q_res(chips)',
 P_PATH='@t6g_mb_lib.t6g(sch_1):page362_i161@pure_quanta.q_res(chips)',
 PATH='I161',
 DRAWING='@T6G_MB_LIB.T6G(SCH_1):PAGE475',
 SEC_TYPE='0402LF',
 WATTAGE='1/16W',
 TOLERANCE='5%',
 MATERIAL='CHIP',
 PHYS_PAGE='362',
 XY='(-10175,3400)',
 ROT='0',
 VER='1',
 PACK_TYPE='0402LF',
 LOCATION='R6801',
 SEC='1',
 CDS_LIB='pure_quanta',
 CDS_PART_NAME='Q_RES_0402LF-0,5%,1/16W,CHIP,CS00002JB13',
 PART_NUMBER='CS00002JB13',
 VALUE='0',
 PRIM_FILE='./archive_libs/logical/q_res/chips/chips.prt';

PART_NAME
 R6802 'Q_RES_0402LF-10K,1%,1/16W,CHIP,CS31002FB08':;

SECTION_NUMBER 1
 '@T6G_MB_LIB.T6G(SCH_1):PAGE160_I68@PURE_QUANTA.Q_RES(CHIPS)':
 C_PATH='@t6g_mb_lib.t6g(sch_1):page160_i68@pure_quanta.q_res(chips)',
 P_PATH='@t6g_mb_lib.t6g(sch_1):page182_i68@pure_quanta.q_res(chips)',
 PATH='I68',
 DRAWING='@T6G_MB_LIB.T6G(SCH_1):PAGE160',
 WATTAGE='1/16W',
 TOLERANCE='1%',
 MATERIAL='CHIP',
 PHYS_PAGE='182',
 XY='(-3375,3075)',
 ROT='0',
 VER='2',
 PACK_TYPE='0402LF',
 LOCATION='R6802',
 CDS_LIB='pure_quanta',
 CDS_PART_NAME='Q_RES_0402LF-10K,1%,1/16W,CHIP,CS31002FB08',
 PART_NUMBER='CS31002FB08',
 VALUE='10K',
 PRIM_FILE='./archive_libs/logical/q_res/chips/chips.prt';

PART_NAME
 R6803 'Q_RES_0402LF-10K,1%,1/16W,CHIP,CS31002FB08':;

SECTION_NUMBER 1
 '@T6G_MB_LIB.T6G(SCH_1):PAGE379_I76@PURE_QUANTA.Q_RES(CHIPS)':
 C_PATH='@t6g_mb_lib.t6g(sch_1):page379_i76@pure_quanta.q_res(chips)',
 P_PATH='@t6g_mb_lib.t6g(sch_1):page183_i76@pure_quanta.q_res(chips)',
 PATH='I76',
 DRAWING='@T6G_MB_LIB.T6G(SCH_1):PAGE379',
 WATTAGE='1/16W',
 TOLERANCE='1%',
 MATERIAL='CHIP',
 PHYS_PAGE='183',
 XY='(-2750,2775)',
 ROT='0',
 VER='2',
 PACK_TYPE='0402LF',
 LOCATION='R6803',
 CDS_LIB='pure_quanta',
 CDS_PART_NAME='Q_RES_0402LF-10K,1%,1/16W,CHIP,CS31002FB08',
 PART_NUMBER='CS31002FB08',
 VALUE='10K',
 PRIM_FILE='./archive_libs/logical/q_res/chips/chips.prt';

PART_NAME
 R6804 'Q_RES_0402LF-0,5%,1/16W,CHIP,CS00002JB13':;

SECTION_NUMBER 1
 '@T6G_MB_LIB.T6G(SCH_1):PAGE80_I342@PURE_QUANTA.Q_RES(CHIPS)':
 C_PATH='@t6g_mb_lib.t6g(sch_1):page80_i342@pure_quanta.q_res(chips)',
 P_PATH='@t6g_mb_lib.t6g(sch_1):page81_i342@pure_quanta.q_res(chips)',
 PATH='I342',
 DRAWING='@T6G_MB_LIB.T6G(SCH_1):PAGE80',
 BOM_COST='MEM',
 WATTAGE='1/16W',
 TOLERANCE='5%',
 MATERIAL='CHIP',
 PHYS_PAGE='81',
 XY='(-6425,3975)',
 ROT='0',
 VER='1',
 PACK_TYPE='0402LF',
 LOCATION='R6804',
 CDS_LIB='pure_quanta',
 CDS_PART_NAME='Q_RES_0402LF-0,5%,1/16W,CHIP,CS00002JB13',
 PART_NUMBER='CS00002JB13',
 VALUE='0',
 PRIM_FILE='./archive_libs/logical/q_res/chips/chips.prt';

PART_NAME
 R6805 'Q_RES_0402LF-0,5%,1/16W,CHIP,CS00002JB13':;

SECTION_NUMBER 1
 '@T6G_MB_LIB.T6G(SCH_1):PAGE80_I343@PURE_QUANTA.Q_RES(CHIPS)':
 C_PATH='@t6g_mb_lib.t6g(sch_1):page80_i343@pure_quanta.q_res(chips)',
 P_PATH='@t6g_mb_lib.t6g(sch_1):page81_i343@pure_quanta.q_res(chips)',
 PATH='I343',
 DRAWING='@T6G_MB_LIB.T6G(SCH_1):PAGE80',
 BOM_COST='MEM',
 WATTAGE='1/16W',
 TOLERANCE='5%',
 MATERIAL='CHIP',
 PHYS_PAGE='81',
 XY='(-6425,3925)',
 ROT='0',
 VER='1',
 PACK_TYPE='0402LF',
 LOCATION='R6805',
 CDS_LIB='pure_quanta',
 CDS_PART_NAME='Q_RES_0402LF-0,5%,1/16W,CHIP,CS00002JB13',
 PART_NUMBER='CS00002JB13',
 VALUE='0',
 PRIM_FILE='./archive_libs/logical/q_res/chips/chips.prt';

PART_NAME
 R6806 'Q_RES_0402LF-0,5%,1/16W,CHIP,CS00002JB13':;

SECTION_NUMBER 1
 '@T6G_MB_LIB.T6G(SCH_1):PAGE80_I344@PURE_QUANTA.Q_RES(CHIPS)':
 C_PATH='@t6g_mb_lib.t6g(sch_1):page80_i344@pure_quanta.q_res(chips)',
 P_PATH='@t6g_mb_lib.t6g(sch_1):page81_i344@pure_quanta.q_res(chips)',
 PATH='I344',
 DRAWING='@T6G_MB_LIB.T6G(SCH_1):PAGE80',
 BOM_COST='MEM',
 WATTAGE='1/16W',
 TOLERANCE='5%',
 MATERIAL='CHIP',
 PHYS_PAGE='81',
 XY='(-6425,3875)',
 ROT='0',
 VER='1',
 PACK_TYPE='0402LF',
 LOCATION='R6806',
 CDS_LIB='pure_quanta',
 CDS_PART_NAME='Q_RES_0402LF-0,5%,1/16W,CHIP,CS00002JB13',
 PART_NUMBER='CS00002JB13',
 VALUE='0',
 PRIM_FILE='./archive_libs/logical/q_res/chips/chips.prt';

PART_NAME
 R6807 'Q_RES_0402LF-0,5%,1/16W,CHIP,CS00002JB13':;

SECTION_NUMBER 1
 '@T6G_MB_LIB.T6G(SCH_1):PAGE80_I345@PURE_QUANTA.Q_RES(CHIPS)':
 C_PATH='@t6g_mb_lib.t6g(sch_1):page80_i345@pure_quanta.q_res(chips)',
 P_PATH='@t6g_mb_lib.t6g(sch_1):page81_i345@pure_quanta.q_res(chips)',
 PATH='I345',
 DRAWING='@T6G_MB_LIB.T6G(SCH_1):PAGE80',
 BOM_COST='MEM',
 WATTAGE='1/16W',
 TOLERANCE='5%',
 MATERIAL='CHIP',
 PHYS_PAGE='81',
 XY='(-6425,3825)',
 ROT='0',
 VER='1',
 PACK_TYPE='0402LF',
 LOCATION='R6807',
 CDS_LIB='pure_quanta',
 CDS_PART_NAME='Q_RES_0402LF-0,5%,1/16W,CHIP,CS00002JB13',
 PART_NUMBER='CS00002JB13',
 VALUE='0',
 PRIM_FILE='./archive_libs/logical/q_res/chips/chips.prt';

PART_NAME
 R6808 'Q_RES_0201LF-1K,1%,1/20W,EMPTY,CS21001FE07':;

SECTION_NUMBER 1
 '@T6G_MB_LIB.T6G(SCH_1):PAGE386_I19@PURE_QUANTA.Q_RES(CHIPS)':
 C_PATH='@t6g_mb_lib.t6g(sch_1):page386_i19@pure_quanta.q_res(chips)',
 P_PATH='@t6g_mb_lib.t6g(sch_1):page277_i19@pure_quanta.q_res(chips)',
 PATH='I19',
 DRAWING='@T6G_MB_LIB.T6G(SCH_1):PAGE386',
 WATTAGE='1/20W',
 TOLERANCE='1%',
 MATERIAL='EMPTY',
 PHYS_PAGE='277',
 XY='(-8425,3900)',
 ROT='0',
 VER='2',
 PACK_TYPE='0201LF',
 LOCATION='R6808',
 CDS_LIB='pure_quanta',
 CDS_PART_NAME='Q_RES_0201LF-1K,1%,1/20W,EMPTY,CS21001FE07',
 PART_NUMBER='CS21001FE07',
 VALUE='1K',
 PRIM_FILE='./archive_libs/logical/q_res/chips/chips.prt';

PART_NAME
 R6809 'Q_RES_0201LF-200,1%,1/20W,CHIP,CS12001FE12':;

SECTION_NUMBER 1
 '@T6G_MB_LIB.T6G(SCH_1):PAGE386_I18@PURE_QUANTA.Q_RES(CHIPS)':
 C_PATH='@t6g_mb_lib.t6g(sch_1):page386_i18@pure_quanta.q_res(chips)',
 P_PATH='@t6g_mb_lib.t6g(sch_1):page277_i18@pure_quanta.q_res(chips)',
 PATH='I18',
 DRAWING='@T6G_MB_LIB.T6G(SCH_1):PAGE386',
 WATTAGE='1/20W',
 TOLERANCE='1%',
 MATERIAL='CHIP',
 PHYS_PAGE='277',
 XY='(-7400,3350)',
 ROT='0',
 VER='2',
 PACK_TYPE='0201LF',
 LOCATION='R6809',
 CDS_LIB='pure_quanta',
 CDS_PART_NAME='Q_RES_0201LF-200,1%,1/20W,CHIP,CS12001FE12',
 PART_NUMBER='CS12001FE12',
 VALUE='200',
 PRIM_FILE='./archive_libs/logical/q_res/chips/chips.prt';

PART_NAME
 R6810 'Q_RES_0201LF-0,5%,1/20W,CHIP,CS00001JE10':;

SECTION_NUMBER 1
 '@T6G_MB_LIB.T6G(SCH_1):PAGE378_I6@PURE_QUANTA.Q_RES(CHIPS)':
 C_PATH='@t6g_mb_lib.t6g(sch_1):page378_i6@pure_quanta.q_res(chips)',
 P_PATH='@t6g_mb_lib.t6g(sch_1):page184_i6@pure_quanta.q_res(chips)',
 PATH='I6',
 DRAWING='@T6G_MB_LIB.T6G(SCH_1):PAGE378',
 SEC_TYPE='0201LF',
 WATTAGE='1/20W',
 TOLERANCE='5%',
 MATERIAL='CHIP',
 PHYS_PAGE='184',
 XY='(-6350,4600)',
 ROT='0',
 VER='1',
 PACK_TYPE='0201LF',
 LOCATION='R6810',
 SEC='1',
 CDS_LIB='pure_quanta',
 CDS_PART_NAME='Q_RES_0201LF-0,5%,1/20W,CHIP,CS00001JE10',
 PART_NUMBER='CS00001JE10',
 VALUE='0',
 PRIM_FILE='./archive_libs/logical/q_res/chips/chips.prt';

PART_NAME
 R6811 'Q_RES_0201LF-0,5%,1/20W,CHIP,CS00001JE10':;

SECTION_NUMBER 1
 '@T6G_MB_LIB.T6G(SCH_1):PAGE378_I7@PURE_QUANTA.Q_RES(CHIPS)':
 C_PATH='@t6g_mb_lib.t6g(sch_1):page378_i7@pure_quanta.q_res(chips)',
 P_PATH='@t6g_mb_lib.t6g(sch_1):page184_i7@pure_quanta.q_res(chips)',
 PATH='I7',
 DRAWING='@T6G_MB_LIB.T6G(SCH_1):PAGE378',
 SEC_TYPE='0201LF',
 WATTAGE='1/20W',
 TOLERANCE='5%',
 MATERIAL='CHIP',
 PHYS_PAGE='184',
 XY='(-6350,4550)',
 ROT='0',
 VER='1',
 PACK_TYPE='0201LF',
 LOCATION='R6811',
 SEC='1',
 CDS_LIB='pure_quanta',
 CDS_PART_NAME='Q_RES_0201LF-0,5%,1/20W,CHIP,CS00001JE10',
 PART_NUMBER='CS00001JE10',
 VALUE='0',
 PRIM_FILE='./archive_libs/logical/q_res/chips/chips.prt';

PART_NAME
 R6812 'Q_RES_0201LF-0,5%,1/20W,CHIP,CS00001JE10':;

SECTION_NUMBER 1
 '@T6G_MB_LIB.T6G(SCH_1):PAGE401_I19@PURE_QUANTA.Q_RES(CHIPS)':
 C_PATH='@t6g_mb_lib.t6g(sch_1):page401_i19@pure_quanta.q_res(chips)',
 P_PATH='@t6g_mb_lib.t6g(sch_1):page320_i19@pure_quanta.q_res(chips)',
 PATH='I19',
 DRAWING='@T6G_MB_LIB.T6G(SCH_1):PAGE401',
 WATTAGE='1/20W',
 TOLERANCE='5%',
 MATERIAL='CHIP',
 PHYS_PAGE='320',
 XY='(-6350,3000)',
 ROT='0',
 VER='1',
 PACK_TYPE='0201LF',
 LOCATION='R6812',
 CDS_LIB='pure_quanta',
 CDS_PART_NAME='Q_RES_0201LF-0,5%,1/20W,CHIP,CS00001JE10',
 PART_NUMBER='CS00001JE10',
 VALUE='0',
 PRIM_FILE='./archive_libs/logical/q_res/chips/chips.prt';

PART_NAME
 R6813 'Q_RES_0201LF-0,5%,1/20W,CHIP,CS00001JE10':;

SECTION_NUMBER 1
 '@T6G_MB_LIB.T6G(SCH_1):PAGE401_I20@PURE_QUANTA.Q_RES(CHIPS)':
 C_PATH='@t6g_mb_lib.t6g(sch_1):page401_i20@pure_quanta.q_res(chips)',
 P_PATH='@t6g_mb_lib.t6g(sch_1):page320_i20@pure_quanta.q_res(chips)',
 PATH='I20',
 DRAWING='@T6G_MB_LIB.T6G(SCH_1):PAGE401',
 WATTAGE='1/20W',
 TOLERANCE='5%',
 MATERIAL='CHIP',
 PHYS_PAGE='320',
 XY='(-6350,2900)',
 ROT='0',
 VER='1',
 PACK_TYPE='0201LF',
 LOCATION='R6813',
 CDS_LIB='pure_quanta',
 CDS_PART_NAME='Q_RES_0201LF-0,5%,1/20W,CHIP,CS00001JE10',
 PART_NUMBER='CS00001JE10',
 VALUE='0',
 PRIM_FILE='./archive_libs/logical/q_res/chips/chips.prt';

PART_NAME
 R6820 'Q_RES_0201LF-0,5%,1/20W,CHIP,CS00001JE10':;

SECTION_NUMBER 1
 '@T6G_MB_LIB.T6G(SCH_1):PAGE386_I15@PURE_QUANTA.Q_RES(CHIPS)':
 C_PATH='@t6g_mb_lib.t6g(sch_1):page386_i15@pure_quanta.q_res(chips)',
 P_PATH='@t6g_mb_lib.t6g(sch_1):page277_i15@pure_quanta.q_res(chips)',
 PATH='I15',
 DRAWING='@T6G_MB_LIB.T6G(SCH_1):PAGE386',
 WATTAGE='1/20W',
 TOLERANCE='5%',
 MATERIAL='CHIP',
 PHYS_PAGE='277',
 XY='(-1050,1800)',
 ROT='0',
 VER='2',
 PACK_TYPE='0201LF',
 LOCATION='R6820',
 CDS_LIB='pure_quanta',
 CDS_PART_NAME='Q_RES_0201LF-0,5%,1/20W,CHIP,CS00001JE10',
 PART_NUMBER='CS00001JE10',
 VALUE='0',
 PRIM_FILE='./archive_libs/logical/q_res/chips/chips.prt';

PART_NAME
 R6821 'Q_RES_0201LF-0,5%,1/20W,CHIP,CS00001JE10':;

SECTION_NUMBER 1
 '@T6G_MB_LIB.T6G(SCH_1):PAGE386_I13@PURE_QUANTA.Q_RES(CHIPS)':
 C_PATH='@t6g_mb_lib.t6g(sch_1):page386_i13@pure_quanta.q_res(chips)',
 P_PATH='@t6g_mb_lib.t6g(sch_1):page277_i13@pure_quanta.q_res(chips)',
 PATH='I13',
 DRAWING='@T6G_MB_LIB.T6G(SCH_1):PAGE386',
 WATTAGE='1/20W',
 TOLERANCE='5%',
 MATERIAL='CHIP',
 PHYS_PAGE='277',
 XY='(-1200,1250)',
 ROT='0',
 VER='2',
 PACK_TYPE='0201LF',
 LOCATION='R6821',
 CDS_LIB='pure_quanta',
 CDS_PART_NAME='Q_RES_0201LF-0,5%,1/20W,CHIP,CS00001JE10',
 PART_NUMBER='CS00001JE10',
 VALUE='0',
 PRIM_FILE='./archive_libs/logical/q_res/chips/chips.prt';

PART_NAME
 R6822 'Q_RES_0201LF-1K,1%,1/20W,CHIP,CS21001FE07':;

SECTION_NUMBER 1
 '@T6G_MB_LIB.T6G(SCH_1):PAGE387_I24@PURE_QUANTA.Q_RES(CHIPS)':
 C_PATH='@t6g_mb_lib.t6g(sch_1):page387_i24@pure_quanta.q_res(chips)',
 P_PATH='@t6g_mb_lib.t6g(sch_1):page278_i24@pure_quanta.q_res(chips)',
 PATH='I24',
 DRAWING='@T6G_MB_LIB.T6G(SCH_1):PAGE387',
 WATTAGE='1/20W',
 TOLERANCE='1%',
 MATERIAL='CHIP',
 PHYS_PAGE='278',
 XY='(-3750,4375)',
 ROT='0',
 VER='2',
 PACK_TYPE='0201LF',
 LOCATION='R6822',
 CDS_LIB='pure_quanta',
 CDS_PART_NAME='Q_RES_0201LF-1K,1%,1/20W,CHIP,CS21001FE07',
 PART_NUMBER='CS21001FE07',
 VALUE='1K',
 PRIM_FILE='./archive_libs/logical/q_res/chips/chips.prt';

PART_NAME
 R6823 'Q_RES_0402LF-0,5%,1/16W,CHIP,CS00002JB13':;

SECTION_NUMBER 1
 '@T6G_MB_LIB.T6G(SCH_1):PAGE80_I350@PURE_QUANTA.Q_RES(CHIPS)':
 C_PATH='@t6g_mb_lib.t6g(sch_1):page80_i350@pure_quanta.q_res(chips)',
 P_PATH='@t6g_mb_lib.t6g(sch_1):page81_i350@pure_quanta.q_res(chips)',
 PATH='I350',
 DRAWING='@T6G_MB_LIB.T6G(SCH_1):PAGE80',
 BOM_COST='MEM',
 WATTAGE='1/16W',
 TOLERANCE='5%',
 MATERIAL='CHIP',
 PHYS_PAGE='81',
 XY='(-3225,5825)',
 ROT='0',
 VER='1',
 PACK_TYPE='0402LF',
 LOCATION='R6823',
 CDS_LIB='pure_quanta',
 CDS_PART_NAME='Q_RES_0402LF-0,5%,1/16W,CHIP,CS00002JB13',
 PART_NUMBER='CS00002JB13',
 VALUE='0',
 PRIM_FILE='./archive_libs/logical/q_res/chips/chips.prt';

PART_NAME
 R6824 'Q_RES_0402LF-0,5%,1/16W,CHIP,CS00002JB13':;

SECTION_NUMBER 1
 '@T6G_MB_LIB.T6G(SCH_1):PAGE80_I351@PURE_QUANTA.Q_RES(CHIPS)':
 C_PATH='@t6g_mb_lib.t6g(sch_1):page80_i351@pure_quanta.q_res(chips)',
 P_PATH='@t6g_mb_lib.t6g(sch_1):page81_i351@pure_quanta.q_res(chips)',
 PATH='I351',
 DRAWING='@T6G_MB_LIB.T6G(SCH_1):PAGE80',
 BOM_COST='MEM',
 WATTAGE='1/16W',
 TOLERANCE='5%',
 MATERIAL='CHIP',
 PHYS_PAGE='81',
 XY='(-3225,4875)',
 ROT='0',
 VER='1',
 PACK_TYPE='0402LF',
 LOCATION='R6824',
 CDS_LIB='pure_quanta',
 CDS_PART_NAME='Q_RES_0402LF-0,5%,1/16W,CHIP,CS00002JB13',
 PART_NUMBER='CS00002JB13',
 VALUE='0',
 PRIM_FILE='./archive_libs/logical/q_res/chips/chips.prt';

PART_NAME
 R6825 'Q_RES_0402LF-0,5%,1/16W,CHIP,CS00002JB13':;

SECTION_NUMBER 1
 '@T6G_MB_LIB.T6G(SCH_1):PAGE80_I352@PURE_QUANTA.Q_RES(CHIPS)':
 C_PATH='@t6g_mb_lib.t6g(sch_1):page80_i352@pure_quanta.q_res(chips)',
 P_PATH='@t6g_mb_lib.t6g(sch_1):page81_i352@pure_quanta.q_res(chips)',
 PATH='I352',
 DRAWING='@T6G_MB_LIB.T6G(SCH_1):PAGE80',
 BOM_COST='MEM',
 WATTAGE='1/16W',
 TOLERANCE='5%',
 MATERIAL='CHIP',
 PHYS_PAGE='81',
 XY='(-3225,4525)',
 ROT='0',
 VER='1',
 PACK_TYPE='0402LF',
 LOCATION='R6825',
 CDS_LIB='pure_quanta',
 CDS_PART_NAME='Q_RES_0402LF-0,5%,1/16W,CHIP,CS00002JB13',
 PART_NUMBER='CS00002JB13',
 VALUE='0',
 PRIM_FILE='./archive_libs/logical/q_res/chips/chips.prt';

PART_NAME
 R6826 'Q_RES_0402LF-0,5%,1/16W,CHIP,CS00002JB13':;

SECTION_NUMBER 1
 '@T6G_MB_LIB.T6G(SCH_1):PAGE80_I353@PURE_QUANTA.Q_RES(CHIPS)':
 C_PATH='@t6g_mb_lib.t6g(sch_1):page80_i353@pure_quanta.q_res(chips)',
 P_PATH='@t6g_mb_lib.t6g(sch_1):page81_i353@pure_quanta.q_res(chips)',
 PATH='I353',
 DRAWING='@T6G_MB_LIB.T6G(SCH_1):PAGE80',
 BOM_COST='MEM',
 WATTAGE='1/16W',
 TOLERANCE='5%',
 MATERIAL='CHIP',
 PHYS_PAGE='81',
 XY='(-3225,4425)',
 ROT='0',
 VER='1',
 PACK_TYPE='0402LF',
 LOCATION='R6826',
 CDS_LIB='pure_quanta',
 CDS_PART_NAME='Q_RES_0402LF-0,5%,1/16W,CHIP,CS00002JB13',
 PART_NUMBER='CS00002JB13',
 VALUE='0',
 PRIM_FILE='./archive_libs/logical/q_res/chips/chips.prt';

PART_NAME
 R6850 'Q_RES_0402LF-33,5%,1/16W,CHIP,CS03302JB10':;

SECTION_NUMBER 1
 '@T6G_MB_LIB.T6G(SCH_1):PAGE79_I146@PURE_QUANTA.Q_RES(CHIPS)':
 C_PATH='@t6g_mb_lib.t6g(sch_1):page79_i146@pure_quanta.q_res(chips)',
 P_PATH='@t6g_mb_lib.t6g(sch_1):page80_i146@pure_quanta.q_res(chips)',
 PATH='I146',
 DRAWING='@T6G_MB_LIB.T6G(SCH_1):PAGE79',
 BOM_COST='MEM',
 WATTAGE='1/16W',
 TOLERANCE='5%',
 MATERIAL='CHIP',
 PHYS_PAGE='80',
 XY='(-2775,4050)',
 ROT='2',
 VER='1',
 PACK_TYPE='0402LF',
 LOCATION='R6850',
 CDS_LIB='pure_quanta',
 CDS_PART_NAME='Q_RES_0402LF-33,5%,1/16W,CHIP,CS03302JB10',
 PART_NUMBER='CS03302JB10',
 VALUE='33',
 PRIM_FILE='./archive_libs/logical/q_res/chips/chips.prt';

PART_NAME
 R6851 'Q_RES_0402LF-33,5%,1/16W,CHIP,CS03302JB10':;

SECTION_NUMBER 1
 '@T6G_MB_LIB.T6G(SCH_1):PAGE79_I147@PURE_QUANTA.Q_RES(CHIPS)':
 C_PATH='@t6g_mb_lib.t6g(sch_1):page79_i147@pure_quanta.q_res(chips)',
 P_PATH='@t6g_mb_lib.t6g(sch_1):page80_i147@pure_quanta.q_res(chips)',
 PATH='I147',
 DRAWING='@T6G_MB_LIB.T6G(SCH_1):PAGE79',
 BOM_COST='MEM',
 WATTAGE='1/16W',
 TOLERANCE='5%',
 MATERIAL='CHIP',
 PHYS_PAGE='80',
 XY='(-2775,3000)',
 ROT='2',
 VER='1',
 PACK_TYPE='0402LF',
 LOCATION='R6851',
 CDS_LIB='pure_quanta',
 CDS_PART_NAME='Q_RES_0402LF-33,5%,1/16W,CHIP,CS03302JB10',
 PART_NUMBER='CS03302JB10',
 VALUE='33',
 PRIM_FILE='./archive_libs/logical/q_res/chips/chips.prt';

PART_NAME
 R6852 'Q_RES_0402LF-0,5%,1/16W,CHIP,CS00002JB13':;

SECTION_NUMBER 1
 '@T6G_MB_LIB.T6G(SCH_1):PAGE80_I360@PURE_QUANTA.Q_RES(CHIPS)':
 C_PATH='@t6g_mb_lib.t6g(sch_1):page80_i360@pure_quanta.q_res(chips)',
 P_PATH='@t6g_mb_lib.t6g(sch_1):page81_i360@pure_quanta.q_res(chips)',
 PATH='I360',
 DRAWING='@T6G_MB_LIB.T6G(SCH_1):PAGE80',
 BOM_COST='MEM',
 WATTAGE='1/16W',
 TOLERANCE='5%',
 MATERIAL='CHIP',
 PHYS_PAGE='81',
 XY='(-6425,5875)',
 ROT='0',
 VER='1',
 PACK_TYPE='0402LF',
 LOCATION='R6852',
 CDS_LIB='pure_quanta',
 CDS_PART_NAME='Q_RES_0402LF-0,5%,1/16W,CHIP,CS00002JB13',
 PART_NUMBER='CS00002JB13',
 VALUE='0',
 PRIM_FILE='./archive_libs/logical/q_res/chips/chips.prt';

PART_NAME
 R6853 'Q_RES_0402LF-0,5%,1/16W,CHIP,CS00002JB13':;

SECTION_NUMBER 1
 '@T6G_MB_LIB.T6G(SCH_1):PAGE80_I362@PURE_QUANTA.Q_RES(CHIPS)':
 C_PATH='@t6g_mb_lib.t6g(sch_1):page80_i362@pure_quanta.q_res(chips)',
 P_PATH='@t6g_mb_lib.t6g(sch_1):page81_i362@pure_quanta.q_res(chips)',
 PATH='I362',
 DRAWING='@T6G_MB_LIB.T6G(SCH_1):PAGE80',
 BOM_COST='MEM',
 WATTAGE='1/16W',
 TOLERANCE='5%',
 MATERIAL='CHIP',
 PHYS_PAGE='81',
 XY='(-6425,5625)',
 ROT='0',
 VER='1',
 PACK_TYPE='0402LF',
 LOCATION='R6853',
 CDS_LIB='pure_quanta',
 CDS_PART_NAME='Q_RES_0402LF-0,5%,1/16W,CHIP,CS00002JB13',
 PART_NUMBER='CS00002JB13',
 VALUE='0',
 PRIM_FILE='./archive_libs/logical/q_res/chips/chips.prt';

PART_NAME
 R6854 'Q_RES_0402LF-33,5%,1/16W,CHIP,CS03302JB10':;

SECTION_NUMBER 1
 '@T6G_MB_LIB.T6G(SCH_1):PAGE80_I364@PURE_QUANTA.Q_RES(CHIPS)':
 C_PATH='@t6g_mb_lib.t6g(sch_1):page80_i364@pure_quanta.q_res(chips)',
 P_PATH='@t6g_mb_lib.t6g(sch_1):page81_i364@pure_quanta.q_res(chips)',
 PATH='I364',
 DRAWING='@T6G_MB_LIB.T6G(SCH_1):PAGE80',
 BOM_COST='MEM',
 WATTAGE='1/16W',
 TOLERANCE='5%',
 MATERIAL='CHIP',
 PHYS_PAGE='81',
 XY='(-6725,1125)',
 ROT='0',
 VER='1',
 PACK_TYPE='0402LF',
 LOCATION='R6854',
 CDS_LIB='pure_quanta',
 CDS_PART_NAME='Q_RES_0402LF-33,5%,1/16W,CHIP,CS03302JB10',
 PART_NUMBER='CS03302JB10',
 VALUE='33',
 PRIM_FILE='./archive_libs/logical/q_res/chips/chips.prt';

PART_NAME
 R6855 'Q_RES_0402LF-33,5%,1/16W,CHIP,CS03302JB10':;

SECTION_NUMBER 1
 '@T6G_MB_LIB.T6G(SCH_1):PAGE80_I366@PURE_QUANTA.Q_RES(CHIPS)':
 C_PATH='@t6g_mb_lib.t6g(sch_1):page80_i366@pure_quanta.q_res(chips)',
 P_PATH='@t6g_mb_lib.t6g(sch_1):page81_i366@pure_quanta.q_res(chips)',
 PATH='I366',
 DRAWING='@T6G_MB_LIB.T6G(SCH_1):PAGE80',
 BOM_COST='MEM',
 WATTAGE='1/16W',
 TOLERANCE='5%',
 MATERIAL='CHIP',
 PHYS_PAGE='81',
 XY='(-2275,925)',
 ROT='0',
 VER='1',
 PACK_TYPE='0402LF',
 LOCATION='R6855',
 CDS_LIB='pure_quanta',
 CDS_PART_NAME='Q_RES_0402LF-33,5%,1/16W,CHIP,CS03302JB10',
 PART_NUMBER='CS03302JB10',
 VALUE='33',
 PRIM_FILE='./archive_libs/logical/q_res/chips/chips.prt';

PART_NAME
 R6856 'Q_RES_0402LF-33,5%,1/16W,CHIP,CS03302JB10':;

SECTION_NUMBER 1
 '@T6G_MB_LIB.T6G(SCH_1):PAGE349_I226@PURE_QUANTA.Q_RES(CHIPS)':
 C_PATH='@t6g_mb_lib.t6g(sch_1):page349_i226@pure_quanta.q_res(chips)',
 P_PATH='@t6g_mb_lib.t6g(sch_1):page151_i226@pure_quanta.q_res(chips)',
 PATH='I226',
 DRAWING='@T6G_MB_LIB.T6G(SCH_1):PAGE349',
 WATTAGE='1/16W',
 TOLERANCE='5%',
 MATERIAL='CHIP',
 PHYS_PAGE='151',
 XY='(2875,850)',
 ROT='0',
 VER='1',
 PACK_TYPE='0402LF',
 LOCATION='R6856',
 CDS_LIB='pure_quanta',
 CDS_PART_NAME='Q_RES_0402LF-33,5%,1/16W,CHIP,CS03302JB10',
 PART_NUMBER='CS03302JB10',
 VALUE='33',
 PRIM_FILE='./archive_libs/logical/q_res/chips/chips.prt';

PART_NAME
 R6857 'Q_RES_0402LF-33,5%,1/16W,CHIP,CS03302JB10':;

SECTION_NUMBER 1
 '@T6G_MB_LIB.T6G(SCH_1):PAGE349_I227@PURE_QUANTA.Q_RES(CHIPS)':
 C_PATH='@t6g_mb_lib.t6g(sch_1):page349_i227@pure_quanta.q_res(chips)',
 P_PATH='@t6g_mb_lib.t6g(sch_1):page151_i227@pure_quanta.q_res(chips)',
 PATH='I227',
 DRAWING='@T6G_MB_LIB.T6G(SCH_1):PAGE349',
 WATTAGE='1/16W',
 TOLERANCE='5%',
 MATERIAL='CHIP',
 PHYS_PAGE='151',
 XY='(2875,750)',
 ROT='0',
 VER='1',
 PACK_TYPE='0402LF',
 LOCATION='R6857',
 CDS_LIB='pure_quanta',
 CDS_PART_NAME='Q_RES_0402LF-33,5%,1/16W,CHIP,CS03302JB10',
 PART_NUMBER='CS03302JB10',
 VALUE='33',
 PRIM_FILE='./archive_libs/logical/q_res/chips/chips.prt';

PART_NAME
 R6858 'Q_RES_0402LF-0,5%,1/16W,CHIP,CS00002JB13':;

SECTION_NUMBER 1
 '@T6G_MB_LIB.T6G(SCH_1):PAGE349_I207@PURE_QUANTA.Q_RES(CHIPS)':
 C_PATH='@t6g_mb_lib.t6g(sch_1):page349_i207@pure_quanta.q_res(chips)',
 P_PATH='@t6g_mb_lib.t6g(sch_1):page151_i207@pure_quanta.q_res(chips)',
 PATH='I207',
 DRAWING='@T6G_MB_LIB.T6G(SCH_1):PAGE349',
 WATTAGE='1/16W',
 TOLERANCE='5%',
 MATERIAL='CHIP',
 PHYS_PAGE='151',
 XY='(-125,2525)',
 ROT='0',
 VER='1',
 PACK_TYPE='0402LF',
 LOCATION='R6858',
 CDS_LIB='pure_quanta',
 CDS_PART_NAME='Q_RES_0402LF-0,5%,1/16W,CHIP,CS00002JB13',
 PART_NUMBER='CS00002JB13',
 VALUE='0',
 PRIM_FILE='./archive_libs/logical/q_res/chips/chips.prt';

PART_NAME
 R6859 'Q_RES_0402LF-0,5%,1/16W,CHIP,CS00002JB13':;

SECTION_NUMBER 1
 '@T6G_MB_LIB.T6G(SCH_1):PAGE349_I206@PURE_QUANTA.Q_RES(CHIPS)':
 C_PATH='@t6g_mb_lib.t6g(sch_1):page349_i206@pure_quanta.q_res(chips)',
 P_PATH='@t6g_mb_lib.t6g(sch_1):page151_i206@pure_quanta.q_res(chips)',
 PATH='I206',
 DRAWING='@T6G_MB_LIB.T6G(SCH_1):PAGE349',
 WATTAGE='1/16W',
 TOLERANCE='5%',
 MATERIAL='CHIP',
 PHYS_PAGE='151',
 XY='(-125,2625)',
 ROT='0',
 VER='1',
 PACK_TYPE='0402LF',
 LOCATION='R6859',
 CDS_LIB='pure_quanta',
 CDS_PART_NAME='Q_RES_0402LF-0,5%,1/16W,CHIP,CS00002JB13',
 PART_NUMBER='CS00002JB13',
 VALUE='0',
 PRIM_FILE='./archive_libs/logical/q_res/chips/chips.prt';

PART_NAME
 R6860 'Q_RES_0402LF-1K,1%,1/16W,CHIP,CS21002FB06':;

SECTION_NUMBER 1
 '@T6G_MB_LIB.T6G(SCH_1):PAGE475_I213@PURE_QUANTA.Q_RES(CHIPS)':
 C_PATH='@t6g_mb_lib.t6g(sch_1):page475_i213@pure_quanta.q_res(chips)',
 P_PATH='@t6g_mb_lib.t6g(sch_1):page362_i213@pure_quanta.q_res(chips)',
 PATH='I213',
 DRAWING='@T6G_MB_LIB.T6G(SCH_1):PAGE475',
 WATTAGE='1/16W',
 TOLERANCE='1%',
 MATERIAL='CHIP',
 PHYS_PAGE='362',
 XY='(-9950,8050)',
 ROT='0',
 VER='1',
 PACK_TYPE='0402LF',
 LOCATION='R6860',
 CDS_LIB='pure_quanta',
 CDS_PART_NAME='Q_RES_0402LF-1K,1%,1/16W,CHIP,CS21002FB06',
 PART_NUMBER='CS21002FB06',
 VALUE='1K',
 PRIM_FILE='./archive_libs/logical/q_res/chips/chips.prt';

PART_NAME
 R6861 'Q_RES_0402LF-1K,1%,1/16W,CHIP,CS21002FB06':;

SECTION_NUMBER 1
 '@T6G_MB_LIB.T6G(SCH_1):PAGE477_I93@PURE_QUANTA.Q_RES(CHIPS)':
 C_PATH='@t6g_mb_lib.t6g(sch_1):page477_i93@pure_quanta.q_res(chips)',
 P_PATH='@t6g_mb_lib.t6g(sch_1):page364_i93@pure_quanta.q_res(chips)',
 PATH='I93',
 DRAWING='@T6G_MB_LIB.T6G(SCH_1):PAGE477',
 WATTAGE='1/16W',
 TOLERANCE='1%',
 MATERIAL='CHIP',
 PHYS_PAGE='364',
 XY='(-7200,6325)',
 ROT='0',
 VER='1',
 PACK_TYPE='0402LF',
 LOCATION='R6861',
 CDS_LIB='pure_quanta',
 CDS_PART_NAME='Q_RES_0402LF-1K,1%,1/16W,CHIP,CS21002FB06',
 PART_NUMBER='CS21002FB06',
 VALUE='1K',
 PRIM_FILE='./archive_libs/logical/q_res/chips/chips.prt';

PART_NAME
 R6862 'Q_RES_0402LF-33,5%,1/16W,CHIP,CS03302JB10':;

SECTION_NUMBER 1
 '@T6G_MB_LIB.T6G(SCH_1):PAGE349_I218@PURE_QUANTA.Q_RES(CHIPS)':
 C_PATH='@t6g_mb_lib.t6g(sch_1):page349_i218@pure_quanta.q_res(chips)',
 P_PATH='@t6g_mb_lib.t6g(sch_1):page151_i218@pure_quanta.q_res(chips)',
 PATH='I218',
 DRAWING='@T6G_MB_LIB.T6G(SCH_1):PAGE349',
 WATTAGE='1/16W',
 TOLERANCE='5%',
 MATERIAL='CHIP',
 PHYS_PAGE='151',
 XY='(1425,5175)',
 ROT='0',
 VER='1',
 PACK_TYPE='0402LF',
 LOCATION='R6862',
 CDS_LIB='pure_quanta',
 CDS_PART_NAME='Q_RES_0402LF-33,5%,1/16W,CHIP,CS03302JB10',
 PART_NUMBER='CS03302JB10',
 VALUE='33',
 PRIM_FILE='./archive_libs/logical/q_res/chips/chips.prt';

PART_NAME
 R6863 'Q_RES_0402LF-33,5%,1/16W,CHIP,CS03302JB10':;

SECTION_NUMBER 1
 '@T6G_MB_LIB.T6G(SCH_1):PAGE349_I219@PURE_QUANTA.Q_RES(CHIPS)':
 C_PATH='@t6g_mb_lib.t6g(sch_1):page349_i219@pure_quanta.q_res(chips)',
 P_PATH='@t6g_mb_lib.t6g(sch_1):page151_i219@pure_quanta.q_res(chips)',
 PATH='I219',
 DRAWING='@T6G_MB_LIB.T6G(SCH_1):PAGE349',
 WATTAGE='1/16W',
 TOLERANCE='5%',
 MATERIAL='CHIP',
 PHYS_PAGE='151',
 XY='(1425,5100)',
 ROT='0',
 VER='1',
 PACK_TYPE='0402LF',
 LOCATION='R6863',
 CDS_LIB='pure_quanta',
 CDS_PART_NAME='Q_RES_0402LF-33,5%,1/16W,CHIP,CS03302JB10',
 PART_NUMBER='CS03302JB10',
 VALUE='33',
 PRIM_FILE='./archive_libs/logical/q_res/chips/chips.prt';

PART_NAME
 R6864 'Q_RES_0402LF-33,5%,1/16W,CHIP,CS03302JB10':;

SECTION_NUMBER 1
 '@T6G_MB_LIB.T6G(SCH_1):PAGE349_I220@PURE_QUANTA.Q_RES(CHIPS)':
 C_PATH='@t6g_mb_lib.t6g(sch_1):page349_i220@pure_quanta.q_res(chips)',
 P_PATH='@t6g_mb_lib.t6g(sch_1):page151_i220@pure_quanta.q_res(chips)',
 PATH='I220',
 DRAWING='@T6G_MB_LIB.T6G(SCH_1):PAGE349',
 WATTAGE='1/16W',
 TOLERANCE='5%',
 MATERIAL='CHIP',
 PHYS_PAGE='151',
 XY='(1425,4975)',
 ROT='0',
 VER='1',
 PACK_TYPE='0402LF',
 LOCATION='R6864',
 CDS_LIB='pure_quanta',
 CDS_PART_NAME='Q_RES_0402LF-33,5%,1/16W,CHIP,CS03302JB10',
 PART_NUMBER='CS03302JB10',
 VALUE='33',
 PRIM_FILE='./archive_libs/logical/q_res/chips/chips.prt';

PART_NAME
 R6865 'Q_RES_0402LF-33,5%,1/16W,CHIP,CS03302JB10':;

SECTION_NUMBER 1
 '@T6G_MB_LIB.T6G(SCH_1):PAGE349_I221@PURE_QUANTA.Q_RES(CHIPS)':
 C_PATH='@t6g_mb_lib.t6g(sch_1):page349_i221@pure_quanta.q_res(chips)',
 P_PATH='@t6g_mb_lib.t6g(sch_1):page151_i221@pure_quanta.q_res(chips)',
 PATH='I221',
 DRAWING='@T6G_MB_LIB.T6G(SCH_1):PAGE349',
 WATTAGE='1/16W',
 TOLERANCE='5%',
 MATERIAL='CHIP',
 PHYS_PAGE='151',
 XY='(1425,4900)',
 ROT='0',
 VER='1',
 PACK_TYPE='0402LF',
 LOCATION='R6865',
 CDS_LIB='pure_quanta',
 CDS_PART_NAME='Q_RES_0402LF-33,5%,1/16W,CHIP,CS03302JB10',
 PART_NUMBER='CS03302JB10',
 VALUE='33',
 PRIM_FILE='./archive_libs/logical/q_res/chips/chips.prt';

PART_NAME
 R6900 'Q_RES_0201LF-1K,1%,1/20W,EMPTY,CS21001FE07':;

SECTION_NUMBER 1
 '@T6G_MB_LIB.T6G(SCH_1):PAGE463_I19@PURE_QUANTA.Q_RES(CHIPS)':
 C_PATH='@t6g_mb_lib.t6g(sch_1):page463_i19@pure_quanta.q_res(chips)',
 P_PATH='@t6g_mb_lib.t6g(sch_1):page354_i19@pure_quanta.q_res(chips)',
 PATH='I19',
 DRAWING='@T6G_MB_LIB.T6G(SCH_1):PAGE463',
 WATTAGE='1/20W',
 TOLERANCE='1%',
 MATERIAL='EMPTY',
 PHYS_PAGE='354',
 XY='(-8675,3925)',
 ROT='0',
 VER='2',
 PACK_TYPE='0201LF',
 LOCATION='R6900',
 CDS_LIB='pure_quanta',
 CDS_PART_NAME='Q_RES_0201LF-1K,1%,1/20W,EMPTY,CS21001FE07',
 PART_NUMBER='CS21001FE07',
 VALUE='1K',
 PRIM_FILE='./archive_libs/logical/q_res/chips/chips.prt';

PART_NAME
 R6901 'Q_RES_0201LF-200,1%,1/20W,CHIP,CS12001FE12':;

SECTION_NUMBER 1
 '@T6G_MB_LIB.T6G(SCH_1):PAGE463_I18@PURE_QUANTA.Q_RES(CHIPS)':
 C_PATH='@t6g_mb_lib.t6g(sch_1):page463_i18@pure_quanta.q_res(chips)',
 P_PATH='@t6g_mb_lib.t6g(sch_1):page354_i18@pure_quanta.q_res(chips)',
 PATH='I18',
 DRAWING='@T6G_MB_LIB.T6G(SCH_1):PAGE463',
 WATTAGE='1/20W',
 TOLERANCE='1%',
 MATERIAL='CHIP',
 PHYS_PAGE='354',
 XY='(-7650,3375)',
 ROT='0',
 VER='2',
 PACK_TYPE='0201LF',
 LOCATION='R6901',
 CDS_LIB='pure_quanta',
 CDS_PART_NAME='Q_RES_0201LF-200,1%,1/20W,CHIP,CS12001FE12',
 PART_NUMBER='CS12001FE12',
 VALUE='200',
 PRIM_FILE='./archive_libs/logical/q_res/chips/chips.prt';

PART_NAME
 R6902 'Q_RES_0201LF-0,5%,1/20W,CHIP,CS00001JE10':;

SECTION_NUMBER 1
 '@T6G_MB_LIB.T6G(SCH_1):PAGE463_I15@PURE_QUANTA.Q_RES(CHIPS)':
 C_PATH='@t6g_mb_lib.t6g(sch_1):page463_i15@pure_quanta.q_res(chips)',
 P_PATH='@t6g_mb_lib.t6g(sch_1):page354_i15@pure_quanta.q_res(chips)',
 PATH='I15',
 DRAWING='@T6G_MB_LIB.T6G(SCH_1):PAGE463',
 WATTAGE='1/20W',
 TOLERANCE='5%',
 MATERIAL='CHIP',
 PHYS_PAGE='354',
 XY='(-1300,1825)',
 ROT='0',
 VER='2',
 PACK_TYPE='0201LF',
 LOCATION='R6902',
 CDS_LIB='pure_quanta',
 CDS_PART_NAME='Q_RES_0201LF-0,5%,1/20W,CHIP,CS00001JE10',
 PART_NUMBER='CS00001JE10',
 VALUE='0',
 PRIM_FILE='./archive_libs/logical/q_res/chips/chips.prt';

PART_NAME
 R6903 'Q_RES_0201LF-0,5%,1/20W,CHIP,CS00001JE10':;

SECTION_NUMBER 1
 '@T6G_MB_LIB.T6G(SCH_1):PAGE463_I13@PURE_QUANTA.Q_RES(CHIPS)':
 C_PATH='@t6g_mb_lib.t6g(sch_1):page463_i13@pure_quanta.q_res(chips)',
 P_PATH='@t6g_mb_lib.t6g(sch_1):page354_i13@pure_quanta.q_res(chips)',
 PATH='I13',
 DRAWING='@T6G_MB_LIB.T6G(SCH_1):PAGE463',
 WATTAGE='1/20W',
 TOLERANCE='5%',
 MATERIAL='CHIP',
 PHYS_PAGE='354',
 XY='(-1450,1275)',
 ROT='0',
 VER='2',
 PACK_TYPE='0201LF',
 LOCATION='R6903',
 CDS_LIB='pure_quanta',
 CDS_PART_NAME='Q_RES_0201LF-0,5%,1/20W,CHIP,CS00001JE10',
 PART_NUMBER='CS00001JE10',
 VALUE='0',
 PRIM_FILE='./archive_libs/logical/q_res/chips/chips.prt';

PART_NAME
 R8000 'Q_RES_0402LF-33.2,1%,1/16W,CHIP,CS03322FB03':;

SECTION_NUMBER 1
 '@T6G_MB_LIB.T6G(SCH_1):PAGE80_I315@PURE_QUANTA.Q_RES(CHIPS)':
 C_PATH='@t6g_mb_lib.t6g(sch_1):page80_i315@pure_quanta.q_res(chips)',
 P_PATH='@t6g_mb_lib.t6g(sch_1):page81_i315@pure_quanta.q_res(chips)',
 PATH='I315',
 DRAWING='@T6G_MB_LIB.T6G(SCH_1):PAGE80',
 WATTAGE='1/16W',
 TOLERANCE='1%',
 MATERIAL='CHIP',
 PHYS_PAGE='81',
 XY='(-6725,2725)',
 ROT='0',
 VER='1',
 PACK_TYPE='0402LF',
 LOCATION='R8000',
 CDS_LIB='pure_quanta',
 CDS_PART_NAME='Q_RES_0402LF-33.2,1%,1/16W,CHIP,CS03322FB03',
 PART_NUMBER='CS03322FB03',
 VALUE='33.2',
 PRIM_FILE='./archive_libs/logical/q_res/chips/chips.prt';

PART_NAME
 R8001 'Q_RES_0402LF-100K,1%,1/16W,EMPTY,CS41002FB09':;

SECTION_NUMBER 1
 '@T6G_MB_LIB.T6G(SCH_1):PAGE330_I12@PURE_QUANTA.Q_RES(CHIPS)':
 C_PATH='@t6g_mb_lib.t6g(sch_1):page330_i12@pure_quanta.q_res(chips)',
 P_PATH='@t6g_mb_lib.t6g(sch_1):page123_i12@pure_quanta.q_res(chips)',
 PATH='I12',
 DRAWING='@T6G_MB_LIB.T6G(SCH_1):PAGE330',
 SEC_TYPE='0402LF',
 WATTAGE='1/16W',
 TOLERANCE='1%',
 MATERIAL='EMPTY',
 PHYS_PAGE='123',
 XY='(-6275,7525)',
 ROT='2',
 VER='2',
 PACK_TYPE='0402LF',
 LOCATION='R8001',
 SEC='1',
 CDS_LIB='pure_quanta',
 CDS_PART_NAME='Q_RES_0402LF-100K,1%,1/16W,EMPTY,CS41002FB09',
 PART_NUMBER='CS41002FB09',
 VALUE='100K',
 PRIM_FILE='./archive_libs/logical/q_res/chips/chips.prt';

PART_NAME
 R8002 'Q_RES_0402LF-4.7K,5%,1/16W,CHIP,CS24702JB10':;

SECTION_NUMBER 1
 '@T6G_MB_LIB.T6G(SCH_1):PAGE330_I55@PURE_QUANTA.Q_RES(CHIPS)':
 C_PATH='@t6g_mb_lib.t6g(sch_1):page330_i55@pure_quanta.q_res(chips)',
 P_PATH='@t6g_mb_lib.t6g(sch_1):page123_i55@pure_quanta.q_res(chips)',
 PATH='I55',
 DRAWING='@T6G_MB_LIB.T6G(SCH_1):PAGE330',
 WATTAGE='1/16W',
 TOLERANCE='5%',
 MATERIAL='CHIP',
 PHYS_PAGE='123',
 XY='(-5675,8475)',
 ROT='2',
 VER='2',
 PACK_TYPE='0402LF',
 LOCATION='R8002',
 CDS_LIB='pure_quanta',
 CDS_PART_NAME='Q_RES_0402LF-4.7K,5%,1/16W,CHIP,CS24702JB10',
 PART_NUMBER='CS24702JB10',
 VALUE='4.7K',
 PRIM_FILE='./archive_libs/logical/q_res/chips/chips.prt';

PART_NAME
 R8003 'Q_RES_0402LF-4.7K,5%,1/16W,CHIP,CS24702JB10':;

SECTION_NUMBER 1
 '@T6G_MB_LIB.T6G(SCH_1):PAGE330_I57@PURE_QUANTA.Q_RES(CHIPS)':
 C_PATH='@t6g_mb_lib.t6g(sch_1):page330_i57@pure_quanta.q_res(chips)',
 P_PATH='@t6g_mb_lib.t6g(sch_1):page123_i57@pure_quanta.q_res(chips)',
 PATH='I57',
 DRAWING='@T6G_MB_LIB.T6G(SCH_1):PAGE330',
 WATTAGE='1/16W',
 TOLERANCE='5%',
 MATERIAL='CHIP',
 PHYS_PAGE='123',
 XY='(-4850,8725)',
 ROT='2',
 VER='2',
 PACK_TYPE='0402LF',
 LOCATION='R8003',
 CDS_LIB='pure_quanta',
 CDS_PART_NAME='Q_RES_0402LF-4.7K,5%,1/16W,CHIP,CS24702JB10',
 PART_NUMBER='CS24702JB10',
 VALUE='4.7K',
 PRIM_FILE='./archive_libs/logical/q_res/chips/chips.prt';

PART_NAME
 R8004 'Q_RES_0402LF-0,5%,1/16W,CHIP,CS00002JB13':;

SECTION_NUMBER 1
 '@T6G_MB_LIB.T6G(SCH_1):PAGE246_I41@PURE_QUANTA.Q_RES(CHIPS)':
 C_PATH='@t6g_mb_lib.t6g(sch_1):page246_i41@pure_quanta.q_res(chips)',
 P_PATH='@t6g_mb_lib.t6g(sch_1):page245_i41@pure_quanta.q_res(chips)',
 PATH='I41',
 DRAWING='@T6G_MB_LIB.T6G(SCH_1):PAGE246',
 WATTAGE='1/16W',
 TOLERANCE='5%',
 MATERIAL='CHIP',
 PHYS_PAGE='245',
 XY='(-3525,1075)',
 ROT='0',
 VER='1',
 PACK_TYPE='0402LF',
 LOCATION='R8004',
 CDS_LIB='pure_quanta',
 CDS_PART_NAME='Q_RES_0402LF-0,5%,1/16W,CHIP,CS00002JB13',
 PART_NUMBER='CS00002JB13',
 VALUE='0',
 PRIM_FILE='./archive_libs/logical/q_res/chips/chips.prt';

PART_NAME
 R8005 'Q_RES_0402LF-33,5%,1/16W,CHIP,CS03302JB10':;

SECTION_NUMBER 1
 '@T6G_MB_LIB.T6G(SCH_1):PAGE76_I234@PURE_QUANTA.Q_RES(CHIPS)':
 C_PATH='@t6g_mb_lib.t6g(sch_1):page76_i234@pure_quanta.q_res(chips)',
 P_PATH='@t6g_mb_lib.t6g(sch_1):page77_i234@pure_quanta.q_res(chips)',
 PATH='I234',
 DRAWING='@T6G_MB_LIB.T6G(SCH_1):PAGE76',
 SEC_TYPE='0402LF',
 WATTAGE='1/16W',
 TOLERANCE='5%',
 MATERIAL='CHIP',
 PHYS_PAGE='77',
 XY='(-6800,2375)',
 ROT='0',
 VER='1',
 PACK_TYPE='0402LF',
 LOCATION='R8005',
 SEC='1',
 CDS_LIB='pure_quanta',
 CDS_PART_NAME='Q_RES_0402LF-33,5%,1/16W,CHIP,CS03302JB10',
 PART_NUMBER='CS03302JB10',
 VALUE='33',
 PRIM_FILE='./archive_libs/logical/q_res/chips/chips.prt';

PART_NAME
 R8006 'Q_RES_0402LF-33,5%,1/16W,CHIP,CS03302JB10':;

SECTION_NUMBER 1
 '@T6G_MB_LIB.T6G(SCH_1):PAGE76_I239@PURE_QUANTA.Q_RES(CHIPS)':
 C_PATH='@t6g_mb_lib.t6g(sch_1):page76_i239@pure_quanta.q_res(chips)',
 P_PATH='@t6g_mb_lib.t6g(sch_1):page77_i239@pure_quanta.q_res(chips)',
 PATH='I239',
 DRAWING='@T6G_MB_LIB.T6G(SCH_1):PAGE76',
 SEC_TYPE='0402LF',
 WATTAGE='1/16W',
 TOLERANCE='5%',
 MATERIAL='CHIP',
 PHYS_PAGE='77',
 XY='(-6800,2325)',
 ROT='0',
 VER='1',
 PACK_TYPE='0402LF',
 LOCATION='R8006',
 SEC='1',
 CDS_LIB='pure_quanta',
 CDS_PART_NAME='Q_RES_0402LF-33,5%,1/16W,CHIP,CS03302JB10',
 PART_NUMBER='CS03302JB10',
 VALUE='33',
 PRIM_FILE='./archive_libs/logical/q_res/chips/chips.prt';

PART_NAME
 R8007 'Q_RES_0402LF-33,5%,1/16W,CHIP,CS03302JB10':;

SECTION_NUMBER 1
 '@T6G_MB_LIB.T6G(SCH_1):PAGE76_I240@PURE_QUANTA.Q_RES(CHIPS)':
 C_PATH='@t6g_mb_lib.t6g(sch_1):page76_i240@pure_quanta.q_res(chips)',
 P_PATH='@t6g_mb_lib.t6g(sch_1):page77_i240@pure_quanta.q_res(chips)',
 PATH='I240',
 DRAWING='@T6G_MB_LIB.T6G(SCH_1):PAGE76',
 SEC_TYPE='0402LF',
 WATTAGE='1/16W',
 TOLERANCE='5%',
 MATERIAL='CHIP',
 PHYS_PAGE='77',
 XY='(-6800,2275)',
 ROT='0',
 VER='1',
 PACK_TYPE='0402LF',
 LOCATION='R8007',
 SEC='1',
 CDS_LIB='pure_quanta',
 CDS_PART_NAME='Q_RES_0402LF-33,5%,1/16W,CHIP,CS03302JB10',
 PART_NUMBER='CS03302JB10',
 VALUE='33',
 PRIM_FILE='./archive_libs/logical/q_res/chips/chips.prt';

PART_NAME
 R8008 'Q_RES_0402LF-33,5%,1/16W,CHIP,CS03302JB10':;

SECTION_NUMBER 1
 '@T6G_MB_LIB.T6G(SCH_1):PAGE76_I241@PURE_QUANTA.Q_RES(CHIPS)':
 C_PATH='@t6g_mb_lib.t6g(sch_1):page76_i241@pure_quanta.q_res(chips)',
 P_PATH='@t6g_mb_lib.t6g(sch_1):page77_i241@pure_quanta.q_res(chips)',
 PATH='I241',
 DRAWING='@T6G_MB_LIB.T6G(SCH_1):PAGE76',
 SEC_TYPE='0402LF',
 WATTAGE='1/16W',
 TOLERANCE='5%',
 MATERIAL='CHIP',
 PHYS_PAGE='77',
 XY='(-6800,2225)',
 ROT='0',
 VER='1',
 PACK_TYPE='0402LF',
 LOCATION='R8008',
 SEC='1',
 CDS_LIB='pure_quanta',
 CDS_PART_NAME='Q_RES_0402LF-33,5%,1/16W,CHIP,CS03302JB10',
 PART_NUMBER='CS03302JB10',
 VALUE='33',
 PRIM_FILE='./archive_libs/logical/q_res/chips/chips.prt';

PART_NAME
 R8009 'Q_RES_0402LF-10K,5%,1/16W,CHIP,CS31002JB08':;

SECTION_NUMBER 1
 '@T6G_MB_LIB.T6G(SCH_1):PAGE201_I26@PURE_QUANTA.Q_RES(CHIPS)':
 C_PATH='@t6g_mb_lib.t6g(sch_1):page201_i26@pure_quanta.q_res(chips)',
 P_PATH='@t6g_mb_lib.t6g(sch_1):page226_i26@pure_quanta.q_res(chips)',
 PATH='I26',
 DRAWING='@T6G_MB_LIB.T6G(SCH_1):PAGE201',
 SEC_TYPE='0402LF',
 WATTAGE='1/16W',
 TOLERANCE='5%',
 MATERIAL='CHIP',
 PHYS_PAGE='226',
 XY='(-4375,4800)',
 ROT='0',
 VER='2',
 PACK_TYPE='0402LF',
 LOCATION='R8009',
 SEC='1',
 CDS_LIB='pure_quanta',
 CDS_PART_NAME='Q_RES_0402LF-10K,5%,1/16W,CHIP,CS31002JB08',
 PART_NUMBER='CS31002JB08',
 VALUE='10K',
 PRIM_FILE='./archive_libs/logical/q_res/chips/chips.prt';

PART_NAME
 R8010 'Q_RES_0402LF-0,5%,1/16W,EMPTY,CS00002JB13':;

SECTION_NUMBER 1
 '@T6G_MB_LIB.T6G(SCH_1):PAGE199_I13@PURE_QUANTA.Q_RES(CHIPS)':
 C_PATH='@t6g_mb_lib.t6g(sch_1):page199_i13@pure_quanta.q_res(chips)',
 P_PATH='@t6g_mb_lib.t6g(sch_1):page224_i13@pure_quanta.q_res(chips)',
 PATH='I13',
 DRAWING='@T6G_MB_LIB.T6G(SCH_1):PAGE199',
 WATTAGE='1/16W',
 TOLERANCE='5%',
 MATERIAL='EMPTY',
 PHYS_PAGE='224',
 XY='(-6250,2125)',
 ROT='0',
 VER='1',
 PACK_TYPE='0402LF',
 LOCATION='R8010',
 CDS_LIB='pure_quanta',
 CDS_PART_NAME='Q_RES_0402LF-0,5%,1/16W,EMPTY,CS00002JB13',
 PART_NUMBER='CS00002JB13',
 VALUE='0',
 PRIM_FILE='./archive_libs/logical/q_res/chips/chips.prt';

PART_NAME
 R8011 'Q_RES_0402LF-1K,1%,1/16W,EMPTY,CS21002FB06':;

SECTION_NUMBER 1
 '@T6G_MB_LIB.T6G(SCH_1):PAGE199_I24@PURE_QUANTA.Q_RES(CHIPS)':
 C_PATH='@t6g_mb_lib.t6g(sch_1):page199_i24@pure_quanta.q_res(chips)',
 P_PATH='@t6g_mb_lib.t6g(sch_1):page224_i24@pure_quanta.q_res(chips)',
 PATH='I24',
 DRAWING='@T6G_MB_LIB.T6G(SCH_1):PAGE199',
 WATTAGE='1/16W',
 TOLERANCE='1%',
 MATERIAL='EMPTY',
 PHYS_PAGE='224',
 XY='(-5975,2350)',
 ROT='0',
 VER='2',
 PACK_TYPE='0402LF',
 LOCATION='R8011',
 CDS_LIB='pure_quanta',
 CDS_PART_NAME='Q_RES_0402LF-1K,1%,1/16W,EMPTY,CS21002FB06',
 PART_NUMBER='CS21002FB06',
 VALUE='1K',
 PRIM_FILE='./archive_libs/logical/q_res/chips/chips.prt';

PART_NAME
 R8012 'Q_RES_0402LF-0,5%,1/16W,CHIP,CS00002JB13':
 ROOM='SCM_P12V_MPS_BOM2';

SECTION_NUMBER 1
 '@T6G_MB_LIB.T6G(SCH_1):PAGE350_I89@PURE_QUANTA.Q_RES(CHIPS)':
 C_PATH='@t6g_mb_lib.t6g(sch_1):page350_i89@pure_quanta.q_res(chips)',
 P_PATH='@t6g_mb_lib.t6g(sch_1):page152_i89@pure_quanta.q_res(chips)',
 PATH='I89',
 DRAWING='@T6G_MB_LIB.T6G(SCH_1):PAGE350',
 SEC_TYPE='0402LF',
 WATTAGE='1/16W',
 TOLERANCE='5%',
 MATERIAL='CHIP',
 PHYS_PAGE='152',
 XY='(3175,12500)',
 ROT='0',
 VER='1',
 PACK_TYPE='0402LF',
 LOCATION='R8012',
 SEC='1',
 CDS_LIB='pure_quanta',
 CDS_PART_NAME='Q_RES_0402LF-0,5%,1/16W,CHIP,CS00002JB13',
 ROOM='SCM_P12V_MPS_BOM2',
 PART_NUMBER='CS00002JB13',
 VALUE='0',
 PRIM_FILE='./archive_libs/logical/q_res/chips/chips.prt';

PART_NAME
 R8013 'Q_RES_0402LF-0,5%,1/16W,EMPTY,CS00002JB13':;

SECTION_NUMBER 1
 '@T6G_MB_LIB.T6G(SCH_1):PAGE258_I64@PURE_QUANTA.Q_RES(CHIPS)':
 C_PATH='@t6g_mb_lib.t6g(sch_1):page258_i64@pure_quanta.q_res(chips)',
 P_PATH='@t6g_mb_lib.t6g(sch_1):page143_i64@pure_quanta.q_res(chips)',
 PATH='I64',
 DRAWING='@T6G_MB_LIB.T6G(SCH_1):PAGE258',
 SEC_TYPE='0402LF',
 WATTAGE='1/16W',
 TOLERANCE='5%',
 MATERIAL='EMPTY',
 PHYS_PAGE='143',
 XY='(-1450,2850)',
 ROT='0',
 VER='1',
 PACK_TYPE='0402LF',
 LOCATION='R8013',
 SEC='1',
 CDS_LIB='pure_quanta',
 CDS_PART_NAME='Q_RES_0402LF-0,5%,1/16W,EMPTY,CS00002JB13',
 PART_NUMBER='CS00002JB13',
 VALUE='0',
 PRIM_FILE='./archive_libs/logical/q_res/chips/chips.prt';

PART_NAME
 R8014 'Q_RES_0402LF-0,5%,1/16W,EMPTY,CS00002JB13':;

SECTION_NUMBER 1
 '@T6G_MB_LIB.T6G(SCH_1):PAGE258_I65@PURE_QUANTA.Q_RES(CHIPS)':
 C_PATH='@t6g_mb_lib.t6g(sch_1):page258_i65@pure_quanta.q_res(chips)',
 P_PATH='@t6g_mb_lib.t6g(sch_1):page143_i65@pure_quanta.q_res(chips)',
 PATH='I65',
 DRAWING='@T6G_MB_LIB.T6G(SCH_1):PAGE258',
 SEC_TYPE='0402LF',
 WATTAGE='1/16W',
 TOLERANCE='5%',
 MATERIAL='EMPTY',
 PHYS_PAGE='143',
 XY='(-1475,1950)',
 ROT='0',
 VER='1',
 PACK_TYPE='0402LF',
 LOCATION='R8014',
 SEC='1',
 CDS_LIB='pure_quanta',
 CDS_PART_NAME='Q_RES_0402LF-0,5%,1/16W,EMPTY,CS00002JB13',
 PART_NUMBER='CS00002JB13',
 VALUE='0',
 PRIM_FILE='./archive_libs/logical/q_res/chips/chips.prt';

PART_NAME
 R8015 'Q_RES_0402LF-0,5%,1/16W,EMPTY,CS00002JB13':;

SECTION_NUMBER 1
 '@T6G_MB_LIB.T6G(SCH_1):PAGE258_I66@PURE_QUANTA.Q_RES(CHIPS)':
 C_PATH='@t6g_mb_lib.t6g(sch_1):page258_i66@pure_quanta.q_res(chips)',
 P_PATH='@t6g_mb_lib.t6g(sch_1):page143_i66@pure_quanta.q_res(chips)',
 PATH='I66',
 DRAWING='@T6G_MB_LIB.T6G(SCH_1):PAGE258',
 SEC_TYPE='0402LF',
 WATTAGE='1/16W',
 TOLERANCE='5%',
 MATERIAL='EMPTY',
 PHYS_PAGE='143',
 XY='(-1450,750)',
 ROT='0',
 VER='1',
 PACK_TYPE='0402LF',
 LOCATION='R8015',
 SEC='1',
 CDS_LIB='pure_quanta',
 CDS_PART_NAME='Q_RES_0402LF-0,5%,1/16W,EMPTY,CS00002JB13',
 PART_NUMBER='CS00002JB13',
 VALUE='0',
 PRIM_FILE='./archive_libs/logical/q_res/chips/chips.prt';

PART_NAME
 R8016 'Q_RES_0402LF-0,5%,1/16W,EMPTY,CS00002JB13':;

SECTION_NUMBER 1
 '@T6G_MB_LIB.T6G(SCH_1):PAGE258_I67@PURE_QUANTA.Q_RES(CHIPS)':
 C_PATH='@t6g_mb_lib.t6g(sch_1):page258_i67@pure_quanta.q_res(chips)',
 P_PATH='@t6g_mb_lib.t6g(sch_1):page143_i67@pure_quanta.q_res(chips)',
 PATH='I67',
 DRAWING='@T6G_MB_LIB.T6G(SCH_1):PAGE258',
 SEC_TYPE='0402LF',
 WATTAGE='1/16W',
 TOLERANCE='5%',
 MATERIAL='EMPTY',
 PHYS_PAGE='143',
 XY='(-1475,-150)',
 ROT='0',
 VER='1',
 PACK_TYPE='0402LF',
 LOCATION='R8016',
 SEC='1',
 CDS_LIB='pure_quanta',
 CDS_PART_NAME='Q_RES_0402LF-0,5%,1/16W,EMPTY,CS00002JB13',
 PART_NUMBER='CS00002JB13',
 VALUE='0',
 PRIM_FILE='./archive_libs/logical/q_res/chips/chips.prt';

PART_NAME
 R8017 'Q_RES_0402LF-0,5%,1/16W,EMPTY,CS00002JB13':;

SECTION_NUMBER 1
 '@T6G_MB_LIB.T6G(SCH_1):PAGE144_I85@PURE_QUANTA.Q_RES(CHIPS)':
 C_PATH='@t6g_mb_lib.t6g(sch_1):page144_i85@pure_quanta.q_res(chips)',
 P_PATH='@t6g_mb_lib.t6g(sch_1):page167_i85@pure_quanta.q_res(chips)',
 PATH='I85',
 DRAWING='@T6G_MB_LIB.T6G(SCH_1):PAGE144',
 SEC_TYPE='0402LF',
 WATTAGE='1/16W',
 TOLERANCE='5%',
 MATERIAL='EMPTY',
 PHYS_PAGE='167',
 XY='(-4750,1550)',
 ROT='2',
 VER='2',
 PACK_TYPE='0402LF',
 LOCATION='R8017',
 SEC='1',
 CDS_LIB='pure_quanta',
 CDS_PART_NAME='Q_RES_0402LF-0,5%,1/16W,EMPTY,CS00002JB13',
 PART_NUMBER='CS00002JB13',
 VALUE='0',
 PRIM_FILE='./archive_libs/logical/q_res/chips/chips.prt';

PART_NAME
 R8018 'Q_RES_0402LF-0,5%,1/16W,CHIP,CS00002JB13':;

SECTION_NUMBER 1
 '@T6G_MB_LIB.T6G(SCH_1):PAGE144_I84@PURE_QUANTA.Q_RES(CHIPS)':
 C_PATH='@t6g_mb_lib.t6g(sch_1):page144_i84@pure_quanta.q_res(chips)',
 P_PATH='@t6g_mb_lib.t6g(sch_1):page167_i84@pure_quanta.q_res(chips)',
 PATH='I84',
 DRAWING='@T6G_MB_LIB.T6G(SCH_1):PAGE144',
 WATTAGE='1/16W',
 TOLERANCE='5%',
 MATERIAL='CHIP',
 PHYS_PAGE='167',
 XY='(-4500,1550)',
 ROT='0',
 VER='2',
 PACK_TYPE='0402LF',
 LOCATION='R8018',
 CDS_LIB='pure_quanta',
 CDS_PART_NAME='Q_RES_0402LF-0,5%,1/16W,CHIP,CS00002JB13',
 PART_NUMBER='CS00002JB13',
 VALUE='0',
 PRIM_FILE='./archive_libs/logical/q_res/chips/chips.prt';

PART_NAME
 R8019 'Q_RES_0402LF-100,1%,1/16W,EMPTY,CS11002FB07':;

SECTION_NUMBER 1
 '@T6G_MB_LIB.T6G(SCH_1):PAGE144_I89@PURE_QUANTA.Q_RES(CHIPS)':
 C_PATH='@t6g_mb_lib.t6g(sch_1):page144_i89@pure_quanta.q_res(chips)',
 P_PATH='@t6g_mb_lib.t6g(sch_1):page167_i89@pure_quanta.q_res(chips)',
 PATH='I89',
 DRAWING='@T6G_MB_LIB.T6G(SCH_1):PAGE144',
 WATTAGE='1/16W',
 TOLERANCE='1%',
 MATERIAL='EMPTY',
 PHYS_PAGE='167',
 XY='(-5475,1000)',
 ROT='0',
 VER='2',
 PACK_TYPE='0402LF',
 LOCATION='R8019',
 CDS_LIB='pure_quanta',
 CDS_PART_NAME='Q_RES_0402LF-100,1%,1/16W,EMPTY,CS11002FB07',
 PART_NUMBER='CS11002FB07',
 VALUE='100',
 PRIM_FILE='./archive_libs/logical/q_res/chips/chips.prt';

PART_NAME
 R8021 'Q_RES_0402LF-0,5%,1/16W,CHIP,CS00002JB13':;

SECTION_NUMBER 1
 '@T6G_MB_LIB.T6G(SCH_1):PAGE80_I318@PURE_QUANTA.Q_RES(CHIPS)':
 C_PATH='@t6g_mb_lib.t6g(sch_1):page80_i318@pure_quanta.q_res(chips)',
 P_PATH='@t6g_mb_lib.t6g(sch_1):page81_i318@pure_quanta.q_res(chips)',
 PATH='I318',
 DRAWING='@T6G_MB_LIB.T6G(SCH_1):PAGE80',
 SEC_TYPE='0402LF',
 BOM_COST='MEM',
 WATTAGE='1/16W',
 TOLERANCE='5%',
 MATERIAL='CHIP',
 PHYS_PAGE='81',
 XY='(-3225,5575)',
 ROT='0',
 VER='1',
 PACK_TYPE='0402LF',
 LOCATION='R8021',
 SEC='1',
 CDS_LIB='pure_quanta',
 CDS_PART_NAME='Q_RES_0402LF-0,5%,1/16W,CHIP,CS00002JB13',
 PART_NUMBER='CS00002JB13',
 VALUE='0',
 PRIM_FILE='./archive_libs/logical/q_res/chips/chips.prt';

PART_NAME
 R8022 'Q_RES_0402LF-560,1%,1/16W,CHIP,CS15602FB03':;

SECTION_NUMBER 1
 '@T6G_MB_LIB.T6G(SCH_1):PAGE375_I44@PURE_QUANTA.Q_RES(CHIPS)':
 C_PATH='@t6g_mb_lib.t6g(sch_1):page375_i44@pure_quanta.q_res(chips)',
 P_PATH='@t6g_mb_lib.t6g(sch_1):page256_i44@pure_quanta.q_res(chips)',
 PATH='I44',
 DRAWING='@T6G_MB_LIB.T6G(SCH_1):PAGE375',
 SEC_TYPE='0402LF',
 WATTAGE='1/16W',
 TOLERANCE='1%',
 MATERIAL='CHIP',
 PHYS_PAGE='256',
 XY='(-3000,3575)',
 ROT='0',
 VER='1',
 PACK_TYPE='0402LF',
 LOCATION='R8022',
 SEC='1',
 CDS_LIB='pure_quanta',
 CDS_PART_NAME='Q_RES_0402LF-560,1%,1/16W,CHIP,CS15602FB03',
 PART_NUMBER='CS15602FB03',
 VALUE='560',
 PRIM_FILE='./archive_libs/logical/q_res/chips/chips.prt';

PART_NAME
 R8023 'Q_RES_0402LF-560,1%,1/16W,CHIP,CS15602FB03':;

SECTION_NUMBER 1
 '@T6G_MB_LIB.T6G(SCH_1):PAGE375_I45@PURE_QUANTA.Q_RES(CHIPS)':
 C_PATH='@t6g_mb_lib.t6g(sch_1):page375_i45@pure_quanta.q_res(chips)',
 P_PATH='@t6g_mb_lib.t6g(sch_1):page256_i45@pure_quanta.q_res(chips)',
 PATH='I45',
 DRAWING='@T6G_MB_LIB.T6G(SCH_1):PAGE375',
 SEC_TYPE='0402LF',
 WATTAGE='1/16W',
 TOLERANCE='1%',
 MATERIAL='CHIP',
 PHYS_PAGE='256',
 XY='(-2075,3575)',
 ROT='0',
 VER='1',
 PACK_TYPE='0402LF',
 LOCATION='R8023',
 SEC='1',
 CDS_LIB='pure_quanta',
 CDS_PART_NAME='Q_RES_0402LF-560,1%,1/16W,CHIP,CS15602FB03',
 PART_NUMBER='CS15602FB03',
 VALUE='560',
 PRIM_FILE='./archive_libs/logical/q_res/chips/chips.prt';

PART_NAME
 R8024 'Q_RES_0402LF-560,1%,1/16W,CHIP,CS15602FB03':;

SECTION_NUMBER 1
 '@T6G_MB_LIB.T6G(SCH_1):PAGE375_I46@PURE_QUANTA.Q_RES(CHIPS)':
 C_PATH='@t6g_mb_lib.t6g(sch_1):page375_i46@pure_quanta.q_res(chips)',
 P_PATH='@t6g_mb_lib.t6g(sch_1):page256_i46@pure_quanta.q_res(chips)',
 PATH='I46',
 DRAWING='@T6G_MB_LIB.T6G(SCH_1):PAGE375',
 SEC_TYPE='0402LF',
 WATTAGE='1/16W',
 TOLERANCE='1%',
 MATERIAL='CHIP',
 PHYS_PAGE='256',
 XY='(-1075,3575)',
 ROT='0',
 VER='1',
 PACK_TYPE='0402LF',
 LOCATION='R8024',
 SEC='1',
 CDS_LIB='pure_quanta',
 CDS_PART_NAME='Q_RES_0402LF-560,1%,1/16W,CHIP,CS15602FB03',
 PART_NUMBER='CS15602FB03',
 VALUE='560',
 PRIM_FILE='./archive_libs/logical/q_res/chips/chips.prt';

PART_NAME
 R8025 'Q_RES_0402LF-560,1%,1/16W,CHIP,CS15602FB03':;

SECTION_NUMBER 1
 '@T6G_MB_LIB.T6G(SCH_1):PAGE375_I51@PURE_QUANTA.Q_RES(CHIPS)':
 C_PATH='@t6g_mb_lib.t6g(sch_1):page375_i51@pure_quanta.q_res(chips)',
 P_PATH='@t6g_mb_lib.t6g(sch_1):page256_i51@pure_quanta.q_res(chips)',
 PATH='I51',
 DRAWING='@T6G_MB_LIB.T6G(SCH_1):PAGE375',
 SEC_TYPE='0402LF',
 WATTAGE='1/16W',
 TOLERANCE='1%',
 MATERIAL='CHIP',
 PHYS_PAGE='256',
 XY='(-2925,2425)',
 ROT='0',
 VER='1',
 PACK_TYPE='0402LF',
 LOCATION='R8025',
 SEC='1',
 CDS_LIB='pure_quanta',
 CDS_PART_NAME='Q_RES_0402LF-560,1%,1/16W,CHIP,CS15602FB03',
 PART_NUMBER='CS15602FB03',
 VALUE='560',
 PRIM_FILE='./archive_libs/logical/q_res/chips/chips.prt';

PART_NAME
 R8026 'Q_RES_0402LF-560,1%,1/16W,CHIP,CS15602FB03':;

SECTION_NUMBER 1
 '@T6G_MB_LIB.T6G(SCH_1):PAGE375_I50@PURE_QUANTA.Q_RES(CHIPS)':
 C_PATH='@t6g_mb_lib.t6g(sch_1):page375_i50@pure_quanta.q_res(chips)',
 P_PATH='@t6g_mb_lib.t6g(sch_1):page256_i50@pure_quanta.q_res(chips)',
 PATH='I50',
 DRAWING='@T6G_MB_LIB.T6G(SCH_1):PAGE375',
 SEC_TYPE='0402LF',
 WATTAGE='1/16W',
 TOLERANCE='1%',
 MATERIAL='CHIP',
 PHYS_PAGE='256',
 XY='(-2000,2425)',
 ROT='0',
 VER='1',
 PACK_TYPE='0402LF',
 LOCATION='R8026',
 SEC='1',
 CDS_LIB='pure_quanta',
 CDS_PART_NAME='Q_RES_0402LF-560,1%,1/16W,CHIP,CS15602FB03',
 PART_NUMBER='CS15602FB03',
 VALUE='560',
 PRIM_FILE='./archive_libs/logical/q_res/chips/chips.prt';

PART_NAME
 R8027 'Q_RES_0402LF-560,1%,1/16W,CHIP,CS15602FB03':;

SECTION_NUMBER 1
 '@T6G_MB_LIB.T6G(SCH_1):PAGE375_I49@PURE_QUANTA.Q_RES(CHIPS)':
 C_PATH='@t6g_mb_lib.t6g(sch_1):page375_i49@pure_quanta.q_res(chips)',
 P_PATH='@t6g_mb_lib.t6g(sch_1):page256_i49@pure_quanta.q_res(chips)',
 PATH='I49',
 DRAWING='@T6G_MB_LIB.T6G(SCH_1):PAGE375',
 SEC_TYPE='0402LF',
 WATTAGE='1/16W',
 TOLERANCE='1%',
 MATERIAL='CHIP',
 PHYS_PAGE='256',
 XY='(-1000,2425)',
 ROT='0',
 VER='1',
 PACK_TYPE='0402LF',
 LOCATION='R8027',
 SEC='1',
 CDS_LIB='pure_quanta',
 CDS_PART_NAME='Q_RES_0402LF-560,1%,1/16W,CHIP,CS15602FB03',
 PART_NUMBER='CS15602FB03',
 VALUE='560',
 PRIM_FILE='./archive_libs/logical/q_res/chips/chips.prt';

PART_NAME
 R8028 'Q_RES_0402LF-4.7K,5%,1/16W,CHIP,CS24702JB10':;

SECTION_NUMBER 1
 '@T6G_MB_LIB.T6G(SCH_1):PAGE375_I62@PURE_QUANTA.Q_RES(CHIPS)':
 C_PATH='@t6g_mb_lib.t6g(sch_1):page375_i62@pure_quanta.q_res(chips)',
 P_PATH='@t6g_mb_lib.t6g(sch_1):page256_i62@pure_quanta.q_res(chips)',
 PATH='I62',
 DRAWING='@T6G_MB_LIB.T6G(SCH_1):PAGE375',
 WATTAGE='1/16W',
 TOLERANCE='5%',
 MATERIAL='CHIP',
 PHYS_PAGE='256',
 XY='(-3025,1425)',
 ROT='2',
 VER='2',
 PACK_TYPE='0402LF',
 LOCATION='R8028',
 CDS_LIB='pure_quanta',
 CDS_PART_NAME='Q_RES_0402LF-4.7K,5%,1/16W,CHIP,CS24702JB10',
 PART_NUMBER='CS24702JB10',
 VALUE='4.7K',
 PRIM_FILE='./archive_libs/logical/q_res/chips/chips.prt';

PART_NAME
 R8029 'Q_RES_0402LF-249,1%,1/16W,CHIP,CS12492FB02':;

SECTION_NUMBER 1
 '@T6G_MB_LIB.T6G(SCH_1):PAGE375_I55@PURE_QUANTA.Q_RES(CHIPS)':
 C_PATH='@t6g_mb_lib.t6g(sch_1):page375_i55@pure_quanta.q_res(chips)',
 P_PATH='@t6g_mb_lib.t6g(sch_1):page256_i55@pure_quanta.q_res(chips)',
 PATH='I55',
 DRAWING='@T6G_MB_LIB.T6G(SCH_1):PAGE375',
 SEC_TYPE='0402LF',
 WATTAGE='1/16W',
 TOLERANCE='1%',
 MATERIAL='CHIP',
 PHYS_PAGE='256',
 XY='(-775,1500)',
 ROT='0',
 VER='1',
 PACK_TYPE='0402LF',
 LOCATION='R8029',
 SEC='1',
 CDS_LIB='pure_quanta',
 CDS_PART_NAME='Q_RES_0402LF-249,1%,1/16W,CHIP,CS12492FB02',
 PART_NUMBER='CS12492FB02',
 VALUE='249',
 PRIM_FILE='./archive_libs/logical/q_res/chips/chips.prt';

PART_NAME
 R8030 'Q_RES_0402LF-0,5%,1/16W,CHIP,CS00002JB13':
 ROOM='SCM_P12V_MAM_BOM1';

SECTION_NUMBER 1
 '@T6G_MB_LIB.T6G(SCH_1):PAGE350_I91@PURE_QUANTA.Q_RES(CHIPS)':
 C_PATH='@t6g_mb_lib.t6g(sch_1):page350_i91@pure_quanta.q_res(chips)',
 P_PATH='@t6g_mb_lib.t6g(sch_1):page152_i91@pure_quanta.q_res(chips)',
 PATH='I91',
 DRAWING='@T6G_MB_LIB.T6G(SCH_1):PAGE350',
 WATTAGE='1/16W',
 TOLERANCE='5%',
 MATERIAL='CHIP',
 PHYS_PAGE='152',
 XY='(3750,14800)',
 ROT='0',
 VER='1',
 PACK_TYPE='0402LF',
 LOCATION='R8030',
 CDS_LIB='pure_quanta',
 CDS_PART_NAME='Q_RES_0402LF-0,5%,1/16W,CHIP,CS00002JB13',
 ROOM='SCM_P12V_MAM_BOM1',
 PART_NUMBER='CS00002JB13',
 VALUE='0',
 PRIM_FILE='./archive_libs/logical/q_res/chips/chips.prt';

PART_NAME
 R8031 'Q_RES_0402LF-0,5%,1/16W,CHIP,CS00002JB13':
 ROOM='SCM_P12V_MPS_BOM2';

SECTION_NUMBER 1
 '@T6G_MB_LIB.T6G(SCH_1):PAGE350_I93@PURE_QUANTA.Q_RES(CHIPS)':
 C_PATH='@t6g_mb_lib.t6g(sch_1):page350_i93@pure_quanta.q_res(chips)',
 P_PATH='@t6g_mb_lib.t6g(sch_1):page152_i93@pure_quanta.q_res(chips)',
 PATH='I93',
 DRAWING='@T6G_MB_LIB.T6G(SCH_1):PAGE350',
 WATTAGE='1/16W',
 TOLERANCE='5%',
 MATERIAL='CHIP',
 PHYS_PAGE='152',
 XY='(3450,11100)',
 ROT='0',
 VER='1',
 PACK_TYPE='0402LF',
 LOCATION='R8031',
 CDS_LIB='pure_quanta',
 CDS_PART_NAME='Q_RES_0402LF-0,5%,1/16W,CHIP,CS00002JB13',
 ROOM='SCM_P12V_MPS_BOM2',
 PART_NUMBER='CS00002JB13',
 VALUE='0',
 PRIM_FILE='./archive_libs/logical/q_res/chips/chips.prt';

PART_NAME
 R8032 'Q_RES_0402LF-0,5%,1/16W,CHIP,CS00002JB13':;

SECTION_NUMBER 1
 '@T6G_MB_LIB.T6G(SCH_1):PAGE80_I319@PURE_QUANTA.Q_RES(CHIPS)':
 C_PATH='@t6g_mb_lib.t6g(sch_1):page80_i319@pure_quanta.q_res(chips)',
 P_PATH='@t6g_mb_lib.t6g(sch_1):page81_i319@pure_quanta.q_res(chips)',
 PATH='I319',
 DRAWING='@T6G_MB_LIB.T6G(SCH_1):PAGE80',
 BOM_COST='MEM',
 WATTAGE='1/16W',
 TOLERANCE='5%',
 MATERIAL='CHIP',
 PHYS_PAGE='81',
 XY='(-3225,5875)',
 ROT='0',
 VER='1',
 PACK_TYPE='0402LF',
 LOCATION='R8032',
 CDS_LIB='pure_quanta',
 CDS_PART_NAME='Q_RES_0402LF-0,5%,1/16W,CHIP,CS00002JB13',
 PART_NUMBER='CS00002JB13',
 VALUE='0',
 PRIM_FILE='./archive_libs/logical/q_res/chips/chips.prt';

PART_NAME
 R8033 'Q_RES_0402LF-1K,1%,1/16W,CHIP,CS21002FB06':;

SECTION_NUMBER 1
 '@T6G_MB_LIB.T6G(SCH_1):PAGE82_I170@PURE_QUANTA.Q_RES(CHIPS)':
 C_PATH='@t6g_mb_lib.t6g(sch_1):page82_i170@pure_quanta.q_res(chips)',
 P_PATH='@t6g_mb_lib.t6g(sch_1):page83_i170@pure_quanta.q_res(chips)',
 PATH='I170',
 DRAWING='@T6G_MB_LIB.T6G(SCH_1):PAGE82',
 WATTAGE='1/16W',
 TOLERANCE='1%',
 MATERIAL='CHIP',
 PHYS_PAGE='83',
 XY='(-4475,3275)',
 ROT='0',
 VER='2',
 PACK_TYPE='0402LF',
 LOCATION='R8033',
 CDS_LIB='pure_quanta',
 CDS_PART_NAME='Q_RES_0402LF-1K,1%,1/16W,CHIP,CS21002FB06',
 PART_NUMBER='CS21002FB06',
 VALUE='1K',
 PRIM_FILE='./archive_libs/logical/q_res/chips/chips.prt';

PART_NAME
 R8034 'Q_RES_0402LF-0,5%,1/16W,CHIP,CS00002JB13':;

SECTION_NUMBER 1
 '@T6G_MB_LIB.T6G(SCH_1):PAGE130_I23@PURE_QUANTA.Q_RES(CHIPS)':
 C_PATH='@t6g_mb_lib.t6g(sch_1):page130_i23@pure_quanta.q_res(chips)',
 P_PATH='@t6g_mb_lib.t6g(sch_1):page153_i23@pure_quanta.q_res(chips)',
 PATH='I23',
 DRAWING='@T6G_MB_LIB.T6G(SCH_1):PAGE130',
 SEC_TYPE='0402LF',
 WATTAGE='1/16W',
 TOLERANCE='5%',
 MATERIAL='CHIP',
 PHYS_PAGE='153',
 XY='(-3475,5075)',
 ROT='0',
 VER='1',
 PACK_TYPE='0402LF',
 LOCATION='R8034',
 SEC='1',
 CDS_LIB='pure_quanta',
 CDS_PART_NAME='Q_RES_0402LF-0,5%,1/16W,CHIP,CS00002JB13',
 PART_NUMBER='CS00002JB13',
 VALUE='0',
 PRIM_FILE='./archive_libs/logical/q_res/chips/chips.prt';

PART_NAME
 R8035 'Q_RES_0402LF-4.7K,5%,1/16W,EMPTY,CS24702JB10':;

SECTION_NUMBER 1
 '@T6G_MB_LIB.T6G(SCH_1):PAGE130_I11@PURE_QUANTA.Q_RES(CHIPS)':
 C_PATH='@t6g_mb_lib.t6g(sch_1):page130_i11@pure_quanta.q_res(chips)',
 P_PATH='@t6g_mb_lib.t6g(sch_1):page153_i11@pure_quanta.q_res(chips)',
 PATH='I11',
 DRAWING='@T6G_MB_LIB.T6G(SCH_1):PAGE130',
 WATTAGE='1/16W',
 TOLERANCE='5%',
 MATERIAL='EMPTY',
 PHYS_PAGE='153',
 XY='(-2750,6050)',
 ROT='0',
 VER='2',
 PACK_TYPE='0402LF',
 LOCATION='R8035',
 CDS_LIB='pure_quanta',
 CDS_PART_NAME='Q_RES_0402LF-4.7K,5%,1/16W,EMPTY,CS24702JB10',
 PART_NUMBER='CS24702JB10',
 VALUE='4.7K',
 PRIM_FILE='./archive_libs/logical/q_res/chips/chips.prt';

PART_NAME
 R8036 'Q_RES_0402LF-4.7K,5%,1/16W,EMPTY,CS24702JB10':;

SECTION_NUMBER 1
 '@T6G_MB_LIB.T6G(SCH_1):PAGE130_I12@PURE_QUANTA.Q_RES(CHIPS)':
 C_PATH='@t6g_mb_lib.t6g(sch_1):page130_i12@pure_quanta.q_res(chips)',
 P_PATH='@t6g_mb_lib.t6g(sch_1):page153_i12@pure_quanta.q_res(chips)',
 PATH='I12',
 DRAWING='@T6G_MB_LIB.T6G(SCH_1):PAGE130',
 WATTAGE='1/16W',
 TOLERANCE='5%',
 MATERIAL='EMPTY',
 PHYS_PAGE='153',
 XY='(-2350,6050)',
 ROT='0',
 VER='2',
 PACK_TYPE='0402LF',
 LOCATION='R8036',
 CDS_LIB='pure_quanta',
 CDS_PART_NAME='Q_RES_0402LF-4.7K,5%,1/16W,EMPTY,CS24702JB10',
 PART_NUMBER='CS24702JB10',
 VALUE='4.7K',
 PRIM_FILE='./archive_libs/logical/q_res/chips/chips.prt';

PART_NAME
 R8037 'Q_RES_0402LF-10K,1%,1/16W,CHIP,CS31002FB08':;

SECTION_NUMBER 1
 '@T6G_MB_LIB.T6G(SCH_1):PAGE85_I540@PURE_QUANTA.Q_RES(CHIPS)':
 C_PATH='@t6g_mb_lib.t6g(sch_1):page85_i540@pure_quanta.q_res(chips)',
 P_PATH='@t6g_mb_lib.t6g(sch_1):page86_i540@pure_quanta.q_res(chips)',
 PATH='I540',
 DRAWING='@T6G_MB_LIB.T6G(SCH_1):PAGE85',
 WATTAGE='1/16W',
 TOLERANCE='1%',
 MATERIAL='CHIP',
 PHYS_PAGE='86',
 XY='(-8750,1375)',
 ROT='0',
 VER='2',
 PACK_TYPE='0402LF',
 LOCATION='R8037',
 CDS_LIB='pure_quanta',
 CDS_PART_NAME='Q_RES_0402LF-10K,1%,1/16W,CHIP,CS31002FB08',
 PART_NUMBER='CS31002FB08',
 VALUE='10K',
 PRIM_FILE='./archive_libs/logical/q_res/chips/chips.prt';

PART_NAME
 R8038 'Q_RES_0402LF-10K,1%,1/16W,CHIP,CS31002FB08':;

SECTION_NUMBER 1
 '@T6G_MB_LIB.T6G(SCH_1):PAGE91_I243@PURE_QUANTA.Q_RES(CHIPS)':
 C_PATH='@t6g_mb_lib.t6g(sch_1):page91_i243@pure_quanta.q_res(chips)',
 P_PATH='@t6g_mb_lib.t6g(sch_1):page92_i243@pure_quanta.q_res(chips)',
 PATH='I243',
 DRAWING='@T6G_MB_LIB.T6G(SCH_1):PAGE91',
 WATTAGE='1/16W',
 TOLERANCE='1%',
 MATERIAL='CHIP',
 PHYS_PAGE='92',
 XY='(-8750,1300)',
 ROT='0',
 VER='2',
 PACK_TYPE='0402LF',
 LOCATION='R8038',
 CDS_LIB='pure_quanta',
 CDS_PART_NAME='Q_RES_0402LF-10K,1%,1/16W,CHIP,CS31002FB08',
 PART_NUMBER='CS31002FB08',
 VALUE='10K',
 PRIM_FILE='./archive_libs/logical/q_res/chips/chips.prt';

PART_NAME
 R8039 'Q_RES_0402LF-10K,1%,1/16W,CHIP,CS31002FB08':;

SECTION_NUMBER 1
 '@T6G_MB_LIB.T6G(SCH_1):PAGE97_I245@PURE_QUANTA.Q_RES(CHIPS)':
 C_PATH='@t6g_mb_lib.t6g(sch_1):page97_i245@pure_quanta.q_res(chips)',
 P_PATH='@t6g_mb_lib.t6g(sch_1):page98_i245@pure_quanta.q_res(chips)',
 PATH='I245',
 DRAWING='@T6G_MB_LIB.T6G(SCH_1):PAGE97',
 WATTAGE='1/16W',
 TOLERANCE='1%',
 MATERIAL='CHIP',
 PHYS_PAGE='98',
 XY='(-8950,1450)',
 ROT='0',
 VER='2',
 PACK_TYPE='0402LF',
 LOCATION='R8039',
 CDS_LIB='pure_quanta',
 CDS_PART_NAME='Q_RES_0402LF-10K,1%,1/16W,CHIP,CS31002FB08',
 PART_NUMBER='CS31002FB08',
 VALUE='10K',
 PRIM_FILE='./archive_libs/logical/q_res/chips/chips.prt';

PART_NAME
 R8040 'Q_RES_0402LF-10K,1%,1/16W,CHIP,CS31002FB08':;

SECTION_NUMBER 1
 '@T6G_MB_LIB.T6G(SCH_1):PAGE103_I245@PURE_QUANTA.Q_RES(CHIPS)':
 C_PATH='@t6g_mb_lib.t6g(sch_1):page103_i245@pure_quanta.q_res(chips)',
 P_PATH='@t6g_mb_lib.t6g(sch_1):page104_i245@pure_quanta.q_res(chips)',
 PATH='I245',
 DRAWING='@T6G_MB_LIB.T6G(SCH_1):PAGE103',
 WATTAGE='1/16W',
 TOLERANCE='1%',
 MATERIAL='CHIP',
 PHYS_PAGE='104',
 XY='(-8975,1375)',
 ROT='0',
 VER='2',
 PACK_TYPE='0402LF',
 LOCATION='R8040',
 CDS_LIB='pure_quanta',
 CDS_PART_NAME='Q_RES_0402LF-10K,1%,1/16W,CHIP,CS31002FB08',
 PART_NUMBER='CS31002FB08',
 VALUE='10K',
 PRIM_FILE='./archive_libs/logical/q_res/chips/chips.prt';

PART_NAME
 R8042 'Q_RES_0402LF-1K,1%,1/16W,EMPTY,CS21002FB06':;

SECTION_NUMBER 1
 '@T6G_MB_LIB.T6G(SCH_1):PAGE175_I32@PURE_QUANTA.Q_RES(CHIPS)':
 C_PATH='@t6g_mb_lib.t6g(sch_1):page175_i32@pure_quanta.q_res(chips)',
 P_PATH='@t6g_mb_lib.t6g(sch_1):page200_i32@pure_quanta.q_res(chips)',
 PATH='I32',
 DRAWING='@T6G_MB_LIB.T6G(SCH_1):PAGE175',
 WATTAGE='1/16W',
 TOLERANCE='1%',
 MATERIAL='EMPTY',
 PHYS_PAGE='200',
 XY='(-8425,5200)',
 ROT='0',
 VER='2',
 PACK_TYPE='0402LF',
 LOCATION='R8042',
 CDS_LIB='pure_quanta',
 CDS_PART_NAME='Q_RES_0402LF-1K,1%,1/16W,EMPTY,CS21002FB06',
 PART_NUMBER='CS21002FB06',
 VALUE='1K',
 PRIM_FILE='./archive_libs/logical/q_res/chips/chips.prt';

PART_NAME
 R8043 'Q_RES_0402LF-1K,1%,1/16W,EMPTY,CS21002FB06':;

SECTION_NUMBER 1
 '@T6G_MB_LIB.T6G(SCH_1):PAGE175_I42@PURE_QUANTA.Q_RES(CHIPS)':
 C_PATH='@t6g_mb_lib.t6g(sch_1):page175_i42@pure_quanta.q_res(chips)',
 P_PATH='@t6g_mb_lib.t6g(sch_1):page200_i42@pure_quanta.q_res(chips)',
 PATH='I42',
 DRAWING='@T6G_MB_LIB.T6G(SCH_1):PAGE175',
 WATTAGE='1/16W',
 TOLERANCE='1%',
 MATERIAL='EMPTY',
 PHYS_PAGE='200',
 XY='(-8200,6175)',
 ROT='0',
 VER='2',
 PACK_TYPE='0402LF',
 LOCATION='R8043',
 CDS_LIB='pure_quanta',
 CDS_PART_NAME='Q_RES_0402LF-1K,1%,1/16W,EMPTY,CS21002FB06',
 PART_NUMBER='CS21002FB06',
 VALUE='1K',
 PRIM_FILE='./archive_libs/logical/q_res/chips/chips.prt';

PART_NAME
 R8045 'Q_RES_0402LF-1K,1%,1/16W,EMPTY,CS21002FB06':;

SECTION_NUMBER 1
 '@T6G_MB_LIB.T6G(SCH_1):PAGE175_I43@PURE_QUANTA.Q_RES(CHIPS)':
 C_PATH='@t6g_mb_lib.t6g(sch_1):page175_i43@pure_quanta.q_res(chips)',
 P_PATH='@t6g_mb_lib.t6g(sch_1):page200_i43@pure_quanta.q_res(chips)',
 PATH='I43',
 DRAWING='@T6G_MB_LIB.T6G(SCH_1):PAGE175',
 WATTAGE='1/16W',
 TOLERANCE='1%',
 MATERIAL='EMPTY',
 PHYS_PAGE='200',
 XY='(-8000,6175)',
 ROT='0',
 VER='2',
 PACK_TYPE='0402LF',
 LOCATION='R8045',
 CDS_LIB='pure_quanta',
 CDS_PART_NAME='Q_RES_0402LF-1K,1%,1/16W,EMPTY,CS21002FB06',
 PART_NUMBER='CS21002FB06',
 VALUE='1K',
 PRIM_FILE='./archive_libs/logical/q_res/chips/chips.prt';

PART_NAME
 R8047 'Q_RES_0402LF-0,5%,1/16W,CHIP,CS00002JB13':;

SECTION_NUMBER 1
 '@T6G_MB_LIB.T6G(SCH_1):PAGE175_I2@PURE_QUANTA.Q_RES(CHIPS)':
 C_PATH='@t6g_mb_lib.t6g(sch_1):page175_i2@pure_quanta.q_res(chips)',
 P_PATH='@t6g_mb_lib.t6g(sch_1):page200_i2@pure_quanta.q_res(chips)',
 PATH='I2',
 DRAWING='@T6G_MB_LIB.T6G(SCH_1):PAGE175',
 WATTAGE='1/16W',
 TOLERANCE='5%',
 MATERIAL='CHIP',
 PHYS_PAGE='200',
 XY='(-8350,1650)',
 ROT='0',
 VER='1',
 PACK_TYPE='0402LF',
 LOCATION='R8047',
 CDS_LIB='pure_quanta',
 CDS_PART_NAME='Q_RES_0402LF-0,5%,1/16W,CHIP,CS00002JB13',
 PART_NUMBER='CS00002JB13',
 VALUE='0',
 PRIM_FILE='./archive_libs/logical/q_res/chips/chips.prt';

PART_NAME
 R8048 'Q_RES_0402LF-1K,1%,1/16W,EMPTY,CS21002FB06':;

SECTION_NUMBER 1
 '@T6G_MB_LIB.T6G(SCH_1):PAGE175_I44@PURE_QUANTA.Q_RES(CHIPS)':
 C_PATH='@t6g_mb_lib.t6g(sch_1):page175_i44@pure_quanta.q_res(chips)',
 P_PATH='@t6g_mb_lib.t6g(sch_1):page200_i44@pure_quanta.q_res(chips)',
 PATH='I44',
 DRAWING='@T6G_MB_LIB.T6G(SCH_1):PAGE175',
 WATTAGE='1/16W',
 TOLERANCE='1%',
 MATERIAL='EMPTY',
 PHYS_PAGE='200',
 XY='(-7750,6175)',
 ROT='0',
 VER='2',
 PACK_TYPE='0402LF',
 LOCATION='R8048',
 CDS_LIB='pure_quanta',
 CDS_PART_NAME='Q_RES_0402LF-1K,1%,1/16W,EMPTY,CS21002FB06',
 PART_NUMBER='CS21002FB06',
 VALUE='1K',
 PRIM_FILE='./archive_libs/logical/q_res/chips/chips.prt';

PART_NAME
 R8056 'Q_RES_0402LF-1K,1%,1/16W,CHIP,CS21002FB06':;

SECTION_NUMBER 1
 '@T6G_MB_LIB.T6G(SCH_1):PAGE175_I90@PURE_QUANTA.Q_RES(CHIPS)':
 C_PATH='@t6g_mb_lib.t6g(sch_1):page175_i90@pure_quanta.q_res(chips)',
 P_PATH='@t6g_mb_lib.t6g(sch_1):page200_i90@pure_quanta.q_res(chips)',
 PATH='I90',
 DRAWING='@T6G_MB_LIB.T6G(SCH_1):PAGE175',
 WATTAGE='1/16W',
 TOLERANCE='1%',
 MATERIAL='CHIP',
 PHYS_PAGE='200',
 XY='(-6475,6450)',
 ROT='0',
 VER='1',
 PACK_TYPE='0402LF',
 LOCATION='R8056',
 CDS_LIB='pure_quanta',
 CDS_PART_NAME='Q_RES_0402LF-1K,1%,1/16W,CHIP,CS21002FB06',
 PART_NUMBER='CS21002FB06',
 VALUE='1K',
 PRIM_FILE='./archive_libs/logical/q_res/chips/chips.prt';

PART_NAME
 R8057 'Q_RES_0402LF-33,5%,1/16W,CHIP,CS03302JB10':;

SECTION_NUMBER 1
 '@T6G_MB_LIB.T6G(SCH_1):PAGE175_I89@PURE_QUANTA.Q_RES(CHIPS)':
 C_PATH='@t6g_mb_lib.t6g(sch_1):page175_i89@pure_quanta.q_res(chips)',
 P_PATH='@t6g_mb_lib.t6g(sch_1):page200_i89@pure_quanta.q_res(chips)',
 PATH='I89',
 DRAWING='@T6G_MB_LIB.T6G(SCH_1):PAGE175',
 WATTAGE='1/16W',
 TOLERANCE='5%',
 MATERIAL='CHIP',
 PHYS_PAGE='200',
 XY='(-6475,6300)',
 ROT='0',
 VER='1',
 PACK_TYPE='0402LF',
 LOCATION='R8057',
 CDS_LIB='pure_quanta',
 CDS_PART_NAME='Q_RES_0402LF-33,5%,1/16W,CHIP,CS03302JB10',
 PART_NUMBER='CS03302JB10',
 VALUE='33',
 PRIM_FILE='./archive_libs/logical/q_res/chips/chips.prt';

PART_NAME
 R8058 'Q_RES_0402LF-0,5%,1/16W,CHIP,CS00002JB13':;

SECTION_NUMBER 1
 '@T6G_MB_LIB.T6G(SCH_1):PAGE175_I88@PURE_QUANTA.Q_RES(CHIPS)':
 C_PATH='@t6g_mb_lib.t6g(sch_1):page175_i88@pure_quanta.q_res(chips)',
 P_PATH='@t6g_mb_lib.t6g(sch_1):page200_i88@pure_quanta.q_res(chips)',
 PATH='I88',
 DRAWING='@T6G_MB_LIB.T6G(SCH_1):PAGE175',
 WATTAGE='1/16W',
 TOLERANCE='5%',
 MATERIAL='CHIP',
 PHYS_PAGE='200',
 XY='(-6475,6150)',
 ROT='0',
 VER='1',
 PACK_TYPE='0402LF',
 LOCATION='R8058',
 CDS_LIB='pure_quanta',
 CDS_PART_NAME='Q_RES_0402LF-0,5%,1/16W,CHIP,CS00002JB13',
 PART_NUMBER='CS00002JB13',
 VALUE='0',
 PRIM_FILE='./archive_libs/logical/q_res/chips/chips.prt';

PART_NAME
 R8063 'Q_RES_0402LF-100,1%,1/16W,CHIP,CS11002FB07':;

SECTION_NUMBER 1
 '@T6G_MB_LIB.T6G(SCH_1):PAGE175_I67@PURE_QUANTA.Q_RES(CHIPS)':
 C_PATH='@t6g_mb_lib.t6g(sch_1):page175_i67@pure_quanta.q_res(chips)',
 P_PATH='@t6g_mb_lib.t6g(sch_1):page200_i67@pure_quanta.q_res(chips)',
 PATH='I67',
 DRAWING='@T6G_MB_LIB.T6G(SCH_1):PAGE175',
 WATTAGE='1/16W',
 TOLERANCE='1%',
 MATERIAL='CHIP',
 PHYS_PAGE='200',
 XY='(-5725,2450)',
 ROT='0',
 VER='1',
 PACK_TYPE='0402LF',
 LOCATION='R8063',
 CDS_LIB='pure_quanta',
 CDS_PART_NAME='Q_RES_0402LF-100,1%,1/16W,CHIP,CS11002FB07',
 PART_NUMBER='CS11002FB07',
 VALUE='100',
 PRIM_FILE='./archive_libs/logical/q_res/chips/chips.prt';

PART_NAME
 R8064 'Q_RES_0402LF-0,5%,1/16W,CHIP,CS00002JB13':;

SECTION_NUMBER 1
 '@T6G_MB_LIB.T6G(SCH_1):PAGE175_I66@PURE_QUANTA.Q_RES(CHIPS)':
 C_PATH='@t6g_mb_lib.t6g(sch_1):page175_i66@pure_quanta.q_res(chips)',
 P_PATH='@t6g_mb_lib.t6g(sch_1):page200_i66@pure_quanta.q_res(chips)',
 PATH='I66',
 DRAWING='@T6G_MB_LIB.T6G(SCH_1):PAGE175',
 WATTAGE='1/16W',
 TOLERANCE='5%',
 MATERIAL='CHIP',
 PHYS_PAGE='200',
 XY='(-5725,2300)',
 ROT='0',
 VER='1',
 PACK_TYPE='0402LF',
 LOCATION='R8064',
 CDS_LIB='pure_quanta',
 CDS_PART_NAME='Q_RES_0402LF-0,5%,1/16W,CHIP,CS00002JB13',
 PART_NUMBER='CS00002JB13',
 VALUE='0',
 PRIM_FILE='./archive_libs/logical/q_res/chips/chips.prt';

PART_NAME
 R8065 'Q_RES_0402LF-1K,1%,1/16W,CHIP,CS21002FB06':;

SECTION_NUMBER 1
 '@T6G_MB_LIB.T6G(SCH_1):PAGE175_I54@PURE_QUANTA.Q_RES(CHIPS)':
 C_PATH='@t6g_mb_lib.t6g(sch_1):page175_i54@pure_quanta.q_res(chips)',
 P_PATH='@t6g_mb_lib.t6g(sch_1):page200_i54@pure_quanta.q_res(chips)',
 PATH='I54',
 DRAWING='@T6G_MB_LIB.T6G(SCH_1):PAGE175',
 WATTAGE='1/16W',
 TOLERANCE='1%',
 MATERIAL='CHIP',
 PHYS_PAGE='200',
 XY='(-6375,1200)',
 ROT='0',
 VER='1',
 PACK_TYPE='0402LF',
 LOCATION='R8065',
 CDS_LIB='pure_quanta',
 CDS_PART_NAME='Q_RES_0402LF-1K,1%,1/16W,CHIP,CS21002FB06',
 PART_NUMBER='CS21002FB06',
 VALUE='1K',
 PRIM_FILE='./archive_libs/logical/q_res/chips/chips.prt';

PART_NAME
 R8066 'Q_RES_0402LF-33,5%,1/16W,CHIP,CS03302JB10':;

SECTION_NUMBER 1
 '@T6G_MB_LIB.T6G(SCH_1):PAGE175_I53@PURE_QUANTA.Q_RES(CHIPS)':
 C_PATH='@t6g_mb_lib.t6g(sch_1):page175_i53@pure_quanta.q_res(chips)',
 P_PATH='@t6g_mb_lib.t6g(sch_1):page200_i53@pure_quanta.q_res(chips)',
 PATH='I53',
 DRAWING='@T6G_MB_LIB.T6G(SCH_1):PAGE175',
 WATTAGE='1/16W',
 TOLERANCE='5%',
 MATERIAL='CHIP',
 PHYS_PAGE='200',
 XY='(-6375,1050)',
 ROT='0',
 VER='1',
 PACK_TYPE='0402LF',
 LOCATION='R8066',
 CDS_LIB='pure_quanta',
 CDS_PART_NAME='Q_RES_0402LF-33,5%,1/16W,CHIP,CS03302JB10',
 PART_NUMBER='CS03302JB10',
 VALUE='33',
 PRIM_FILE='./archive_libs/logical/q_res/chips/chips.prt';

PART_NAME
 R8070 'Q_RES_0402LF-1K,1%,1/16W,CHIP,CS21002FB06':;

SECTION_NUMBER 1
 '@T6G_MB_LIB.T6G(SCH_1):PAGE175_I68@PURE_QUANTA.Q_RES(CHIPS)':
 C_PATH='@t6g_mb_lib.t6g(sch_1):page175_i68@pure_quanta.q_res(chips)',
 P_PATH='@t6g_mb_lib.t6g(sch_1):page200_i68@pure_quanta.q_res(chips)',
 PATH='I68',
 DRAWING='@T6G_MB_LIB.T6G(SCH_1):PAGE175',
 WATTAGE='1/16W',
 TOLERANCE='1%',
 MATERIAL='CHIP',
 PHYS_PAGE='200',
 XY='(-5875,2600)',
 ROT='0',
 VER='1',
 PACK_TYPE='0402LF',
 LOCATION='R8070',
 CDS_LIB='pure_quanta',
 CDS_PART_NAME='Q_RES_0402LF-1K,1%,1/16W,CHIP,CS21002FB06',
 PART_NUMBER='CS21002FB06',
 VALUE='1K',
 PRIM_FILE='./archive_libs/logical/q_res/chips/chips.prt';

PART_NAME
 R8071 'Q_RES_0402LF-0,5%,1/16W,CHIP,CS00002JB13':;

SECTION_NUMBER 1
 '@T6G_MB_LIB.T6G(SCH_1):PAGE175_I85@PURE_QUANTA.Q_RES(CHIPS)':
 C_PATH='@t6g_mb_lib.t6g(sch_1):page175_i85@pure_quanta.q_res(chips)',
 P_PATH='@t6g_mb_lib.t6g(sch_1):page200_i85@pure_quanta.q_res(chips)',
 PATH='I85',
 DRAWING='@T6G_MB_LIB.T6G(SCH_1):PAGE175',
 WATTAGE='1/16W',
 TOLERANCE='5%',
 MATERIAL='CHIP',
 PHYS_PAGE='200',
 XY='(-5750,5150)',
 ROT='0',
 VER='1',
 PACK_TYPE='0402LF',
 LOCATION='R8071',
 CDS_LIB='pure_quanta',
 CDS_PART_NAME='Q_RES_0402LF-0,5%,1/16W,CHIP,CS00002JB13',
 PART_NUMBER='CS00002JB13',
 VALUE='0',
 PRIM_FILE='./archive_libs/logical/q_res/chips/chips.prt';

PART_NAME
 R8072 'Q_RES_0402LF-0,5%,1/16W,CHIP,CS00002JB13':;

SECTION_NUMBER 1
 '@T6G_MB_LIB.T6G(SCH_1):PAGE175_I82@PURE_QUANTA.Q_RES(CHIPS)':
 C_PATH='@t6g_mb_lib.t6g(sch_1):page175_i82@pure_quanta.q_res(chips)',
 P_PATH='@t6g_mb_lib.t6g(sch_1):page200_i82@pure_quanta.q_res(chips)',
 PATH='I82',
 DRAWING='@T6G_MB_LIB.T6G(SCH_1):PAGE175',
 WATTAGE='1/16W',
 TOLERANCE='5%',
 MATERIAL='CHIP',
 PHYS_PAGE='200',
 XY='(-5750,5000)',
 ROT='0',
 VER='1',
 PACK_TYPE='0402LF',
 LOCATION='R8072',
 CDS_LIB='pure_quanta',
 CDS_PART_NAME='Q_RES_0402LF-0,5%,1/16W,CHIP,CS00002JB13',
 PART_NUMBER='CS00002JB13',
 VALUE='0',
 PRIM_FILE='./archive_libs/logical/q_res/chips/chips.prt';

PART_NAME
 R8073 'Q_RES_0402LF-33,5%,1/16W,CHIP,CS03302JB10':;

SECTION_NUMBER 1
 '@T6G_MB_LIB.T6G(SCH_1):PAGE175_I81@PURE_QUANTA.Q_RES(CHIPS)':
 C_PATH='@t6g_mb_lib.t6g(sch_1):page175_i81@pure_quanta.q_res(chips)',
 P_PATH='@t6g_mb_lib.t6g(sch_1):page200_i81@pure_quanta.q_res(chips)',
 PATH='I81',
 DRAWING='@T6G_MB_LIB.T6G(SCH_1):PAGE175',
 WATTAGE='1/16W',
 TOLERANCE='5%',
 MATERIAL='CHIP',
 PHYS_PAGE='200',
 XY='(-5750,4850)',
 ROT='0',
 VER='1',
 PACK_TYPE='0402LF',
 LOCATION='R8073',
 CDS_LIB='pure_quanta',
 CDS_PART_NAME='Q_RES_0402LF-33,5%,1/16W,CHIP,CS03302JB10',
 PART_NUMBER='CS03302JB10',
 VALUE='33',
 PRIM_FILE='./archive_libs/logical/q_res/chips/chips.prt';

PART_NAME
 R8075 'Q_RES_0402LF-1K,1%,1/16W,CHIP,CS21002FB06':;

SECTION_NUMBER 1
 '@T6G_MB_LIB.T6G(SCH_1):PAGE175_I71@PURE_QUANTA.Q_RES(CHIPS)':
 C_PATH='@t6g_mb_lib.t6g(sch_1):page175_i71@pure_quanta.q_res(chips)',
 P_PATH='@t6g_mb_lib.t6g(sch_1):page200_i71@pure_quanta.q_res(chips)',
 PATH='I71',
 DRAWING='@T6G_MB_LIB.T6G(SCH_1):PAGE175',
 WATTAGE='1/16W',
 TOLERANCE='1%',
 MATERIAL='CHIP',
 PHYS_PAGE='200',
 XY='(-5175,2175)',
 ROT='0',
 VER='1',
 PACK_TYPE='0402LF',
 LOCATION='R8075',
 CDS_LIB='pure_quanta',
 CDS_PART_NAME='Q_RES_0402LF-1K,1%,1/16W,CHIP,CS21002FB06',
 PART_NUMBER='CS21002FB06',
 VALUE='1K',
 PRIM_FILE='./archive_libs/logical/q_res/chips/chips.prt';

PART_NAME
 R8080 'Q_RES_0402LF-0,5%,1/16W,CHIP,CS00002JB13':;

SECTION_NUMBER 1
 '@T6G_MB_LIB.T6G(SCH_1):PAGE85_I544@PURE_QUANTA.Q_RES(CHIPS)':
 C_PATH='@t6g_mb_lib.t6g(sch_1):page85_i544@pure_quanta.q_res(chips)',
 P_PATH='@t6g_mb_lib.t6g(sch_1):page86_i544@pure_quanta.q_res(chips)',
 PATH='I544',
 DRAWING='@T6G_MB_LIB.T6G(SCH_1):PAGE85',
 WATTAGE='1/16W',
 TOLERANCE='5%',
 MATERIAL='CHIP',
 PHYS_PAGE='86',
 XY='(-4525,900)',
 ROT='0',
 VER='1',
 PACK_TYPE='0402LF',
 LOCATION='R8080',
 CDS_LIB='pure_quanta',
 CDS_PART_NAME='Q_RES_0402LF-0,5%,1/16W,CHIP,CS00002JB13',
 PART_NUMBER='CS00002JB13',
 VALUE='0',
 PRIM_FILE='./archive_libs/logical/q_res/chips/chips.prt';

PART_NAME
 R8081 'Q_RES_0402LF-0,5%,1/16W,CHIP,CS00002JB13':;

SECTION_NUMBER 1
 '@T6G_MB_LIB.T6G(SCH_1):PAGE85_I545@PURE_QUANTA.Q_RES(CHIPS)':
 C_PATH='@t6g_mb_lib.t6g(sch_1):page85_i545@pure_quanta.q_res(chips)',
 P_PATH='@t6g_mb_lib.t6g(sch_1):page86_i545@pure_quanta.q_res(chips)',
 PATH='I545',
 DRAWING='@T6G_MB_LIB.T6G(SCH_1):PAGE85',
 WATTAGE='1/16W',
 TOLERANCE='5%',
 MATERIAL='CHIP',
 PHYS_PAGE='86',
 XY='(-3100,900)',
 ROT='0',
 VER='1',
 PACK_TYPE='0402LF',
 LOCATION='R8081',
 CDS_LIB='pure_quanta',
 CDS_PART_NAME='Q_RES_0402LF-0,5%,1/16W,CHIP,CS00002JB13',
 PART_NUMBER='CS00002JB13',
 VALUE='0',
 PRIM_FILE='./archive_libs/logical/q_res/chips/chips.prt';

PART_NAME
 R8082 'Q_RES_0402LF-10K,1%,1/16W,EMPTY,CS31002FB08':;

SECTION_NUMBER 1
 '@T6G_MB_LIB.T6G(SCH_1):PAGE85_I547@PURE_QUANTA.Q_RES(CHIPS)':
 C_PATH='@t6g_mb_lib.t6g(sch_1):page85_i547@pure_quanta.q_res(chips)',
 P_PATH='@t6g_mb_lib.t6g(sch_1):page86_i547@pure_quanta.q_res(chips)',
 PATH='I547',
 DRAWING='@T6G_MB_LIB.T6G(SCH_1):PAGE85',
 WATTAGE='1/16W',
 TOLERANCE='1%',
 MATERIAL='EMPTY',
 PHYS_PAGE='86',
 XY='(-4950,1375)',
 ROT='0',
 VER='1',
 PACK_TYPE='0402LF',
 LOCATION='R8082',
 CDS_LIB='pure_quanta',
 CDS_PART_NAME='Q_RES_0402LF-10K,1%,1/16W,EMPTY,CS31002FB08',
 PART_NUMBER='CS31002FB08',
 VALUE='10K',
 PRIM_FILE='./archive_libs/logical/q_res/chips/chips.prt';

PART_NAME
 R8083 'Q_RES_0402LF-0,5%,1/16W,CHIP,CS00002JB13':;

SECTION_NUMBER 1
 '@T6G_MB_LIB.T6G(SCH_1):PAGE91_I248@PURE_QUANTA.Q_RES(CHIPS)':
 C_PATH='@t6g_mb_lib.t6g(sch_1):page91_i248@pure_quanta.q_res(chips)',
 P_PATH='@t6g_mb_lib.t6g(sch_1):page92_i248@pure_quanta.q_res(chips)',
 PATH='I248',
 DRAWING='@T6G_MB_LIB.T6G(SCH_1):PAGE91',
 WATTAGE='1/16W',
 TOLERANCE='5%',
 MATERIAL='CHIP',
 PHYS_PAGE='92',
 XY='(-3350,775)',
 ROT='0',
 VER='1',
 PACK_TYPE='0402LF',
 LOCATION='R8083',
 CDS_LIB='pure_quanta',
 CDS_PART_NAME='Q_RES_0402LF-0,5%,1/16W,CHIP,CS00002JB13',
 PART_NUMBER='CS00002JB13',
 VALUE='0',
 PRIM_FILE='./archive_libs/logical/q_res/chips/chips.prt';

PART_NAME
 R8084 'Q_RES_0402LF-0,5%,1/16W,CHIP,CS00002JB13':;

SECTION_NUMBER 1
 '@T6G_MB_LIB.T6G(SCH_1):PAGE91_I250@PURE_QUANTA.Q_RES(CHIPS)':
 C_PATH='@t6g_mb_lib.t6g(sch_1):page91_i250@pure_quanta.q_res(chips)',
 P_PATH='@t6g_mb_lib.t6g(sch_1):page92_i250@pure_quanta.q_res(chips)',
 PATH='I250',
 DRAWING='@T6G_MB_LIB.T6G(SCH_1):PAGE91',
 WATTAGE='1/16W',
 TOLERANCE='5%',
 MATERIAL='CHIP',
 PHYS_PAGE='92',
 XY='(-1925,775)',
 ROT='0',
 VER='1',
 PACK_TYPE='0402LF',
 LOCATION='R8084',
 CDS_LIB='pure_quanta',
 CDS_PART_NAME='Q_RES_0402LF-0,5%,1/16W,CHIP,CS00002JB13',
 PART_NUMBER='CS00002JB13',
 VALUE='0',
 PRIM_FILE='./archive_libs/logical/q_res/chips/chips.prt';

PART_NAME
 R8085 'Q_RES_0402LF-10K,1%,1/16W,EMPTY,CS31002FB08':;

SECTION_NUMBER 1
 '@T6G_MB_LIB.T6G(SCH_1):PAGE91_I249@PURE_QUANTA.Q_RES(CHIPS)':
 C_PATH='@t6g_mb_lib.t6g(sch_1):page91_i249@pure_quanta.q_res(chips)',
 P_PATH='@t6g_mb_lib.t6g(sch_1):page92_i249@pure_quanta.q_res(chips)',
 PATH='I249',
 DRAWING='@T6G_MB_LIB.T6G(SCH_1):PAGE91',
 WATTAGE='1/16W',
 TOLERANCE='1%',
 MATERIAL='EMPTY',
 PHYS_PAGE='92',
 XY='(-3775,1250)',
 ROT='0',
 VER='1',
 PACK_TYPE='0402LF',
 LOCATION='R8085',
 CDS_LIB='pure_quanta',
 CDS_PART_NAME='Q_RES_0402LF-10K,1%,1/16W,EMPTY,CS31002FB08',
 PART_NUMBER='CS31002FB08',
 VALUE='10K',
 PRIM_FILE='./archive_libs/logical/q_res/chips/chips.prt';

PART_NAME
 R8086 'Q_RES_0402LF-0,5%,1/16W,CHIP,CS00002JB13':;

SECTION_NUMBER 1
 '@T6G_MB_LIB.T6G(SCH_1):PAGE97_I250@PURE_QUANTA.Q_RES(CHIPS)':
 C_PATH='@t6g_mb_lib.t6g(sch_1):page97_i250@pure_quanta.q_res(chips)',
 P_PATH='@t6g_mb_lib.t6g(sch_1):page98_i250@pure_quanta.q_res(chips)',
 PATH='I250',
 DRAWING='@T6G_MB_LIB.T6G(SCH_1):PAGE97',
 WATTAGE='1/16W',
 TOLERANCE='5%',
 MATERIAL='CHIP',
 PHYS_PAGE='98',
 XY='(-4000,925)',
 ROT='0',
 VER='1',
 PACK_TYPE='0402LF',
 LOCATION='R8086',
 CDS_LIB='pure_quanta',
 CDS_PART_NAME='Q_RES_0402LF-0,5%,1/16W,CHIP,CS00002JB13',
 PART_NUMBER='CS00002JB13',
 VALUE='0',
 PRIM_FILE='./archive_libs/logical/q_res/chips/chips.prt';

PART_NAME
 R8087 'Q_RES_0402LF-0,5%,1/16W,CHIP,CS00002JB13':;

SECTION_NUMBER 1
 '@T6G_MB_LIB.T6G(SCH_1):PAGE97_I252@PURE_QUANTA.Q_RES(CHIPS)':
 C_PATH='@t6g_mb_lib.t6g(sch_1):page97_i252@pure_quanta.q_res(chips)',
 P_PATH='@t6g_mb_lib.t6g(sch_1):page98_i252@pure_quanta.q_res(chips)',
 PATH='I252',
 DRAWING='@T6G_MB_LIB.T6G(SCH_1):PAGE97',
 WATTAGE='1/16W',
 TOLERANCE='5%',
 MATERIAL='CHIP',
 PHYS_PAGE='98',
 XY='(-2575,925)',
 ROT='0',
 VER='1',
 PACK_TYPE='0402LF',
 LOCATION='R8087',
 CDS_LIB='pure_quanta',
 CDS_PART_NAME='Q_RES_0402LF-0,5%,1/16W,CHIP,CS00002JB13',
 PART_NUMBER='CS00002JB13',
 VALUE='0',
 PRIM_FILE='./archive_libs/logical/q_res/chips/chips.prt';

PART_NAME
 R8088 'Q_RES_0402LF-10K,1%,1/16W,EMPTY,CS31002FB08':;

SECTION_NUMBER 1
 '@T6G_MB_LIB.T6G(SCH_1):PAGE97_I251@PURE_QUANTA.Q_RES(CHIPS)':
 C_PATH='@t6g_mb_lib.t6g(sch_1):page97_i251@pure_quanta.q_res(chips)',
 P_PATH='@t6g_mb_lib.t6g(sch_1):page98_i251@pure_quanta.q_res(chips)',
 PATH='I251',
 DRAWING='@T6G_MB_LIB.T6G(SCH_1):PAGE97',
 WATTAGE='1/16W',
 TOLERANCE='1%',
 MATERIAL='EMPTY',
 PHYS_PAGE='98',
 XY='(-4425,1400)',
 ROT='0',
 VER='1',
 PACK_TYPE='0402LF',
 LOCATION='R8088',
 CDS_LIB='pure_quanta',
 CDS_PART_NAME='Q_RES_0402LF-10K,1%,1/16W,EMPTY,CS31002FB08',
 PART_NUMBER='CS31002FB08',
 VALUE='10K',
 PRIM_FILE='./archive_libs/logical/q_res/chips/chips.prt';

PART_NAME
 R8089 'Q_RES_0402LF-0,5%,1/16W,CHIP,CS00002JB13':;

SECTION_NUMBER 1
 '@T6G_MB_LIB.T6G(SCH_1):PAGE103_I249@PURE_QUANTA.Q_RES(CHIPS)':
 C_PATH='@t6g_mb_lib.t6g(sch_1):page103_i249@pure_quanta.q_res(chips)',
 P_PATH='@t6g_mb_lib.t6g(sch_1):page104_i249@pure_quanta.q_res(chips)',
 PATH='I249',
 DRAWING='@T6G_MB_LIB.T6G(SCH_1):PAGE103',
 WATTAGE='1/16W',
 TOLERANCE='5%',
 MATERIAL='CHIP',
 PHYS_PAGE='104',
 XY='(-3850,750)',
 ROT='0',
 VER='1',
 PACK_TYPE='0402LF',
 LOCATION='R8089',
 CDS_LIB='pure_quanta',
 CDS_PART_NAME='Q_RES_0402LF-0,5%,1/16W,CHIP,CS00002JB13',
 PART_NUMBER='CS00002JB13',
 VALUE='0',
 PRIM_FILE='./archive_libs/logical/q_res/chips/chips.prt';

PART_NAME
 R8090 'Q_RES_0402LF-0,5%,1/16W,CHIP,CS00002JB13':;

SECTION_NUMBER 1
 '@T6G_MB_LIB.T6G(SCH_1):PAGE103_I252@PURE_QUANTA.Q_RES(CHIPS)':
 C_PATH='@t6g_mb_lib.t6g(sch_1):page103_i252@pure_quanta.q_res(chips)',
 P_PATH='@t6g_mb_lib.t6g(sch_1):page104_i252@pure_quanta.q_res(chips)',
 PATH='I252',
 DRAWING='@T6G_MB_LIB.T6G(SCH_1):PAGE103',
 WATTAGE='1/16W',
 TOLERANCE='5%',
 MATERIAL='CHIP',
 PHYS_PAGE='104',
 XY='(-2425,750)',
 ROT='0',
 VER='1',
 PACK_TYPE='0402LF',
 LOCATION='R8090',
 CDS_LIB='pure_quanta',
 CDS_PART_NAME='Q_RES_0402LF-0,5%,1/16W,CHIP,CS00002JB13',
 PART_NUMBER='CS00002JB13',
 VALUE='0',
 PRIM_FILE='./archive_libs/logical/q_res/chips/chips.prt';

PART_NAME
 R8091 'Q_RES_0402LF-10K,1%,1/16W,EMPTY,CS31002FB08':;

SECTION_NUMBER 1
 '@T6G_MB_LIB.T6G(SCH_1):PAGE103_I251@PURE_QUANTA.Q_RES(CHIPS)':
 C_PATH='@t6g_mb_lib.t6g(sch_1):page103_i251@pure_quanta.q_res(chips)',
 P_PATH='@t6g_mb_lib.t6g(sch_1):page104_i251@pure_quanta.q_res(chips)',
 PATH='I251',
 DRAWING='@T6G_MB_LIB.T6G(SCH_1):PAGE103',
 WATTAGE='1/16W',
 TOLERANCE='1%',
 MATERIAL='EMPTY',
 PHYS_PAGE='104',
 XY='(-4275,1225)',
 ROT='0',
 VER='1',
 PACK_TYPE='0402LF',
 LOCATION='R8091',
 CDS_LIB='pure_quanta',
 CDS_PART_NAME='Q_RES_0402LF-10K,1%,1/16W,EMPTY,CS31002FB08',
 PART_NUMBER='CS31002FB08',
 VALUE='10K',
 PRIM_FILE='./archive_libs/logical/q_res/chips/chips.prt';

PART_NAME
 R8092 'Q_RES_0402LF-10K,5%,1/16W,EMPTY,CS31002JB08':;

SECTION_NUMBER 1
 '@T6G_MB_LIB.T6G(SCH_1):PAGE340_I90@PURE_QUANTA.Q_RES(CHIPS)':
 C_PATH='@t6g_mb_lib.t6g(sch_1):page340_i90@pure_quanta.q_res(chips)',
 P_PATH='@t6g_mb_lib.t6g(sch_1):page136_i90@pure_quanta.q_res(chips)',
 PATH='I90',
 DRAWING='@T6G_MB_LIB.T6G(SCH_1):PAGE340',
 WATTAGE='1/16W',
 TOLERANCE='5%',
 MATERIAL='EMPTY',
 PHYS_PAGE='136',
 XY='(-3175,4900)',
 ROT='2',
 VER='2',
 PACK_TYPE='0402LF',
 LOCATION='R8092',
 CDS_LIB='pure_quanta',
 CDS_PART_NAME='Q_RES_0402LF-10K,5%,1/16W,EMPTY,CS31002JB08',
 PART_NUMBER='CS31002JB08',
 VALUE='10K',
 PRIM_FILE='./archive_libs/logical/q_res/chips/chips.prt';

PART_NAME
 R8093 'Q_RES_0402LF-100K,1%,1/16W,CHIP,CS41002FB09':;

SECTION_NUMBER 1
 '@T6G_MB_LIB.T6G(SCH_1):PAGE340_I84@PURE_QUANTA.Q_RES(CHIPS)':
 C_PATH='@t6g_mb_lib.t6g(sch_1):page340_i84@pure_quanta.q_res(chips)',
 P_PATH='@t6g_mb_lib.t6g(sch_1):page136_i84@pure_quanta.q_res(chips)',
 PATH='I84',
 DRAWING='@T6G_MB_LIB.T6G(SCH_1):PAGE340',
 WATTAGE='1/16W',
 TOLERANCE='1%',
 MATERIAL='CHIP',
 PHYS_PAGE='136',
 XY='(-3175,4300)',
 ROT='0',
 VER='2',
 PACK_TYPE='0402LF',
 LOCATION='R8093',
 CDS_LIB='pure_quanta',
 CDS_PART_NAME='Q_RES_0402LF-100K,1%,1/16W,CHIP,CS41002FB09',
 PART_NUMBER='CS41002FB09',
 VALUE='100K',
 PRIM_FILE='./archive_libs/logical/q_res/chips/chips.prt';

PART_NAME
 R8094 'Q_RES_0402LF-0,5%,1/16W,CHIP,CS00002JB13':;

SECTION_NUMBER 1
 '@T6G_MB_LIB.T6G(SCH_1):PAGE340_I85@PURE_QUANTA.Q_RES(CHIPS)':
 C_PATH='@t6g_mb_lib.t6g(sch_1):page340_i85@pure_quanta.q_res(chips)',
 P_PATH='@t6g_mb_lib.t6g(sch_1):page136_i85@pure_quanta.q_res(chips)',
 PATH='I85',
 DRAWING='@T6G_MB_LIB.T6G(SCH_1):PAGE340',
 SEC_TYPE='0402LF',
 WATTAGE='1/16W',
 TOLERANCE='5%',
 MATERIAL='CHIP',
 PHYS_PAGE='136',
 XY='(-2650,4575)',
 ROT='0',
 VER='1',
 PACK_TYPE='0402LF',
 LOCATION='R8094',
 SEC='1',
 CDS_LIB='pure_quanta',
 CDS_PART_NAME='Q_RES_0402LF-0,5%,1/16W,CHIP,CS00002JB13',
 PART_NUMBER='CS00002JB13',
 VALUE='0',
 PRIM_FILE='./archive_libs/logical/q_res/chips/chips.prt';

PART_NAME
 R8095 'Q_RES_0402LF-10K,5%,1/16W,EMPTY,CS31002JB08':;

SECTION_NUMBER 1
 '@T6G_MB_LIB.T6G(SCH_1):PAGE257_I77@PURE_QUANTA.Q_RES(CHIPS)':
 C_PATH='@t6g_mb_lib.t6g(sch_1):page257_i77@pure_quanta.q_res(chips)',
 P_PATH='@t6g_mb_lib.t6g(sch_1):page142_i77@pure_quanta.q_res(chips)',
 PATH='I77',
 DRAWING='@T6G_MB_LIB.T6G(SCH_1):PAGE257',
 WATTAGE='1/16W',
 TOLERANCE='5%',
 MATERIAL='EMPTY',
 PHYS_PAGE='142',
 XY='(-3375,-950)',
 ROT='2',
 VER='2',
 PACK_TYPE='0402LF',
 LOCATION='R8095',
 CDS_LIB='pure_quanta',
 CDS_PART_NAME='Q_RES_0402LF-10K,5%,1/16W,EMPTY,CS31002JB08',
 PART_NUMBER='CS31002JB08',
 VALUE='10K',
 PRIM_FILE='./archive_libs/logical/q_res/chips/chips.prt';

PART_NAME
 R8096 'Q_RES_0402LF-100K,1%,1/16W,CHIP,CS41002FB09':;

SECTION_NUMBER 1
 '@T6G_MB_LIB.T6G(SCH_1):PAGE257_I70@PURE_QUANTA.Q_RES(CHIPS)':
 C_PATH='@t6g_mb_lib.t6g(sch_1):page257_i70@pure_quanta.q_res(chips)',
 P_PATH='@t6g_mb_lib.t6g(sch_1):page142_i70@pure_quanta.q_res(chips)',
 PATH='I70',
 DRAWING='@T6G_MB_LIB.T6G(SCH_1):PAGE257',
 WATTAGE='1/16W',
 TOLERANCE='1%',
 MATERIAL='CHIP',
 PHYS_PAGE='142',
 XY='(-3525,-1525)',
 ROT='0',
 VER='2',
 PACK_TYPE='0402LF',
 LOCATION='R8096',
 CDS_LIB='pure_quanta',
 CDS_PART_NAME='Q_RES_0402LF-100K,1%,1/16W,CHIP,CS41002FB09',
 PART_NUMBER='CS41002FB09',
 VALUE='100K',
 PRIM_FILE='./archive_libs/logical/q_res/chips/chips.prt';

PART_NAME
 R8097 'Q_RES_0402LF-0,5%,1/16W,CHIP,CS00002JB13':;

SECTION_NUMBER 1
 '@T6G_MB_LIB.T6G(SCH_1):PAGE257_I73@PURE_QUANTA.Q_RES(CHIPS)':
 C_PATH='@t6g_mb_lib.t6g(sch_1):page257_i73@pure_quanta.q_res(chips)',
 P_PATH='@t6g_mb_lib.t6g(sch_1):page142_i73@pure_quanta.q_res(chips)',
 PATH='I73',
 DRAWING='@T6G_MB_LIB.T6G(SCH_1):PAGE257',
 WATTAGE='1/16W',
 TOLERANCE='5%',
 MATERIAL='CHIP',
 PHYS_PAGE='142',
 XY='(-3050,-1250)',
 ROT='0',
 VER='1',
 PACK_TYPE='0402LF',
 LOCATION='R8097',
 CDS_LIB='pure_quanta',
 CDS_PART_NAME='Q_RES_0402LF-0,5%,1/16W,CHIP,CS00002JB13',
 PART_NUMBER='CS00002JB13',
 VALUE='0',
 PRIM_FILE='./archive_libs/logical/q_res/chips/chips.prt';

PART_NAME
 R8098 'Q_RES_0402LF-10K,5%,1/16W,EMPTY,CS31002JB08':
 ROOM='E1S_P3V3_BOM2';

SECTION_NUMBER 1
 '@T6G_MB_LIB.T6G(SCH_1):PAGE323_I70@PURE_QUANTA.Q_RES(CHIPS)':
 C_PATH='@t6g_mb_lib.t6g(sch_1):page323_i70@pure_quanta.q_res(chips)',
 P_PATH='@t6g_mb_lib.t6g(sch_1):page147_i70@pure_quanta.q_res(chips)',
 PATH='I70',
 DRAWING='@T6G_MB_LIB.T6G(SCH_1):PAGE323',
 WATTAGE='1/16W',
 TOLERANCE='5%',
 MATERIAL='EMPTY',
 PHYS_PAGE='147',
 XY='(-2100,-1600)',
 ROT='0',
 VER='2',
 PACK_TYPE='0402LF',
 LOCATION='R8098',
 CDS_LIB='pure_quanta',
 CDS_PART_NAME='Q_RES_0402LF-10K,5%,1/16W,EMPTY,CS31002JB08',
 ROOM='E1S_P3V3_BOM2',
 PART_NUMBER='CS31002JB08',
 VALUE='10K',
 PRIM_FILE='./archive_libs/logical/q_res/chips/chips.prt';

PART_NAME
 R8099 'Q_RES_0402LF-100K,1%,1/16W,CHIP,CS41002FB09':
 ROOM='E1S_P3V3_BOM2';

SECTION_NUMBER 1
 '@T6G_MB_LIB.T6G(SCH_1):PAGE323_I68@PURE_QUANTA.Q_RES(CHIPS)':
 C_PATH='@t6g_mb_lib.t6g(sch_1):page323_i68@pure_quanta.q_res(chips)',
 P_PATH='@t6g_mb_lib.t6g(sch_1):page147_i68@pure_quanta.q_res(chips)',
 PATH='I68',
 DRAWING='@T6G_MB_LIB.T6G(SCH_1):PAGE323',
 WATTAGE='1/16W',
 TOLERANCE='1%',
 MATERIAL='CHIP',
 PHYS_PAGE='147',
 XY='(-2250,-2475)',
 ROT='0',
 VER='2',
 PACK_TYPE='0402LF',
 LOCATION='R8099',
 CDS_LIB='pure_quanta',
 CDS_PART_NAME='Q_RES_0402LF-100K,1%,1/16W,CHIP,CS41002FB09',
 ROOM='E1S_P3V3_BOM2',
 PART_NUMBER='CS41002FB09',
 VALUE='100K',
 PRIM_FILE='./archive_libs/logical/q_res/chips/chips.prt';

PART_NAME
 R8100 'Q_RES_0402LF-0,5%,1/16W,CHIP,CS00002JB13':
 ROOM='E1S_P3V3_BOM2';

SECTION_NUMBER 1
 '@T6G_MB_LIB.T6G(SCH_1):PAGE323_I71@PURE_QUANTA.Q_RES(CHIPS)':
 C_PATH='@t6g_mb_lib.t6g(sch_1):page323_i71@pure_quanta.q_res(chips)',
 P_PATH='@t6g_mb_lib.t6g(sch_1):page147_i71@pure_quanta.q_res(chips)',
 PATH='I71',
 DRAWING='@T6G_MB_LIB.T6G(SCH_1):PAGE323',
 WATTAGE='1/16W',
 TOLERANCE='5%',
 MATERIAL='CHIP',
 PHYS_PAGE='147',
 XY='(-1725,-2100)',
 ROT='0',
 VER='1',
 PACK_TYPE='0402LF',
 LOCATION='R8100',
 CDS_LIB='pure_quanta',
 CDS_PART_NAME='Q_RES_0402LF-0,5%,1/16W,CHIP,CS00002JB13',
 ROOM='E1S_P3V3_BOM2',
 PART_NUMBER='CS00002JB13',
 VALUE='0',
 PRIM_FILE='./archive_libs/logical/q_res/chips/chips.prt';

PART_NAME
 R8101 'Q_RES_0402LF-0,5%,1/16W,CHIP,CS00002JB13':;

SECTION_NUMBER 1
 '@T6G_MB_LIB.T6G(SCH_1):PAGE348_I215@PURE_QUANTA.Q_RES(CHIPS)':
 C_PATH='@t6g_mb_lib.t6g(sch_1):page348_i215@pure_quanta.q_res(chips)',
 P_PATH='@t6g_mb_lib.t6g(sch_1):page150_i215@pure_quanta.q_res(chips)',
 PATH='I215',
 DRAWING='@T6G_MB_LIB.T6G(SCH_1):PAGE348',
 BOM_COST='MEM',
 WATTAGE='1/16W',
 TOLERANCE='5%',
 MATERIAL='CHIP',
 PHYS_PAGE='150',
 XY='(-10300,6525)',
 ROT='2',
 VER='1',
 PACK_TYPE='0402LF',
 LOCATION='R8101',
 CDS_LIB='pure_quanta',
 CDS_PART_NAME='Q_RES_0402LF-0,5%,1/16W,CHIP,CS00002JB13',
 PART_NUMBER='CS00002JB13',
 VALUE='0',
 PRIM_FILE='./archive_libs/logical/q_res/chips/chips.prt';

PART_NAME
 R8102 'Q_RES_0402LF-0,5%,1/16W,CHIP,CS00002JB13':;

SECTION_NUMBER 1
 '@T6G_MB_LIB.T6G(SCH_1):PAGE363_I467@PURE_QUANTA.Q_RES(CHIPS)':
 C_PATH='@t6g_mb_lib.t6g(sch_1):page363_i467@pure_quanta.q_res(chips)',
 P_PATH='@t6g_mb_lib.t6g(sch_1):page240_i467@pure_quanta.q_res(chips)',
 PATH='I467',
 DRAWING='@T6G_MB_LIB.T6G(SCH_1):PAGE363',
 WATTAGE='1/16W',
 TOLERANCE='5%',
 MATERIAL='CHIP',
 PHYS_PAGE='240',
 XY='(-5750,775)',
 ROT='0',
 VER='1',
 PACK_TYPE='0402LF',
 LOCATION='R8102',
 CDS_LIB='pure_quanta',
 CDS_PART_NAME='Q_RES_0402LF-0,5%,1/16W,CHIP,CS00002JB13',
 PART_NUMBER='CS00002JB13',
 VALUE='0',
 PRIM_FILE='./archive_libs/logical/q_res/chips/chips.prt';

PART_NAME
 R8103 'Q_RES_0402LF-8.45K,1%,1/16W,EMPTY,CS28452FB06':;

SECTION_NUMBER 1
 '@T6G_MB_LIB.T6G(SCH_1):PAGE365_I27@PURE_QUANTA.Q_RES(CHIPS)':
 C_PATH='@t6g_mb_lib.t6g(sch_1):page365_i27@pure_quanta.q_res(chips)',
 P_PATH='@t6g_mb_lib.t6g(sch_1):page242_i27@pure_quanta.q_res(chips)',
 PATH='I27',
 DRAWING='@T6G_MB_LIB.T6G(SCH_1):PAGE365',
 WATTAGE='1/16W',
 TOLERANCE='1%',
 MATERIAL='EMPTY',
 PHYS_PAGE='242',
 XY='(9375,1900)',
 ROT='0',
 VER='2',
 PACK_TYPE='0402LF',
 LOCATION='R8103',
 CDS_LIB='pure_quanta',
 CDS_PART_NAME='Q_RES_0402LF-8.45K,1%,1/16W,EMPTY,CS28452FB06',
 PART_NUMBER='CS28452FB06',
 VALUE='8.45K',
 PRIM_FILE='./archive_libs/logical/q_res/chips/chips.prt';

PART_NAME
 R8104 'Q_RES_0402LF-0,5%,1/16W,EMPTY,CS00002JB13':;

SECTION_NUMBER 1
 '@T6G_MB_LIB.T6G(SCH_1):PAGE365_I18@PURE_QUANTA.Q_RES(CHIPS)':
 C_PATH='@t6g_mb_lib.t6g(sch_1):page365_i18@pure_quanta.q_res(chips)',
 P_PATH='@t6g_mb_lib.t6g(sch_1):page242_i18@pure_quanta.q_res(chips)',
 PATH='I18',
 DRAWING='@T6G_MB_LIB.T6G(SCH_1):PAGE365',
 WATTAGE='1/16W',
 TOLERANCE='5%',
 MATERIAL='EMPTY',
 PHYS_PAGE='242',
 XY='(9975,1400)',
 ROT='0',
 VER='1',
 PACK_TYPE='0402LF',
 LOCATION='R8104',
 CDS_LIB='pure_quanta',
 CDS_PART_NAME='Q_RES_0402LF-0,5%,1/16W,EMPTY,CS00002JB13',
 PART_NUMBER='CS00002JB13',
 VALUE='0',
 PRIM_FILE='./archive_libs/logical/q_res/chips/chips.prt';

PART_NAME
 R8105 'Q_RES_0402LF-0,5%,1/16W,EMPTY,CS00002JB13':;

SECTION_NUMBER 1
 '@T6G_MB_LIB.T6G(SCH_1):PAGE365_I20@PURE_QUANTA.Q_RES(CHIPS)':
 C_PATH='@t6g_mb_lib.t6g(sch_1):page365_i20@pure_quanta.q_res(chips)',
 P_PATH='@t6g_mb_lib.t6g(sch_1):page242_i20@pure_quanta.q_res(chips)',
 PATH='I20',
 DRAWING='@T6G_MB_LIB.T6G(SCH_1):PAGE365',
 WATTAGE='1/16W',
 TOLERANCE='5%',
 MATERIAL='EMPTY',
 PHYS_PAGE='242',
 XY='(13875,1400)',
 ROT='0',
 VER='1',
 PACK_TYPE='0402LF',
 LOCATION='R8105',
 CDS_LIB='pure_quanta',
 CDS_PART_NAME='Q_RES_0402LF-0,5%,1/16W,EMPTY,CS00002JB13',
 PART_NUMBER='CS00002JB13',
 VALUE='0',
 PRIM_FILE='./archive_libs/logical/q_res/chips/chips.prt';

PART_NAME
 R8106 'Q_RES_0402LF-1K,1%,1/16W,CHIP,CS21002FB06':;

SECTION_NUMBER 1
 '@T6G_MB_LIB.T6G(SCH_1):PAGE365_I31@PURE_QUANTA.Q_RES(CHIPS)':
 C_PATH='@t6g_mb_lib.t6g(sch_1):page365_i31@pure_quanta.q_res(chips)',
 P_PATH='@t6g_mb_lib.t6g(sch_1):page242_i31@pure_quanta.q_res(chips)',
 PATH='I31',
 DRAWING='@T6G_MB_LIB.T6G(SCH_1):PAGE365',
 WATTAGE='1/16W',
 TOLERANCE='1%',
 MATERIAL='CHIP',
 PHYS_PAGE='242',
 XY='(14500,2050)',
 ROT='0',
 VER='2',
 PACK_TYPE='0402LF',
 LOCATION='R8106',
 CDS_LIB='pure_quanta',
 CDS_PART_NAME='Q_RES_0402LF-1K,1%,1/16W,CHIP,CS21002FB06',
 PART_NUMBER='CS21002FB06',
 VALUE='1K',
 PRIM_FILE='./archive_libs/logical/q_res/chips/chips.prt';

PART_NAME
 R8107 'Q_RES_0402LF-10K,1%,1/16W,EMPTY,CS31002FB08':
 ROOM='HSC BOM2';

SECTION_NUMBER 1
 '@T6G_MB_LIB.T6G(SCH_1):PAGE371_I81@PURE_QUANTA.Q_RES(CHIPS)':
 C_PATH='@t6g_mb_lib.t6g(sch_1):page371_i81@pure_quanta.q_res(chips)',
 P_PATH='@t6g_mb_lib.t6g(sch_1):page267_i81@pure_quanta.q_res(chips)',
 PATH='I81',
 DRAWING='@T6G_MB_LIB.T6G(SCH_1):PAGE371',
 WATTAGE='1/16W',
 TOLERANCE='1%',
 MATERIAL='EMPTY',
 PHYS_PAGE='267',
 XY='(-8925,3700)',
 ROT='0',
 VER='2',
 PACK_TYPE='0402LF',
 LOCATION='R8107',
 CDS_LIB='pure_quanta',
 CDS_PART_NAME='Q_RES_0402LF-10K,1%,1/16W,EMPTY,CS31002FB08',
 ROOM='HSC BOM2',
 PART_NUMBER='CS31002FB08',
 VALUE='10K',
 PRIM_FILE='./archive_libs/logical/q_res/chips/chips.prt';

PART_NAME
 R8108 'Q_RES_0402LF-160K,1%,1/16W,EMPTY,CS41602FB05':
 ROOM='HSC BOM2';

SECTION_NUMBER 1
 '@T6G_MB_LIB.T6G(SCH_1):PAGE371_I84@PURE_QUANTA.Q_RES(CHIPS)':
 C_PATH='@t6g_mb_lib.t6g(sch_1):page371_i84@pure_quanta.q_res(chips)',
 P_PATH='@t6g_mb_lib.t6g(sch_1):page267_i84@pure_quanta.q_res(chips)',
 PATH='I84',
 DRAWING='@T6G_MB_LIB.T6G(SCH_1):PAGE371',
 WATTAGE='1/16W',
 TOLERANCE='1%',
 MATERIAL='EMPTY',
 PHYS_PAGE='267',
 XY='(-7925,3750)',
 ROT='0',
 VER='2',
 PACK_TYPE='0402LF',
 LOCATION='R8108',
 CDS_LIB='pure_quanta',
 CDS_PART_NAME='Q_RES_0402LF-160K,1%,1/16W,EMPTY,CS41602FB05',
 ROOM='HSC BOM2',
 PART_NUMBER='CS41602FB05',
 VALUE='160K',
 PRIM_FILE='./archive_libs/logical/q_res/chips/chips.prt';

PART_NAME
 R8109 'Q_RES_0402LF-10K,1%,1/16W,EMPTY,CS31002FB08':
 ROOM='HSC BOM2';

SECTION_NUMBER 1
 '@T6G_MB_LIB.T6G(SCH_1):PAGE371_I82@PURE_QUANTA.Q_RES(CHIPS)':
 C_PATH='@t6g_mb_lib.t6g(sch_1):page371_i82@pure_quanta.q_res(chips)',
 P_PATH='@t6g_mb_lib.t6g(sch_1):page267_i82@pure_quanta.q_res(chips)',
 PATH='I82',
 DRAWING='@T6G_MB_LIB.T6G(SCH_1):PAGE371',
 WATTAGE='1/16W',
 TOLERANCE='1%',
 MATERIAL='EMPTY',
 PHYS_PAGE='267',
 XY='(-7925,3075)',
 ROT='0',
 VER='2',
 PACK_TYPE='0402LF',
 LOCATION='R8109',
 CDS_LIB='pure_quanta',
 CDS_PART_NAME='Q_RES_0402LF-10K,1%,1/16W,EMPTY,CS31002FB08',
 ROOM='HSC BOM2',
 PART_NUMBER='CS31002FB08',
 VALUE='10K',
 PRIM_FILE='./archive_libs/logical/q_res/chips/chips.prt';

PART_NAME
 R8110 'Q_RES_0402LF-33.2,1%,1/16W,EMPTY,CS03322FB03':
 ROOM='HSC BOM2';

SECTION_NUMBER 1
 '@T6G_MB_LIB.T6G(SCH_1):PAGE371_I96@PURE_QUANTA.Q_RES(CHIPS)':
 C_PATH='@t6g_mb_lib.t6g(sch_1):page371_i96@pure_quanta.q_res(chips)',
 P_PATH='@t6g_mb_lib.t6g(sch_1):page267_i96@pure_quanta.q_res(chips)',
 PATH='I96',
 DRAWING='@T6G_MB_LIB.T6G(SCH_1):PAGE371',
 WATTAGE='1/16W',
 TOLERANCE='1%',
 MATERIAL='EMPTY',
 PHYS_PAGE='267',
 XY='(-5375,3475)',
 ROT='0',
 VER='1',
 PACK_TYPE='0402LF',
 LOCATION='R8110',
 CDS_LIB='pure_quanta',
 CDS_PART_NAME='Q_RES_0402LF-33.2,1%,1/16W,EMPTY,CS03322FB03',
 ROOM='HSC BOM2',
 PART_NUMBER='CS03322FB03',
 VALUE='33.2',
 PRIM_FILE='./archive_libs/logical/q_res/chips/chips.prt';

PART_NAME
 R8111 'Q_RES_0402LF-10K,1%,1/16W,EMPTY,CS31002FB08':
 ROOM='HSC BOM2';

SECTION_NUMBER 1
 '@T6G_MB_LIB.T6G(SCH_1):PAGE371_I98@PURE_QUANTA.Q_RES(CHIPS)':
 C_PATH='@t6g_mb_lib.t6g(sch_1):page371_i98@pure_quanta.q_res(chips)',
 P_PATH='@t6g_mb_lib.t6g(sch_1):page267_i98@pure_quanta.q_res(chips)',
 PATH='I98',
 DRAWING='@T6G_MB_LIB.T6G(SCH_1):PAGE371',
 WATTAGE='1/16W',
 TOLERANCE='1%',
 MATERIAL='EMPTY',
 PHYS_PAGE='267',
 XY='(-4550,3750)',
 ROT='0',
 VER='2',
 PACK_TYPE='0402LF',
 LOCATION='R8111',
 CDS_LIB='pure_quanta',
 CDS_PART_NAME='Q_RES_0402LF-10K,1%,1/16W,EMPTY,CS31002FB08',
 ROOM='HSC BOM2',
 PART_NUMBER='CS31002FB08',
 VALUE='10K',
 PRIM_FILE='./archive_libs/logical/q_res/chips/chips.prt';

PART_NAME
 R8112 'Q_RES_0402LF-1M,1%,1/16W,EMPTY,CS51002FB05':
 ROOM='HSC BOM2';

SECTION_NUMBER 1
 '@T6G_MB_LIB.T6G(SCH_1):PAGE371_I103@PURE_QUANTA.Q_RES(CHIPS)':
 C_PATH='@t6g_mb_lib.t6g(sch_1):page371_i103@pure_quanta.q_res(chips)',
 P_PATH='@t6g_mb_lib.t6g(sch_1):page267_i103@pure_quanta.q_res(chips)',
 PATH='I103',
 DRAWING='@T6G_MB_LIB.T6G(SCH_1):PAGE371',
 WATTAGE='1/16W',
 TOLERANCE='1%',
 MATERIAL='EMPTY',
 PHYS_PAGE='267',
 XY='(-6300,3800)',
 ROT='0',
 VER='1',
 PACK_TYPE='0402LF',
 LOCATION='R8112',
 CDS_LIB='pure_quanta',
 CDS_PART_NAME='Q_RES_0402LF-1M,1%,1/16W,EMPTY,CS51002FB05',
 ROOM='HSC BOM2',
 PART_NUMBER='CS51002FB05',
 VALUE='1M',
 PRIM_FILE='./archive_libs/logical/q_res/chips/chips.prt';

PART_NAME
 R8113 'Q_RES_0402LF-10K,1%,1/16W,CHIP,CS31002FB08':;

SECTION_NUMBER 1
 '@T6G_MB_LIB.T6G(SCH_1):PAGE372_I52@PURE_QUANTA.Q_RES(CHIPS)':
 C_PATH='@t6g_mb_lib.t6g(sch_1):page372_i52@pure_quanta.q_res(chips)',
 P_PATH='@t6g_mb_lib.t6g(sch_1):page268_i52@pure_quanta.q_res(chips)',
 PATH='I52',
 DRAWING='@T6G_MB_LIB.T6G(SCH_1):PAGE372',
 WATTAGE='1/16W',
 TOLERANCE='1%',
 MATERIAL='CHIP',
 PHYS_PAGE='268',
 XY='(-5500,3650)',
 ROT='0',
 VER='2',
 PACK_TYPE='0402LF',
 LOCATION='R8113',
 CDS_LIB='pure_quanta',
 CDS_PART_NAME='Q_RES_0402LF-10K,1%,1/16W,CHIP,CS31002FB08',
 PART_NUMBER='CS31002FB08',
 VALUE='10K',
 PRIM_FILE='./archive_libs/logical/q_res/chips/chips.prt';

PART_NAME
 R8114 'Q_RES_0402LF-17.8K,1%,1/16W,CHIP,CS31782FB04':;

SECTION_NUMBER 1
 '@T6G_MB_LIB.T6G(SCH_1):PAGE372_I56@PURE_QUANTA.Q_RES(CHIPS)':
 C_PATH='@t6g_mb_lib.t6g(sch_1):page372_i56@pure_quanta.q_res(chips)',
 P_PATH='@t6g_mb_lib.t6g(sch_1):page268_i56@pure_quanta.q_res(chips)',
 PATH='I56',
 DRAWING='@T6G_MB_LIB.T6G(SCH_1):PAGE372',
 WATTAGE='1/16W',
 TOLERANCE='1%',
 MATERIAL='CHIP',
 PHYS_PAGE='268',
 XY='(-4500,3700)',
 ROT='0',
 VER='2',
 PACK_TYPE='0402LF',
 LOCATION='R8114',
 CDS_LIB='pure_quanta',
 CDS_PART_NAME='Q_RES_0402LF-17.8K,1%,1/16W,CHIP,CS31782FB04',
 PART_NUMBER='CS31782FB04',
 VALUE='17.8K',
 PRIM_FILE='./archive_libs/logical/q_res/chips/chips.prt';

PART_NAME
 R8115 'Q_RES_0402LF-5.11K,1%,1/16W,CHIP,CS25112FB04':;

SECTION_NUMBER 1
 '@T6G_MB_LIB.T6G(SCH_1):PAGE372_I55@PURE_QUANTA.Q_RES(CHIPS)':
 C_PATH='@t6g_mb_lib.t6g(sch_1):page372_i55@pure_quanta.q_res(chips)',
 P_PATH='@t6g_mb_lib.t6g(sch_1):page268_i55@pure_quanta.q_res(chips)',
 PATH='I55',
 DRAWING='@T6G_MB_LIB.T6G(SCH_1):PAGE372',
 WATTAGE='1/16W',
 TOLERANCE='1%',
 MATERIAL='CHIP',
 PHYS_PAGE='268',
 XY='(-4500,3025)',
 ROT='0',
 VER='2',
 PACK_TYPE='0402LF',
 LOCATION='R8115',
 CDS_LIB='pure_quanta',
 CDS_PART_NAME='Q_RES_0402LF-5.11K,1%,1/16W,CHIP,CS25112FB04',
 PART_NUMBER='CS25112FB04',
 VALUE='5.11K',
 PRIM_FILE='./archive_libs/logical/q_res/chips/chips.prt';

PART_NAME
 R8116 'Q_RES_0402LF-0,5%,1/16W,EMPTY,CS00002JB13':;

SECTION_NUMBER 1
 '@T6G_MB_LIB.T6G(SCH_1):PAGE182_I13@PURE_QUANTA.Q_RES(CHIPS)':
 C_PATH='@t6g_mb_lib.t6g(sch_1):page182_i13@pure_quanta.q_res(chips)',
 P_PATH='@t6g_mb_lib.t6g(sch_1):page207_i13@pure_quanta.q_res(chips)',
 PATH='I13',
 DRAWING='@T6G_MB_LIB.T6G(SCH_1):PAGE182',
 WATTAGE='1/16W',
 TOLERANCE='5%',
 MATERIAL='EMPTY',
 PHYS_PAGE='207',
 XY='(-6275,2125)',
 ROT='0',
 VER='1',
 PACK_TYPE='0402LF',
 LOCATION='R8116',
 CDS_LIB='pure_quanta',
 CDS_PART_NAME='Q_RES_0402LF-0,5%,1/16W,EMPTY,CS00002JB13',
 PART_NUMBER='CS00002JB13',
 VALUE='0',
 PRIM_FILE='./archive_libs/logical/q_res/chips/chips.prt';

PART_NAME
 R8117 'Q_RES_0402LF-1M,1%,1/16W,CHIP,CS51002FB05':;

SECTION_NUMBER 1
 '@T6G_MB_LIB.T6G(SCH_1):PAGE372_I63@PURE_QUANTA.Q_RES(CHIPS)':
 C_PATH='@t6g_mb_lib.t6g(sch_1):page372_i63@pure_quanta.q_res(chips)',
 P_PATH='@t6g_mb_lib.t6g(sch_1):page268_i63@pure_quanta.q_res(chips)',
 PATH='I63',
 DRAWING='@T6G_MB_LIB.T6G(SCH_1):PAGE372',
 WATTAGE='1/16W',
 TOLERANCE='1%',
 MATERIAL='CHIP',
 PHYS_PAGE='268',
 XY='(-2875,3750)',
 ROT='0',
 VER='1',
 PACK_TYPE='0402LF',
 LOCATION='R8117',
 CDS_LIB='pure_quanta',
 CDS_PART_NAME='Q_RES_0402LF-1M,1%,1/16W,CHIP,CS51002FB05',
 PART_NUMBER='CS51002FB05',
 VALUE='1M',
 PRIM_FILE='./archive_libs/logical/q_res/chips/chips.prt';

PART_NAME
 R8118 'Q_RES_0402LF-33.2,1%,1/16W,CHIP,CS03322FB03':;

SECTION_NUMBER 1
 '@T6G_MB_LIB.T6G(SCH_1):PAGE372_I67@PURE_QUANTA.Q_RES(CHIPS)':
 C_PATH='@t6g_mb_lib.t6g(sch_1):page372_i67@pure_quanta.q_res(chips)',
 P_PATH='@t6g_mb_lib.t6g(sch_1):page268_i67@pure_quanta.q_res(chips)',
 PATH='I67',
 DRAWING='@T6G_MB_LIB.T6G(SCH_1):PAGE372',
 WATTAGE='1/16W',
 TOLERANCE='1%',
 MATERIAL='CHIP',
 PHYS_PAGE='268',
 XY='(-1950,3425)',
 ROT='0',
 VER='1',
 PACK_TYPE='0402LF',
 LOCATION='R8118',
 CDS_LIB='pure_quanta',
 CDS_PART_NAME='Q_RES_0402LF-33.2,1%,1/16W,CHIP,CS03322FB03',
 PART_NUMBER='CS03322FB03',
 VALUE='33.2',
 PRIM_FILE='./archive_libs/logical/q_res/chips/chips.prt';

PART_NAME
 R8119 'Q_RES_0402LF-1K,1%,1/16W,CHIP,CS21002FB06':;

SECTION_NUMBER 1
 '@T6G_MB_LIB.T6G(SCH_1):PAGE372_I69@PURE_QUANTA.Q_RES(CHIPS)':
 C_PATH='@t6g_mb_lib.t6g(sch_1):page372_i69@pure_quanta.q_res(chips)',
 P_PATH='@t6g_mb_lib.t6g(sch_1):page268_i69@pure_quanta.q_res(chips)',
 PATH='I69',
 DRAWING='@T6G_MB_LIB.T6G(SCH_1):PAGE372',
 WATTAGE='1/16W',
 TOLERANCE='1%',
 MATERIAL='CHIP',
 PHYS_PAGE='268',
 XY='(-975,3700)',
 ROT='0',
 VER='2',
 PACK_TYPE='0402LF',
 LOCATION='R8119',
 CDS_LIB='pure_quanta',
 CDS_PART_NAME='Q_RES_0402LF-1K,1%,1/16W,CHIP,CS21002FB06',
 PART_NUMBER='CS21002FB06',
 VALUE='1K',
 PRIM_FILE='./archive_libs/logical/q_res/chips/chips.prt';

PART_NAME
 R8120 'Q_RES_0402LF-10K,1%,1/16W,CHIP,CS31002FB08':;

SECTION_NUMBER 1
 '@T6G_MB_LIB.T6G(SCH_1):PAGE372_I72@PURE_QUANTA.Q_RES(CHIPS)':
 C_PATH='@t6g_mb_lib.t6g(sch_1):page372_i72@pure_quanta.q_res(chips)',
 P_PATH='@t6g_mb_lib.t6g(sch_1):page268_i72@pure_quanta.q_res(chips)',
 PATH='I72',
 DRAWING='@T6G_MB_LIB.T6G(SCH_1):PAGE372',
 WATTAGE='1/16W',
 TOLERANCE='1%',
 MATERIAL='CHIP',
 PHYS_PAGE='268',
 XY='(-5175,1950)',
 ROT='0',
 VER='2',
 PACK_TYPE='0402LF',
 LOCATION='R8120',
 CDS_LIB='pure_quanta',
 CDS_PART_NAME='Q_RES_0402LF-10K,1%,1/16W,CHIP,CS31002FB08',
 PART_NUMBER='CS31002FB08',
 VALUE='10K',
 PRIM_FILE='./archive_libs/logical/q_res/chips/chips.prt';

PART_NAME
 R8121 'Q_RES_0402LF-17.8K,1%,1/16W,CHIP,CS31782FB04':;

SECTION_NUMBER 1
 '@T6G_MB_LIB.T6G(SCH_1):PAGE372_I76@PURE_QUANTA.Q_RES(CHIPS)':
 C_PATH='@t6g_mb_lib.t6g(sch_1):page372_i76@pure_quanta.q_res(chips)',
 P_PATH='@t6g_mb_lib.t6g(sch_1):page268_i76@pure_quanta.q_res(chips)',
 PATH='I76',
 DRAWING='@T6G_MB_LIB.T6G(SCH_1):PAGE372',
 WATTAGE='1/16W',
 TOLERANCE='1%',
 MATERIAL='CHIP',
 PHYS_PAGE='268',
 XY='(-4175,2000)',
 ROT='0',
 VER='2',
 PACK_TYPE='0402LF',
 LOCATION='R8121',
 CDS_LIB='pure_quanta',
 CDS_PART_NAME='Q_RES_0402LF-17.8K,1%,1/16W,CHIP,CS31782FB04',
 PART_NUMBER='CS31782FB04',
 VALUE='17.8K',
 PRIM_FILE='./archive_libs/logical/q_res/chips/chips.prt';

PART_NAME
 R8122 'Q_RES_0402LF-5.11K,1%,1/16W,CHIP,CS25112FB04':;

SECTION_NUMBER 1
 '@T6G_MB_LIB.T6G(SCH_1):PAGE372_I75@PURE_QUANTA.Q_RES(CHIPS)':
 C_PATH='@t6g_mb_lib.t6g(sch_1):page372_i75@pure_quanta.q_res(chips)',
 P_PATH='@t6g_mb_lib.t6g(sch_1):page268_i75@pure_quanta.q_res(chips)',
 PATH='I75',
 DRAWING='@T6G_MB_LIB.T6G(SCH_1):PAGE372',
 WATTAGE='1/16W',
 TOLERANCE='1%',
 MATERIAL='CHIP',
 PHYS_PAGE='268',
 XY='(-4175,1325)',
 ROT='0',
 VER='2',
 PACK_TYPE='0402LF',
 LOCATION='R8122',
 CDS_LIB='pure_quanta',
 CDS_PART_NAME='Q_RES_0402LF-5.11K,1%,1/16W,CHIP,CS25112FB04',
 PART_NUMBER='CS25112FB04',
 VALUE='5.11K',
 PRIM_FILE='./archive_libs/logical/q_res/chips/chips.prt';

PART_NAME
 R8123 'Q_RES_0402LF-1M,1%,1/16W,CHIP,CS51002FB05':;

SECTION_NUMBER 1
 '@T6G_MB_LIB.T6G(SCH_1):PAGE372_I81@PURE_QUANTA.Q_RES(CHIPS)':
 C_PATH='@t6g_mb_lib.t6g(sch_1):page372_i81@pure_quanta.q_res(chips)',
 P_PATH='@t6g_mb_lib.t6g(sch_1):page268_i81@pure_quanta.q_res(chips)',
 PATH='I81',
 DRAWING='@T6G_MB_LIB.T6G(SCH_1):PAGE372',
 WATTAGE='1/16W',
 TOLERANCE='1%',
 MATERIAL='CHIP',
 PHYS_PAGE='268',
 XY='(-2550,2050)',
 ROT='0',
 VER='1',
 PACK_TYPE='0402LF',
 LOCATION='R8123',
 CDS_LIB='pure_quanta',
 CDS_PART_NAME='Q_RES_0402LF-1M,1%,1/16W,CHIP,CS51002FB05',
 PART_NUMBER='CS51002FB05',
 VALUE='1M',
 PRIM_FILE='./archive_libs/logical/q_res/chips/chips.prt';

PART_NAME
 R8124 'Q_RES_0402LF-33.2,1%,1/16W,CHIP,CS03322FB03':;

SECTION_NUMBER 1
 '@T6G_MB_LIB.T6G(SCH_1):PAGE372_I85@PURE_QUANTA.Q_RES(CHIPS)':
 C_PATH='@t6g_mb_lib.t6g(sch_1):page372_i85@pure_quanta.q_res(chips)',
 P_PATH='@t6g_mb_lib.t6g(sch_1):page268_i85@pure_quanta.q_res(chips)',
 PATH='I85',
 DRAWING='@T6G_MB_LIB.T6G(SCH_1):PAGE372',
 WATTAGE='1/16W',
 TOLERANCE='1%',
 MATERIAL='CHIP',
 PHYS_PAGE='268',
 XY='(-1625,1725)',
 ROT='0',
 VER='1',
 PACK_TYPE='0402LF',
 LOCATION='R8124',
 CDS_LIB='pure_quanta',
 CDS_PART_NAME='Q_RES_0402LF-33.2,1%,1/16W,CHIP,CS03322FB03',
 PART_NUMBER='CS03322FB03',
 VALUE='33.2',
 PRIM_FILE='./archive_libs/logical/q_res/chips/chips.prt';

PART_NAME
 R8125 'Q_RES_0402LF-1K,1%,1/16W,CHIP,CS21002FB06':;

SECTION_NUMBER 1
 '@T6G_MB_LIB.T6G(SCH_1):PAGE372_I104@PURE_QUANTA.Q_RES(CHIPS)':
 C_PATH='@t6g_mb_lib.t6g(sch_1):page372_i104@pure_quanta.q_res(chips)',
 P_PATH='@t6g_mb_lib.t6g(sch_1):page268_i104@pure_quanta.q_res(chips)',
 PATH='I104',
 DRAWING='@T6G_MB_LIB.T6G(SCH_1):PAGE372',
 WATTAGE='1/16W',
 TOLERANCE='1%',
 MATERIAL='CHIP',
 PHYS_PAGE='268',
 XY='(-650,2000)',
 ROT='0',
 VER='2',
 PACK_TYPE='0402LF',
 LOCATION='R8125',
 CDS_LIB='pure_quanta',
 CDS_PART_NAME='Q_RES_0402LF-1K,1%,1/16W,CHIP,CS21002FB06',
 PART_NUMBER='CS21002FB06',
 VALUE='1K',
 PRIM_FILE='./archive_libs/logical/q_res/chips/chips.prt';

PART_NAME
 R8146 'Q_RES_0402LF-0,5%,1/16W,EMPTY,CS00002JB13':;

SECTION_NUMBER 1
 '@T6G_MB_LIB.T6G(SCH_1):PAGE199_I9@PURE_QUANTA.Q_RES(CHIPS)':
 C_PATH='@t6g_mb_lib.t6g(sch_1):page199_i9@pure_quanta.q_res(chips)',
 P_PATH='@t6g_mb_lib.t6g(sch_1):page224_i9@pure_quanta.q_res(chips)',
 PATH='I9',
 DRAWING='@T6G_MB_LIB.T6G(SCH_1):PAGE199',
 WATTAGE='1/16W',
 TOLERANCE='5%',
 MATERIAL='EMPTY',
 PHYS_PAGE='224',
 XY='(-6175,1725)',
 ROT='0',
 VER='1',
 PACK_TYPE='0402LF',
 LOCATION='R8146',
 CDS_LIB='pure_quanta',
 CDS_PART_NAME='Q_RES_0402LF-0,5%,1/16W,EMPTY,CS00002JB13',
 PART_NUMBER='CS00002JB13',
 VALUE='0',
 PRIM_FILE='./archive_libs/logical/q_res/chips/chips.prt';

PART_NAME
 R8153 'Q_RES_0402LF-1K,1%,1/16W,EMPTY,CS21002FB06':;

SECTION_NUMBER 1
 '@T6G_MB_LIB.T6G(SCH_1):PAGE185_I6@PURE_QUANTA.Q_RES(CHIPS)':
 C_PATH='@t6g_mb_lib.t6g(sch_1):page185_i6@pure_quanta.q_res(chips)',
 P_PATH='@t6g_mb_lib.t6g(sch_1):page210_i6@pure_quanta.q_res(chips)',
 PATH='I6',
 DRAWING='@T6G_MB_LIB.T6G(SCH_1):PAGE185',
 WATTAGE='1/16W',
 TOLERANCE='1%',
 MATERIAL='EMPTY',
 PHYS_PAGE='210',
 XY='(-5025,6800)',
 ROT='0',
 VER='2',
 PACK_TYPE='0402LF',
 LOCATION='R8153',
 CDS_LIB='pure_quanta',
 CDS_PART_NAME='Q_RES_0402LF-1K,1%,1/16W,EMPTY,CS21002FB06',
 PART_NUMBER='CS21002FB06',
 VALUE='1K',
 PRIM_FILE='./archive_libs/logical/q_res/chips/chips.prt';

PART_NAME
 R8156 'Q_RES_0402LF-1K,1%,1/16W,EMPTY,CS21002FB06':;

SECTION_NUMBER 1
 '@T6G_MB_LIB.T6G(SCH_1):PAGE185_I68@PURE_QUANTA.Q_RES(CHIPS)':
 C_PATH='@t6g_mb_lib.t6g(sch_1):page185_i68@pure_quanta.q_res(chips)',
 P_PATH='@t6g_mb_lib.t6g(sch_1):page210_i68@pure_quanta.q_res(chips)',
 PATH='I68',
 DRAWING='@T6G_MB_LIB.T6G(SCH_1):PAGE185',
 WATTAGE='1/16W',
 TOLERANCE='1%',
 MATERIAL='EMPTY',
 PHYS_PAGE='210',
 XY='(-4475,7750)',
 ROT='0',
 VER='2',
 PACK_TYPE='0402LF',
 LOCATION='R8156',
 CDS_LIB='pure_quanta',
 CDS_PART_NAME='Q_RES_0402LF-1K,1%,1/16W,EMPTY,CS21002FB06',
 PART_NUMBER='CS21002FB06',
 VALUE='1K',
 PRIM_FILE='./archive_libs/logical/q_res/chips/chips.prt';

PART_NAME
 R8160 'Q_RES_0402LF-1K,1%,1/16W,EMPTY,CS21002FB06':;

SECTION_NUMBER 1
 '@T6G_MB_LIB.T6G(SCH_1):PAGE185_I69@PURE_QUANTA.Q_RES(CHIPS)':
 C_PATH='@t6g_mb_lib.t6g(sch_1):page185_i69@pure_quanta.q_res(chips)',
 P_PATH='@t6g_mb_lib.t6g(sch_1):page210_i69@pure_quanta.q_res(chips)',
 PATH='I69',
 DRAWING='@T6G_MB_LIB.T6G(SCH_1):PAGE185',
 WATTAGE='1/16W',
 TOLERANCE='1%',
 MATERIAL='EMPTY',
 PHYS_PAGE='210',
 XY='(-4200,7750)',
 ROT='0',
 VER='2',
 PACK_TYPE='0402LF',
 LOCATION='R8160',
 CDS_LIB='pure_quanta',
 CDS_PART_NAME='Q_RES_0402LF-1K,1%,1/16W,EMPTY,CS21002FB06',
 PART_NUMBER='CS21002FB06',
 VALUE='1K',
 PRIM_FILE='./archive_libs/logical/q_res/chips/chips.prt';

PART_NAME
 R8165 'Q_RES_0402LF-1K,1%,1/16W,CHIP,CS21002FB06':;

SECTION_NUMBER 1
 '@T6G_MB_LIB.T6G(SCH_1):PAGE185_I27@PURE_QUANTA.Q_RES(CHIPS)':
 C_PATH='@t6g_mb_lib.t6g(sch_1):page185_i27@pure_quanta.q_res(chips)',
 P_PATH='@t6g_mb_lib.t6g(sch_1):page210_i27@pure_quanta.q_res(chips)',
 PATH='I27',
 DRAWING='@T6G_MB_LIB.T6G(SCH_1):PAGE185',
 WATTAGE='1/16W',
 TOLERANCE='1%',
 MATERIAL='CHIP',
 PHYS_PAGE='210',
 XY='(-3100,3025)',
 ROT='0',
 VER='1',
 PACK_TYPE='0402LF',
 LOCATION='R8165',
 CDS_LIB='pure_quanta',
 CDS_PART_NAME='Q_RES_0402LF-1K,1%,1/16W,CHIP,CS21002FB06',
 PART_NUMBER='CS21002FB06',
 VALUE='1K',
 PRIM_FILE='./archive_libs/logical/q_res/chips/chips.prt';

PART_NAME
 R8166 'Q_RES_0402LF-33,5%,1/16W,CHIP,CS03302JB10':;

SECTION_NUMBER 1
 '@T6G_MB_LIB.T6G(SCH_1):PAGE185_I23@PURE_QUANTA.Q_RES(CHIPS)':
 C_PATH='@t6g_mb_lib.t6g(sch_1):page185_i23@pure_quanta.q_res(chips)',
 P_PATH='@t6g_mb_lib.t6g(sch_1):page210_i23@pure_quanta.q_res(chips)',
 PATH='I23',
 DRAWING='@T6G_MB_LIB.T6G(SCH_1):PAGE185',
 WATTAGE='1/16W',
 TOLERANCE='5%',
 MATERIAL='CHIP',
 PHYS_PAGE='210',
 XY='(-3100,2775)',
 ROT='0',
 VER='1',
 PACK_TYPE='0402LF',
 LOCATION='R8166',
 CDS_LIB='pure_quanta',
 CDS_PART_NAME='Q_RES_0402LF-33,5%,1/16W,CHIP,CS03302JB10',
 PART_NUMBER='CS03302JB10',
 VALUE='33',
 PRIM_FILE='./archive_libs/logical/q_res/chips/chips.prt';

PART_NAME
 R8167 'Q_RES_0402LF-1K,1%,1/16W,CHIP,CS21002FB06':;

SECTION_NUMBER 1
 '@T6G_MB_LIB.T6G(SCH_1):PAGE185_I78@PURE_QUANTA.Q_RES(CHIPS)':
 C_PATH='@t6g_mb_lib.t6g(sch_1):page185_i78@pure_quanta.q_res(chips)',
 P_PATH='@t6g_mb_lib.t6g(sch_1):page210_i78@pure_quanta.q_res(chips)',
 PATH='I78',
 DRAWING='@T6G_MB_LIB.T6G(SCH_1):PAGE185',
 WATTAGE='1/16W',
 TOLERANCE='1%',
 MATERIAL='CHIP',
 PHYS_PAGE='210',
 XY='(-2900,8150)',
 ROT='0',
 VER='1',
 PACK_TYPE='0402LF',
 LOCATION='R8167',
 CDS_LIB='pure_quanta',
 CDS_PART_NAME='Q_RES_0402LF-1K,1%,1/16W,CHIP,CS21002FB06',
 PART_NUMBER='CS21002FB06',
 VALUE='1K',
 PRIM_FILE='./archive_libs/logical/q_res/chips/chips.prt';

PART_NAME
 R8168 'Q_RES_0402LF-0,5%,1/16W,CHIP,CS00002JB13':;

SECTION_NUMBER 1
 '@T6G_MB_LIB.T6G(SCH_1):PAGE185_I43@PURE_QUANTA.Q_RES(CHIPS)':
 C_PATH='@t6g_mb_lib.t6g(sch_1):page185_i43@pure_quanta.q_res(chips)',
 P_PATH='@t6g_mb_lib.t6g(sch_1):page210_i43@pure_quanta.q_res(chips)',
 PATH='I43',
 DRAWING='@T6G_MB_LIB.T6G(SCH_1):PAGE185',
 WATTAGE='1/16W',
 TOLERANCE='5%',
 MATERIAL='CHIP',
 PHYS_PAGE='210',
 XY='(-2825,3875)',
 ROT='0',
 VER='1',
 PACK_TYPE='0402LF',
 LOCATION='R8168',
 CDS_LIB='pure_quanta',
 CDS_PART_NAME='Q_RES_0402LF-0,5%,1/16W,CHIP,CS00002JB13',
 PART_NUMBER='CS00002JB13',
 VALUE='0',
 PRIM_FILE='./archive_libs/logical/q_res/chips/chips.prt';

PART_NAME
 R8171 'Q_RES_0402LF-49.9,1%,1/16W,CHIP,CS04992FB07':;

SECTION_NUMBER 1
 '@T6G_MB_LIB.T6G(SCH_1):PAGE185_I83@PURE_QUANTA.Q_RES(CHIPS)':
 C_PATH='@t6g_mb_lib.t6g(sch_1):page185_i83@pure_quanta.q_res(chips)',
 P_PATH='@t6g_mb_lib.t6g(sch_1):page210_i83@pure_quanta.q_res(chips)',
 PATH='I83',
 DRAWING='@T6G_MB_LIB.T6G(SCH_1):PAGE185',
 WATTAGE='1/16W',
 TOLERANCE='1%',
 MATERIAL='CHIP',
 PHYS_PAGE='210',
 XY='(-2800,7125)',
 ROT='0',
 VER='1',
 PACK_TYPE='0402LF',
 LOCATION='R8171',
 CDS_LIB='pure_quanta',
 CDS_PART_NAME='Q_RES_0402LF-49.9,1%,1/16W,CHIP,CS04992FB07',
 PART_NUMBER='CS04992FB07',
 VALUE='49.9',
 PRIM_FILE='./archive_libs/logical/q_res/chips/chips.prt';

PART_NAME
 R8176 'Q_RES_0402LF-0,5%,1/16W,CHIP,CS00002JB13':;

SECTION_NUMBER 1
 '@T6G_MB_LIB.T6G(SCH_1):PAGE185_I80@PURE_QUANTA.Q_RES(CHIPS)':
 C_PATH='@t6g_mb_lib.t6g(sch_1):page185_i80@pure_quanta.q_res(chips)',
 P_PATH='@t6g_mb_lib.t6g(sch_1):page210_i80@pure_quanta.q_res(chips)',
 PATH='I80',
 DRAWING='@T6G_MB_LIB.T6G(SCH_1):PAGE185',
 WATTAGE='1/16W',
 TOLERANCE='5%',
 MATERIAL='CHIP',
 PHYS_PAGE='210',
 XY='(-2700,6575)',
 ROT='0',
 VER='1',
 PACK_TYPE='0402LF',
 LOCATION='R8176',
 CDS_LIB='pure_quanta',
 CDS_PART_NAME='Q_RES_0402LF-0,5%,1/16W,CHIP,CS00002JB13',
 PART_NUMBER='CS00002JB13',
 VALUE='0',
 PRIM_FILE='./archive_libs/logical/q_res/chips/chips.prt';

PART_NAME
 R8177 'Q_RES_0402LF-33,5%,1/16W,CHIP,CS03302JB10':;

SECTION_NUMBER 1
 '@T6G_MB_LIB.T6G(SCH_1):PAGE185_I79@PURE_QUANTA.Q_RES(CHIPS)':
 C_PATH='@t6g_mb_lib.t6g(sch_1):page185_i79@pure_quanta.q_res(chips)',
 P_PATH='@t6g_mb_lib.t6g(sch_1):page210_i79@pure_quanta.q_res(chips)',
 PATH='I79',
 DRAWING='@T6G_MB_LIB.T6G(SCH_1):PAGE185',
 WATTAGE='1/16W',
 TOLERANCE='5%',
 MATERIAL='CHIP',
 PHYS_PAGE='210',
 XY='(-2700,6425)',
 ROT='0',
 VER='1',
 PACK_TYPE='0402LF',
 LOCATION='R8177',
 CDS_LIB='pure_quanta',
 CDS_PART_NAME='Q_RES_0402LF-33,5%,1/16W,CHIP,CS03302JB10',
 PART_NUMBER='CS03302JB10',
 VALUE='33',
 PRIM_FILE='./archive_libs/logical/q_res/chips/chips.prt';

PART_NAME
 R8178 'Q_RES_0402LF-33,5%,1/16W,CHIP,CS03302JB10':;

SECTION_NUMBER 1
 '@T6G_MB_LIB.T6G(SCH_1):PAGE185_I85@PURE_QUANTA.Q_RES(CHIPS)':
 C_PATH='@t6g_mb_lib.t6g(sch_1):page185_i85@pure_quanta.q_res(chips)',
 P_PATH='@t6g_mb_lib.t6g(sch_1):page210_i85@pure_quanta.q_res(chips)',
 PATH='I85',
 DRAWING='@T6G_MB_LIB.T6G(SCH_1):PAGE185',
 WATTAGE='1/16W',
 TOLERANCE='5%',
 MATERIAL='CHIP',
 PHYS_PAGE='210',
 XY='(-2675,7875)',
 ROT='0',
 VER='1',
 PACK_TYPE='0402LF',
 LOCATION='R8178',
 CDS_LIB='pure_quanta',
 CDS_PART_NAME='Q_RES_0402LF-33,5%,1/16W,CHIP,CS03302JB10',
 PART_NUMBER='CS03302JB10',
 VALUE='33',
 PRIM_FILE='./archive_libs/logical/q_res/chips/chips.prt';

PART_NAME
 R8179 'Q_RES_0402LF-0,5%,1/16W,CHIP,CS00002JB13':;

SECTION_NUMBER 1
 '@T6G_MB_LIB.T6G(SCH_1):PAGE185_I84@PURE_QUANTA.Q_RES(CHIPS)':
 C_PATH='@t6g_mb_lib.t6g(sch_1):page185_i84@pure_quanta.q_res(chips)',
 P_PATH='@t6g_mb_lib.t6g(sch_1):page210_i84@pure_quanta.q_res(chips)',
 PATH='I84',
 DRAWING='@T6G_MB_LIB.T6G(SCH_1):PAGE185',
 WATTAGE='1/16W',
 TOLERANCE='5%',
 MATERIAL='CHIP',
 PHYS_PAGE='210',
 XY='(-2675,7725)',
 ROT='0',
 VER='1',
 PACK_TYPE='0402LF',
 LOCATION='R8179',
 CDS_LIB='pure_quanta',
 CDS_PART_NAME='Q_RES_0402LF-0,5%,1/16W,CHIP,CS00002JB13',
 PART_NUMBER='CS00002JB13',
 VALUE='0',
 PRIM_FILE='./archive_libs/logical/q_res/chips/chips.prt';

PART_NAME
 R8180 'Q_RES_0402LF-1K,1%,1/16W,CHIP,CS21002FB06':;

SECTION_NUMBER 1
 '@T6G_MB_LIB.T6G(SCH_1):PAGE185_I54@PURE_QUANTA.Q_RES(CHIPS)':
 C_PATH='@t6g_mb_lib.t6g(sch_1):page185_i54@pure_quanta.q_res(chips)',
 P_PATH='@t6g_mb_lib.t6g(sch_1):page210_i54@pure_quanta.q_res(chips)',
 PATH='I54',
 DRAWING='@T6G_MB_LIB.T6G(SCH_1):PAGE185',
 WATTAGE='1/16W',
 TOLERANCE='1%',
 MATERIAL='CHIP',
 PHYS_PAGE='210',
 XY='(-2175,3750)',
 ROT='0',
 VER='1',
 PACK_TYPE='0402LF',
 LOCATION='R8180',
 CDS_LIB='pure_quanta',
 CDS_PART_NAME='Q_RES_0402LF-1K,1%,1/16W,CHIP,CS21002FB06',
 PART_NUMBER='CS21002FB06',
 VALUE='1K',
 PRIM_FILE='./archive_libs/logical/q_res/chips/chips.prt';

PART_NAME
 R8182 'Q_RES_0402LF-49.9,1%,1/16W,CHIP,CS04992FB07':;

SECTION_NUMBER 1
 '@T6G_MB_LIB.T6G(SCH_1):PAGE185_I42@PURE_QUANTA.Q_RES(CHIPS)':
 C_PATH='@t6g_mb_lib.t6g(sch_1):page185_i42@pure_quanta.q_res(chips)',
 P_PATH='@t6g_mb_lib.t6g(sch_1):page210_i42@pure_quanta.q_res(chips)',
 PATH='I42',
 DRAWING='@T6G_MB_LIB.T6G(SCH_1):PAGE185',
 WATTAGE='1/16W',
 TOLERANCE='1%',
 MATERIAL='CHIP',
 PHYS_PAGE='210',
 XY='(-2825,4025)',
 ROT='0',
 VER='1',
 PACK_TYPE='0402LF',
 LOCATION='R8182',
 CDS_LIB='pure_quanta',
 CDS_PART_NAME='Q_RES_0402LF-49.9,1%,1/16W,CHIP,CS04992FB07',
 PART_NUMBER='CS04992FB07',
 VALUE='49.9',
 PRIM_FILE='./archive_libs/logical/q_res/chips/chips.prt';

PART_NAME
 R8184 'Q_RES_0402LF-1K,1%,1/16W,CHIP,CS21002FB06':;

SECTION_NUMBER 1
 '@T6G_MB_LIB.T6G(SCH_1):PAGE185_I41@PURE_QUANTA.Q_RES(CHIPS)':
 C_PATH='@t6g_mb_lib.t6g(sch_1):page185_i41@pure_quanta.q_res(chips)',
 P_PATH='@t6g_mb_lib.t6g(sch_1):page210_i41@pure_quanta.q_res(chips)',
 PATH='I41',
 DRAWING='@T6G_MB_LIB.T6G(SCH_1):PAGE185',
 WATTAGE='1/16W',
 TOLERANCE='1%',
 MATERIAL='CHIP',
 PHYS_PAGE='210',
 XY='(-2850,4175)',
 ROT='0',
 VER='1',
 PACK_TYPE='0402LF',
 LOCATION='R8184',
 CDS_LIB='pure_quanta',
 CDS_PART_NAME='Q_RES_0402LF-1K,1%,1/16W,CHIP,CS21002FB06',
 PART_NUMBER='CS21002FB06',
 VALUE='1K',
 PRIM_FILE='./archive_libs/logical/q_res/chips/chips.prt';

PART_NAME
 R8219 'Q_RES_0402LF-1K,1%,1/16W,EMPTY,CS21002FB06':;

SECTION_NUMBER 1
 '@T6G_MB_LIB.T6G(SCH_1):PAGE192_I30@PURE_QUANTA.Q_RES(CHIPS)':
 C_PATH='@t6g_mb_lib.t6g(sch_1):page192_i30@pure_quanta.q_res(chips)',
 P_PATH='@t6g_mb_lib.t6g(sch_1):page217_i30@pure_quanta.q_res(chips)',
 PATH='I30',
 DRAWING='@T6G_MB_LIB.T6G(SCH_1):PAGE192',
 WATTAGE='1/16W',
 TOLERANCE='1%',
 MATERIAL='EMPTY',
 PHYS_PAGE='217',
 XY='(-4825,6125)',
 ROT='0',
 VER='2',
 PACK_TYPE='0402LF',
 LOCATION='R8219',
 CDS_LIB='pure_quanta',
 CDS_PART_NAME='Q_RES_0402LF-1K,1%,1/16W,EMPTY,CS21002FB06',
 PART_NUMBER='CS21002FB06',
 VALUE='1K',
 PRIM_FILE='./archive_libs/logical/q_res/chips/chips.prt';

PART_NAME
 R8220 'Q_RES_0402LF-1K,1%,1/16W,EMPTY,CS21002FB06':;

SECTION_NUMBER 1
 '@T6G_MB_LIB.T6G(SCH_1):PAGE192_I40@PURE_QUANTA.Q_RES(CHIPS)':
 C_PATH='@t6g_mb_lib.t6g(sch_1):page192_i40@pure_quanta.q_res(chips)',
 P_PATH='@t6g_mb_lib.t6g(sch_1):page217_i40@pure_quanta.q_res(chips)',
 PATH='I40',
 DRAWING='@T6G_MB_LIB.T6G(SCH_1):PAGE192',
 WATTAGE='1/16W',
 TOLERANCE='1%',
 MATERIAL='EMPTY',
 PHYS_PAGE='217',
 XY='(-4575,7100)',
 ROT='0',
 VER='2',
 PACK_TYPE='0402LF',
 LOCATION='R8220',
 CDS_LIB='pure_quanta',
 CDS_PART_NAME='Q_RES_0402LF-1K,1%,1/16W,EMPTY,CS21002FB06',
 PART_NUMBER='CS21002FB06',
 VALUE='1K',
 PRIM_FILE='./archive_libs/logical/q_res/chips/chips.prt';

PART_NAME
 R8222 'Q_RES_0402LF-1K,1%,1/16W,EMPTY,CS21002FB06':;

SECTION_NUMBER 1
 '@T6G_MB_LIB.T6G(SCH_1):PAGE192_I41@PURE_QUANTA.Q_RES(CHIPS)':
 C_PATH='@t6g_mb_lib.t6g(sch_1):page192_i41@pure_quanta.q_res(chips)',
 P_PATH='@t6g_mb_lib.t6g(sch_1):page217_i41@pure_quanta.q_res(chips)',
 PATH='I41',
 DRAWING='@T6G_MB_LIB.T6G(SCH_1):PAGE192',
 WATTAGE='1/16W',
 TOLERANCE='1%',
 MATERIAL='EMPTY',
 PHYS_PAGE='217',
 XY='(-4400,7100)',
 ROT='0',
 VER='2',
 PACK_TYPE='0402LF',
 LOCATION='R8222',
 CDS_LIB='pure_quanta',
 CDS_PART_NAME='Q_RES_0402LF-1K,1%,1/16W,EMPTY,CS21002FB06',
 PART_NUMBER='CS21002FB06',
 VALUE='1K',
 PRIM_FILE='./archive_libs/logical/q_res/chips/chips.prt';

PART_NAME
 R8224 'Q_RES_0402LF-0,5%,1/16W,CHIP,CS00002JB13':;

SECTION_NUMBER 1
 '@T6G_MB_LIB.T6G(SCH_1):PAGE192_I2@PURE_QUANTA.Q_RES(CHIPS)':
 C_PATH='@t6g_mb_lib.t6g(sch_1):page192_i2@pure_quanta.q_res(chips)',
 P_PATH='@t6g_mb_lib.t6g(sch_1):page217_i2@pure_quanta.q_res(chips)',
 PATH='I2',
 DRAWING='@T6G_MB_LIB.T6G(SCH_1):PAGE192',
 WATTAGE='1/16W',
 TOLERANCE='5%',
 MATERIAL='CHIP',
 PHYS_PAGE='217',
 XY='(-4700,2575)',
 ROT='0',
 VER='1',
 PACK_TYPE='0402LF',
 LOCATION='R8224',
 CDS_LIB='pure_quanta',
 CDS_PART_NAME='Q_RES_0402LF-0,5%,1/16W,CHIP,CS00002JB13',
 PART_NUMBER='CS00002JB13',
 VALUE='0',
 PRIM_FILE='./archive_libs/logical/q_res/chips/chips.prt';

PART_NAME
 R8225 'Q_RES_0402LF-1K,1%,1/16W,EMPTY,CS21002FB06':;

SECTION_NUMBER 1
 '@T6G_MB_LIB.T6G(SCH_1):PAGE192_I42@PURE_QUANTA.Q_RES(CHIPS)':
 C_PATH='@t6g_mb_lib.t6g(sch_1):page192_i42@pure_quanta.q_res(chips)',
 P_PATH='@t6g_mb_lib.t6g(sch_1):page217_i42@pure_quanta.q_res(chips)',
 PATH='I42',
 DRAWING='@T6G_MB_LIB.T6G(SCH_1):PAGE192',
 WATTAGE='1/16W',
 TOLERANCE='1%',
 MATERIAL='EMPTY',
 PHYS_PAGE='217',
 XY='(-4200,7100)',
 ROT='0',
 VER='2',
 PACK_TYPE='0402LF',
 LOCATION='R8225',
 CDS_LIB='pure_quanta',
 CDS_PART_NAME='Q_RES_0402LF-1K,1%,1/16W,EMPTY,CS21002FB06',
 PART_NUMBER='CS21002FB06',
 VALUE='1K',
 PRIM_FILE='./archive_libs/logical/q_res/chips/chips.prt';

PART_NAME
 R8233 'Q_RES_0402LF-1K,1%,1/16W,CHIP,CS21002FB06':;

SECTION_NUMBER 1
 '@T6G_MB_LIB.T6G(SCH_1):PAGE192_I89@PURE_QUANTA.Q_RES(CHIPS)':
 C_PATH='@t6g_mb_lib.t6g(sch_1):page192_i89@pure_quanta.q_res(chips)',
 P_PATH='@t6g_mb_lib.t6g(sch_1):page217_i89@pure_quanta.q_res(chips)',
 PATH='I89',
 DRAWING='@T6G_MB_LIB.T6G(SCH_1):PAGE192',
 WATTAGE='1/16W',
 TOLERANCE='1%',
 MATERIAL='CHIP',
 PHYS_PAGE='217',
 XY='(-2875,7375)',
 ROT='0',
 VER='1',
 PACK_TYPE='0402LF',
 LOCATION='R8233',
 CDS_LIB='pure_quanta',
 CDS_PART_NAME='Q_RES_0402LF-1K,1%,1/16W,CHIP,CS21002FB06',
 PART_NUMBER='CS21002FB06',
 VALUE='1K',
 PRIM_FILE='./archive_libs/logical/q_res/chips/chips.prt';

PART_NAME
 R8234 'Q_RES_0402LF-33,5%,1/16W,CHIP,CS03302JB10':;

SECTION_NUMBER 1
 '@T6G_MB_LIB.T6G(SCH_1):PAGE192_I88@PURE_QUANTA.Q_RES(CHIPS)':
 C_PATH='@t6g_mb_lib.t6g(sch_1):page192_i88@pure_quanta.q_res(chips)',
 P_PATH='@t6g_mb_lib.t6g(sch_1):page217_i88@pure_quanta.q_res(chips)',
 PATH='I88',
 DRAWING='@T6G_MB_LIB.T6G(SCH_1):PAGE192',
 WATTAGE='1/16W',
 TOLERANCE='5%',
 MATERIAL='CHIP',
 PHYS_PAGE='217',
 XY='(-2875,7225)',
 ROT='0',
 VER='1',
 PACK_TYPE='0402LF',
 LOCATION='R8234',
 CDS_LIB='pure_quanta',
 CDS_PART_NAME='Q_RES_0402LF-33,5%,1/16W,CHIP,CS03302JB10',
 PART_NUMBER='CS03302JB10',
 VALUE='33',
 PRIM_FILE='./archive_libs/logical/q_res/chips/chips.prt';

PART_NAME
 R8235 'Q_RES_0402LF-0,5%,1/16W,CHIP,CS00002JB13':;

SECTION_NUMBER 1
 '@T6G_MB_LIB.T6G(SCH_1):PAGE192_I87@PURE_QUANTA.Q_RES(CHIPS)':
 C_PATH='@t6g_mb_lib.t6g(sch_1):page192_i87@pure_quanta.q_res(chips)',
 P_PATH='@t6g_mb_lib.t6g(sch_1):page217_i87@pure_quanta.q_res(chips)',
 PATH='I87',
 DRAWING='@T6G_MB_LIB.T6G(SCH_1):PAGE192',
 WATTAGE='1/16W',
 TOLERANCE='5%',
 MATERIAL='CHIP',
 PHYS_PAGE='217',
 XY='(-2875,7075)',
 ROT='0',
 VER='1',
 PACK_TYPE='0402LF',
 LOCATION='R8235',
 CDS_LIB='pure_quanta',
 CDS_PART_NAME='Q_RES_0402LF-0,5%,1/16W,CHIP,CS00002JB13',
 PART_NUMBER='CS00002JB13',
 VALUE='0',
 PRIM_FILE='./archive_libs/logical/q_res/chips/chips.prt';

PART_NAME
 R8238 'Q_RES_0402LF-49.9,1%,1/16W,CHIP,CS04992FB07':;

SECTION_NUMBER 1
 '@T6G_MB_LIB.T6G(SCH_1):PAGE192_I82@PURE_QUANTA.Q_RES(CHIPS)':
 C_PATH='@t6g_mb_lib.t6g(sch_1):page192_i82@pure_quanta.q_res(chips)',
 P_PATH='@t6g_mb_lib.t6g(sch_1):page217_i82@pure_quanta.q_res(chips)',
 PATH='I82',
 DRAWING='@T6G_MB_LIB.T6G(SCH_1):PAGE192',
 WATTAGE='1/16W',
 TOLERANCE='1%',
 MATERIAL='CHIP',
 PHYS_PAGE='217',
 XY='(-2875,6475)',
 ROT='0',
 VER='1',
 PACK_TYPE='0402LF',
 LOCATION='R8238',
 CDS_LIB='pure_quanta',
 CDS_PART_NAME='Q_RES_0402LF-49.9,1%,1/16W,CHIP,CS04992FB07',
 PART_NUMBER='CS04992FB07',
 VALUE='49.9',
 PRIM_FILE='./archive_libs/logical/q_res/chips/chips.prt';

PART_NAME
 R8241 'Q_RES_0402LF-0,5%,1/16W,CHIP,CS00002JB13':;

SECTION_NUMBER 1
 '@T6G_MB_LIB.T6G(SCH_1):PAGE192_I64@PURE_QUANTA.Q_RES(CHIPS)':
 C_PATH='@t6g_mb_lib.t6g(sch_1):page192_i64@pure_quanta.q_res(chips)',
 P_PATH='@t6g_mb_lib.t6g(sch_1):page217_i64@pure_quanta.q_res(chips)',
 PATH='I64',
 DRAWING='@T6G_MB_LIB.T6G(SCH_1):PAGE192',
 WATTAGE='1/16W',
 TOLERANCE='5%',
 MATERIAL='CHIP',
 PHYS_PAGE='217',
 XY='(-2200,3225)',
 ROT='0',
 VER='1',
 PACK_TYPE='0402LF',
 LOCATION='R8241',
 CDS_LIB='pure_quanta',
 CDS_PART_NAME='Q_RES_0402LF-0,5%,1/16W,CHIP,CS00002JB13',
 PART_NUMBER='CS00002JB13',
 VALUE='0',
 PRIM_FILE='./archive_libs/logical/q_res/chips/chips.prt';

PART_NAME
 R8242 'Q_RES_0402LF-1K,1%,1/16W,CHIP,CS21002FB06':;

SECTION_NUMBER 1
 '@T6G_MB_LIB.T6G(SCH_1):PAGE192_I51@PURE_QUANTA.Q_RES(CHIPS)':
 C_PATH='@t6g_mb_lib.t6g(sch_1):page192_i51@pure_quanta.q_res(chips)',
 P_PATH='@t6g_mb_lib.t6g(sch_1):page217_i51@pure_quanta.q_res(chips)',
 PATH='I51',
 DRAWING='@T6G_MB_LIB.T6G(SCH_1):PAGE192',
 WATTAGE='1/16W',
 TOLERANCE='1%',
 MATERIAL='CHIP',
 PHYS_PAGE='217',
 XY='(-2775,2125)',
 ROT='0',
 VER='1',
 PACK_TYPE='0402LF',
 LOCATION='R8242',
 CDS_LIB='pure_quanta',
 CDS_PART_NAME='Q_RES_0402LF-1K,1%,1/16W,CHIP,CS21002FB06',
 PART_NUMBER='CS21002FB06',
 VALUE='1K',
 PRIM_FILE='./archive_libs/logical/q_res/chips/chips.prt';

PART_NAME
 R8243 'Q_RES_0402LF-33,5%,1/16W,CHIP,CS03302JB10':;

SECTION_NUMBER 1
 '@T6G_MB_LIB.T6G(SCH_1):PAGE192_I50@PURE_QUANTA.Q_RES(CHIPS)':
 C_PATH='@t6g_mb_lib.t6g(sch_1):page192_i50@pure_quanta.q_res(chips)',
 P_PATH='@t6g_mb_lib.t6g(sch_1):page217_i50@pure_quanta.q_res(chips)',
 PATH='I50',
 DRAWING='@T6G_MB_LIB.T6G(SCH_1):PAGE192',
 WATTAGE='1/16W',
 TOLERANCE='5%',
 MATERIAL='CHIP',
 PHYS_PAGE='217',
 XY='(-2775,1975)',
 ROT='0',
 VER='1',
 PACK_TYPE='0402LF',
 LOCATION='R8243',
 CDS_LIB='pure_quanta',
 CDS_PART_NAME='Q_RES_0402LF-33,5%,1/16W,CHIP,CS03302JB10',
 PART_NUMBER='CS03302JB10',
 VALUE='33',
 PRIM_FILE='./archive_libs/logical/q_res/chips/chips.prt';

PART_NAME
 R8247 'Q_RES_0402LF-1K,1%,1/16W,CHIP,CS21002FB06':;

SECTION_NUMBER 1
 '@T6G_MB_LIB.T6G(SCH_1):PAGE192_I66@PURE_QUANTA.Q_RES(CHIPS)':
 C_PATH='@t6g_mb_lib.t6g(sch_1):page192_i66@pure_quanta.q_res(chips)',
 P_PATH='@t6g_mb_lib.t6g(sch_1):page217_i66@pure_quanta.q_res(chips)',
 PATH='I66',
 DRAWING='@T6G_MB_LIB.T6G(SCH_1):PAGE192',
 WATTAGE='1/16W',
 TOLERANCE='1%',
 MATERIAL='CHIP',
 PHYS_PAGE='217',
 XY='(-2225,3525)',
 ROT='0',
 VER='1',
 PACK_TYPE='0402LF',
 LOCATION='R8247',
 CDS_LIB='pure_quanta',
 CDS_PART_NAME='Q_RES_0402LF-1K,1%,1/16W,CHIP,CS21002FB06',
 PART_NUMBER='CS21002FB06',
 VALUE='1K',
 PRIM_FILE='./archive_libs/logical/q_res/chips/chips.prt';

PART_NAME
 R8248 'Q_RES_0402LF-0,5%,1/16W,CHIP,CS00002JB13':;

SECTION_NUMBER 1
 '@T6G_MB_LIB.T6G(SCH_1):PAGE192_I84@PURE_QUANTA.Q_RES(CHIPS)':
 C_PATH='@t6g_mb_lib.t6g(sch_1):page192_i84@pure_quanta.q_res(chips)',
 P_PATH='@t6g_mb_lib.t6g(sch_1):page217_i84@pure_quanta.q_res(chips)',
 PATH='I84',
 DRAWING='@T6G_MB_LIB.T6G(SCH_1):PAGE192',
 WATTAGE='1/16W',
 TOLERANCE='5%',
 MATERIAL='CHIP',
 PHYS_PAGE='217',
 XY='(-2175,6075)',
 ROT='0',
 VER='1',
 PACK_TYPE='0402LF',
 LOCATION='R8248',
 CDS_LIB='pure_quanta',
 CDS_PART_NAME='Q_RES_0402LF-0,5%,1/16W,CHIP,CS00002JB13',
 PART_NUMBER='CS00002JB13',
 VALUE='0',
 PRIM_FILE='./archive_libs/logical/q_res/chips/chips.prt';

PART_NAME
 R8249 'Q_RES_0402LF-0,5%,1/16W,CHIP,CS00002JB13':;

SECTION_NUMBER 1
 '@T6G_MB_LIB.T6G(SCH_1):PAGE192_I81@PURE_QUANTA.Q_RES(CHIPS)':
 C_PATH='@t6g_mb_lib.t6g(sch_1):page192_i81@pure_quanta.q_res(chips)',
 P_PATH='@t6g_mb_lib.t6g(sch_1):page217_i81@pure_quanta.q_res(chips)',
 PATH='I81',
 DRAWING='@T6G_MB_LIB.T6G(SCH_1):PAGE192',
 WATTAGE='1/16W',
 TOLERANCE='5%',
 MATERIAL='CHIP',
 PHYS_PAGE='217',
 XY='(-2175,5925)',
 ROT='0',
 VER='1',
 PACK_TYPE='0402LF',
 LOCATION='R8249',
 CDS_LIB='pure_quanta',
 CDS_PART_NAME='Q_RES_0402LF-0,5%,1/16W,CHIP,CS00002JB13',
 PART_NUMBER='CS00002JB13',
 VALUE='0',
 PRIM_FILE='./archive_libs/logical/q_res/chips/chips.prt';

PART_NAME
 R8250 'Q_RES_0402LF-33,5%,1/16W,CHIP,CS03302JB10':;

SECTION_NUMBER 1
 '@T6G_MB_LIB.T6G(SCH_1):PAGE192_I80@PURE_QUANTA.Q_RES(CHIPS)':
 C_PATH='@t6g_mb_lib.t6g(sch_1):page192_i80@pure_quanta.q_res(chips)',
 P_PATH='@t6g_mb_lib.t6g(sch_1):page217_i80@pure_quanta.q_res(chips)',
 PATH='I80',
 DRAWING='@T6G_MB_LIB.T6G(SCH_1):PAGE192',
 WATTAGE='1/16W',
 TOLERANCE='5%',
 MATERIAL='CHIP',
 PHYS_PAGE='217',
 XY='(-2175,5775)',
 ROT='0',
 VER='1',
 PACK_TYPE='0402LF',
 LOCATION='R8250',
 CDS_LIB='pure_quanta',
 CDS_PART_NAME='Q_RES_0402LF-33,5%,1/16W,CHIP,CS03302JB10',
 PART_NUMBER='CS03302JB10',
 VALUE='33',
 PRIM_FILE='./archive_libs/logical/q_res/chips/chips.prt';

PART_NAME
 R8252 'Q_RES_0402LF-1K,1%,1/16W,CHIP,CS21002FB06':;

SECTION_NUMBER 1
 '@T6G_MB_LIB.T6G(SCH_1):PAGE192_I71@PURE_QUANTA.Q_RES(CHIPS)':
 C_PATH='@t6g_mb_lib.t6g(sch_1):page192_i71@pure_quanta.q_res(chips)',
 P_PATH='@t6g_mb_lib.t6g(sch_1):page217_i71@pure_quanta.q_res(chips)',
 PATH='I71',
 DRAWING='@T6G_MB_LIB.T6G(SCH_1):PAGE192',
 WATTAGE='1/16W',
 TOLERANCE='1%',
 MATERIAL='CHIP',
 PHYS_PAGE='217',
 XY='(-1550,3100)',
 ROT='0',
 VER='1',
 PACK_TYPE='0402LF',
 LOCATION='R8252',
 CDS_LIB='pure_quanta',
 CDS_PART_NAME='Q_RES_0402LF-1K,1%,1/16W,CHIP,CS21002FB06',
 PART_NUMBER='CS21002FB06',
 VALUE='1K',
 PRIM_FILE='./archive_libs/logical/q_res/chips/chips.prt';

PART_NAME
 R8282 'Q_RES_0402LF-0,5%,1/16W,CHIP,CS00002JB13':;

SECTION_NUMBER 1
 '@T6G_MB_LIB.T6G(SCH_1):PAGE168_I2@PURE_QUANTA.Q_RES(CHIPS)':
 C_PATH='@t6g_mb_lib.t6g(sch_1):page168_i2@pure_quanta.q_res(chips)',
 P_PATH='@t6g_mb_lib.t6g(sch_1):page193_i2@pure_quanta.q_res(chips)',
 PATH='I2',
 DRAWING='@T6G_MB_LIB.T6G(SCH_1):PAGE168',
 WATTAGE='1/16W',
 TOLERANCE='5%',
 MATERIAL='CHIP',
 PHYS_PAGE='193',
 XY='(-8150,1825)',
 ROT='0',
 VER='1',
 PACK_TYPE='0402LF',
 LOCATION='R8282',
 CDS_LIB='pure_quanta',
 CDS_PART_NAME='Q_RES_0402LF-0,5%,1/16W,CHIP,CS00002JB13',
 PART_NUMBER='CS00002JB13',
 VALUE='0',
 PRIM_FILE='./archive_libs/logical/q_res/chips/chips.prt';

PART_NAME
 R8286 'Q_RES_0402LF-1K,1%,1/16W,EMPTY,CS21002FB06':;

SECTION_NUMBER 1
 '@T6G_MB_LIB.T6G(SCH_1):PAGE168_I6@PURE_QUANTA.Q_RES(CHIPS)':
 C_PATH='@t6g_mb_lib.t6g(sch_1):page168_i6@pure_quanta.q_res(chips)',
 P_PATH='@t6g_mb_lib.t6g(sch_1):page193_i6@pure_quanta.q_res(chips)',
 PATH='I6',
 DRAWING='@T6G_MB_LIB.T6G(SCH_1):PAGE168',
 WATTAGE='1/16W',
 TOLERANCE='1%',
 MATERIAL='EMPTY',
 PHYS_PAGE='193',
 XY='(-7850,5425)',
 ROT='0',
 VER='2',
 PACK_TYPE='0402LF',
 LOCATION='R8286',
 CDS_LIB='pure_quanta',
 CDS_PART_NAME='Q_RES_0402LF-1K,1%,1/16W,EMPTY,CS21002FB06',
 PART_NUMBER='CS21002FB06',
 VALUE='1K',
 PRIM_FILE='./archive_libs/logical/q_res/chips/chips.prt';

PART_NAME
 R8287 'Q_RES_0402LF-1K,1%,1/16W,EMPTY,CS21002FB06':;

SECTION_NUMBER 1
 '@T6G_MB_LIB.T6G(SCH_1):PAGE168_I69@PURE_QUANTA.Q_RES(CHIPS)':
 C_PATH='@t6g_mb_lib.t6g(sch_1):page168_i69@pure_quanta.q_res(chips)',
 P_PATH='@t6g_mb_lib.t6g(sch_1):page193_i69@pure_quanta.q_res(chips)',
 PATH='I69',
 DRAWING='@T6G_MB_LIB.T6G(SCH_1):PAGE168',
 WATTAGE='1/16W',
 TOLERANCE='1%',
 MATERIAL='EMPTY',
 PHYS_PAGE='193',
 XY='(-7550,6375)',
 ROT='0',
 VER='2',
 PACK_TYPE='0402LF',
 LOCATION='R8287',
 CDS_LIB='pure_quanta',
 CDS_PART_NAME='Q_RES_0402LF-1K,1%,1/16W,EMPTY,CS21002FB06',
 PART_NUMBER='CS21002FB06',
 VALUE='1K',
 PRIM_FILE='./archive_libs/logical/q_res/chips/chips.prt';

PART_NAME
 R8289 'Q_RES_0402LF-1K,1%,1/16W,EMPTY,CS21002FB06':;

SECTION_NUMBER 1
 '@T6G_MB_LIB.T6G(SCH_1):PAGE168_I70@PURE_QUANTA.Q_RES(CHIPS)':
 C_PATH='@t6g_mb_lib.t6g(sch_1):page168_i70@pure_quanta.q_res(chips)',
 P_PATH='@t6g_mb_lib.t6g(sch_1):page193_i70@pure_quanta.q_res(chips)',
 PATH='I70',
 DRAWING='@T6G_MB_LIB.T6G(SCH_1):PAGE168',
 WATTAGE='1/16W',
 TOLERANCE='1%',
 MATERIAL='EMPTY',
 PHYS_PAGE='193',
 XY='(-7250,6375)',
 ROT='0',
 VER='2',
 PACK_TYPE='0402LF',
 LOCATION='R8289',
 CDS_LIB='pure_quanta',
 CDS_PART_NAME='Q_RES_0402LF-1K,1%,1/16W,EMPTY,CS21002FB06',
 PART_NUMBER='CS21002FB06',
 VALUE='1K',
 PRIM_FILE='./archive_libs/logical/q_res/chips/chips.prt';

PART_NAME
 R8293 'Q_RES_0402LF-1K,1%,1/16W,EMPTY,CS21002FB06':;

SECTION_NUMBER 1
 '@T6G_MB_LIB.T6G(SCH_1):PAGE168_I71@PURE_QUANTA.Q_RES(CHIPS)':
 C_PATH='@t6g_mb_lib.t6g(sch_1):page168_i71@pure_quanta.q_res(chips)',
 P_PATH='@t6g_mb_lib.t6g(sch_1):page193_i71@pure_quanta.q_res(chips)',
 PATH='I71',
 DRAWING='@T6G_MB_LIB.T6G(SCH_1):PAGE168',
 WATTAGE='1/16W',
 TOLERANCE='1%',
 MATERIAL='EMPTY',
 PHYS_PAGE='193',
 XY='(-6975,6375)',
 ROT='0',
 VER='2',
 PACK_TYPE='0402LF',
 LOCATION='R8293',
 CDS_LIB='pure_quanta',
 CDS_PART_NAME='Q_RES_0402LF-1K,1%,1/16W,EMPTY,CS21002FB06',
 PART_NUMBER='CS21002FB06',
 VALUE='1K',
 PRIM_FILE='./archive_libs/logical/q_res/chips/chips.prt';

PART_NAME
 R8298 'Q_RES_0402LF-1K,1%,1/16W,CHIP,CS21002FB06':;

SECTION_NUMBER 1
 '@T6G_MB_LIB.T6G(SCH_1):PAGE168_I28@PURE_QUANTA.Q_RES(CHIPS)':
 C_PATH='@t6g_mb_lib.t6g(sch_1):page168_i28@pure_quanta.q_res(chips)',
 P_PATH='@t6g_mb_lib.t6g(sch_1):page193_i28@pure_quanta.q_res(chips)',
 PATH='I28',
 DRAWING='@T6G_MB_LIB.T6G(SCH_1):PAGE168',
 WATTAGE='1/16W',
 TOLERANCE='1%',
 MATERIAL='CHIP',
 PHYS_PAGE='193',
 XY='(-5900,1650)',
 ROT='0',
 VER='1',
 PACK_TYPE='0402LF',
 LOCATION='R8298',
 CDS_LIB='pure_quanta',
 CDS_PART_NAME='Q_RES_0402LF-1K,1%,1/16W,CHIP,CS21002FB06',
 PART_NUMBER='CS21002FB06',
 VALUE='1K',
 PRIM_FILE='./archive_libs/logical/q_res/chips/chips.prt';

PART_NAME
 R8299 'Q_RES_0402LF-33,5%,1/16W,CHIP,CS03302JB10':;

SECTION_NUMBER 1
 '@T6G_MB_LIB.T6G(SCH_1):PAGE168_I24@PURE_QUANTA.Q_RES(CHIPS)':
 C_PATH='@t6g_mb_lib.t6g(sch_1):page168_i24@pure_quanta.q_res(chips)',
 P_PATH='@t6g_mb_lib.t6g(sch_1):page193_i24@pure_quanta.q_res(chips)',
 PATH='I24',
 DRAWING='@T6G_MB_LIB.T6G(SCH_1):PAGE168',
 WATTAGE='1/16W',
 TOLERANCE='5%',
 MATERIAL='CHIP',
 PHYS_PAGE='193',
 XY='(-5900,1400)',
 ROT='0',
 VER='1',
 PACK_TYPE='0402LF',
 LOCATION='R8299',
 CDS_LIB='pure_quanta',
 CDS_PART_NAME='Q_RES_0402LF-33,5%,1/16W,CHIP,CS03302JB10',
 PART_NUMBER='CS03302JB10',
 VALUE='33',
 PRIM_FILE='./archive_libs/logical/q_res/chips/chips.prt';

PART_NAME
 R8300 'Q_RES_0402LF-1K,1%,1/16W,CHIP,CS21002FB06':;

SECTION_NUMBER 1
 '@T6G_MB_LIB.T6G(SCH_1):PAGE168_I82@PURE_QUANTA.Q_RES(CHIPS)':
 C_PATH='@t6g_mb_lib.t6g(sch_1):page168_i82@pure_quanta.q_res(chips)',
 P_PATH='@t6g_mb_lib.t6g(sch_1):page193_i82@pure_quanta.q_res(chips)',
 PATH='I82',
 DRAWING='@T6G_MB_LIB.T6G(SCH_1):PAGE168',
 WATTAGE='1/16W',
 TOLERANCE='1%',
 MATERIAL='CHIP',
 PHYS_PAGE='193',
 XY='(-5700,6775)',
 ROT='0',
 VER='1',
 PACK_TYPE='0402LF',
 LOCATION='R8300',
 CDS_LIB='pure_quanta',
 CDS_PART_NAME='Q_RES_0402LF-1K,1%,1/16W,CHIP,CS21002FB06',
 PART_NUMBER='CS21002FB06',
 VALUE='1K',
 PRIM_FILE='./archive_libs/logical/q_res/chips/chips.prt';

PART_NAME
 R8301 'Q_RES_0402LF-0,5%,1/16W,CHIP,CS00002JB13':;

SECTION_NUMBER 1
 '@T6G_MB_LIB.T6G(SCH_1):PAGE168_I58@PURE_QUANTA.Q_RES(CHIPS)':
 C_PATH='@t6g_mb_lib.t6g(sch_1):page168_i58@pure_quanta.q_res(chips)',
 P_PATH='@t6g_mb_lib.t6g(sch_1):page193_i58@pure_quanta.q_res(chips)',
 PATH='I58',
 DRAWING='@T6G_MB_LIB.T6G(SCH_1):PAGE168',
 WATTAGE='1/16W',
 TOLERANCE='5%',
 MATERIAL='CHIP',
 PHYS_PAGE='193',
 XY='(-5550,2500)',
 ROT='0',
 VER='1',
 PACK_TYPE='0402LF',
 LOCATION='R8301',
 CDS_LIB='pure_quanta',
 CDS_PART_NAME='Q_RES_0402LF-0,5%,1/16W,CHIP,CS00002JB13',
 PART_NUMBER='CS00002JB13',
 VALUE='0',
 PRIM_FILE='./archive_libs/logical/q_res/chips/chips.prt';

PART_NAME
 R8304 'Q_RES_0402LF-49.9,1%,1/16W,CHIP,CS04992FB07':;

SECTION_NUMBER 1
 '@T6G_MB_LIB.T6G(SCH_1):PAGE168_I87@PURE_QUANTA.Q_RES(CHIPS)':
 C_PATH='@t6g_mb_lib.t6g(sch_1):page168_i87@pure_quanta.q_res(chips)',
 P_PATH='@t6g_mb_lib.t6g(sch_1):page193_i87@pure_quanta.q_res(chips)',
 PATH='I87',
 DRAWING='@T6G_MB_LIB.T6G(SCH_1):PAGE168',
 WATTAGE='1/16W',
 TOLERANCE='1%',
 MATERIAL='CHIP',
 PHYS_PAGE='193',
 XY='(-5600,5750)',
 ROT='0',
 VER='1',
 PACK_TYPE='0402LF',
 LOCATION='R8304',
 CDS_LIB='pure_quanta',
 CDS_PART_NAME='Q_RES_0402LF-49.9,1%,1/16W,CHIP,CS04992FB07',
 PART_NUMBER='CS04992FB07',
 VALUE='49.9',
 PRIM_FILE='./archive_libs/logical/q_res/chips/chips.prt';

PART_NAME
 R8305 'Q_RES_0402LF-0,5%,1/16W,CHIP,CS00002JB13':;

SECTION_NUMBER 1
 '@T6G_MB_LIB.T6G(SCH_1):PAGE28_I229@PURE_QUANTA.Q_RES(CHIPS)':
 C_PATH='@t6g_mb_lib.t6g(sch_1):page28_i229@pure_quanta.q_res(chips)',
 P_PATH='@t6g_mb_lib.t6g(sch_1):page28_i229@pure_quanta.q_res(chips)',
 PATH='I229',
 DRAWING='@T6G_MB_LIB.T6G(SCH_1):PAGE28',
 SEC_TYPE='0402LF',
 WATTAGE='1/16W',
 TOLERANCE='5%',
 MATERIAL='CHIP',
 PHYS_PAGE='28',
 XY='(-2000,10775)',
 ROT='0',
 VER='1',
 PACK_TYPE='0402LF',
 LOCATION='R8305',
 SEC='1',
 CDS_LIB='pure_quanta',
 CDS_PART_NAME='Q_RES_0402LF-0,5%,1/16W,CHIP,CS00002JB13',
 PART_NUMBER='CS00002JB13',
 VALUE='0',
 PRIM_FILE='./archive_libs/logical/q_res/chips/chips.prt';

PART_NAME
 R8306 'Q_RES_0402LF-0,5%,1/16W,CHIP,CS00002JB13':;

SECTION_NUMBER 1
 '@T6G_MB_LIB.T6G(SCH_1):PAGE28_I228@PURE_QUANTA.Q_RES(CHIPS)':
 C_PATH='@t6g_mb_lib.t6g(sch_1):page28_i228@pure_quanta.q_res(chips)',
 P_PATH='@t6g_mb_lib.t6g(sch_1):page28_i228@pure_quanta.q_res(chips)',
 PATH='I228',
 DRAWING='@T6G_MB_LIB.T6G(SCH_1):PAGE28',
 SEC_TYPE='0402LF',
 WATTAGE='1/16W',
 TOLERANCE='5%',
 MATERIAL='CHIP',
 PHYS_PAGE='28',
 XY='(-2000,10725)',
 ROT='0',
 VER='1',
 PACK_TYPE='0402LF',
 LOCATION='R8306',
 SEC='1',
 CDS_LIB='pure_quanta',
 CDS_PART_NAME='Q_RES_0402LF-0,5%,1/16W,CHIP,CS00002JB13',
 PART_NUMBER='CS00002JB13',
 VALUE='0',
 PRIM_FILE='./archive_libs/logical/q_res/chips/chips.prt';

PART_NAME
 R8308 'Q_RES_0402LF-0,5%,1/16W,CHIP,CS00002JB13':;

SECTION_NUMBER 1
 '@T6G_MB_LIB.T6G(SCH_1):PAGE168_I85@PURE_QUANTA.Q_RES(CHIPS)':
 C_PATH='@t6g_mb_lib.t6g(sch_1):page168_i85@pure_quanta.q_res(chips)',
 P_PATH='@t6g_mb_lib.t6g(sch_1):page193_i85@pure_quanta.q_res(chips)',
 PATH='I85',
 DRAWING='@T6G_MB_LIB.T6G(SCH_1):PAGE168',
 WATTAGE='1/16W',
 TOLERANCE='5%',
 MATERIAL='CHIP',
 PHYS_PAGE='193',
 XY='(-5500,5350)',
 ROT='0',
 VER='1',
 PACK_TYPE='0402LF',
 LOCATION='R8308',
 CDS_LIB='pure_quanta',
 CDS_PART_NAME='Q_RES_0402LF-0,5%,1/16W,CHIP,CS00002JB13',
 PART_NUMBER='CS00002JB13',
 VALUE='0',
 PRIM_FILE='./archive_libs/logical/q_res/chips/chips.prt';

PART_NAME
 R8309 'Q_RES_0402LF-0,5%,1/16W,CHIP,CS00002JB13':;

SECTION_NUMBER 1
 '@T6G_MB_LIB.T6G(SCH_1):PAGE168_I84@PURE_QUANTA.Q_RES(CHIPS)':
 C_PATH='@t6g_mb_lib.t6g(sch_1):page168_i84@pure_quanta.q_res(chips)',
 P_PATH='@t6g_mb_lib.t6g(sch_1):page193_i84@pure_quanta.q_res(chips)',
 PATH='I84',
 DRAWING='@T6G_MB_LIB.T6G(SCH_1):PAGE168',
 WATTAGE='1/16W',
 TOLERANCE='5%',
 MATERIAL='CHIP',
 PHYS_PAGE='193',
 XY='(-5500,5200)',
 ROT='0',
 VER='1',
 PACK_TYPE='0402LF',
 LOCATION='R8309',
 CDS_LIB='pure_quanta',
 CDS_PART_NAME='Q_RES_0402LF-0,5%,1/16W,CHIP,CS00002JB13',
 PART_NUMBER='CS00002JB13',
 VALUE='0',
 PRIM_FILE='./archive_libs/logical/q_res/chips/chips.prt';

PART_NAME
 R8310 'Q_RES_0402LF-33,5%,1/16W,CHIP,CS03302JB10':;

SECTION_NUMBER 1
 '@T6G_MB_LIB.T6G(SCH_1):PAGE168_I83@PURE_QUANTA.Q_RES(CHIPS)':
 C_PATH='@t6g_mb_lib.t6g(sch_1):page168_i83@pure_quanta.q_res(chips)',
 P_PATH='@t6g_mb_lib.t6g(sch_1):page193_i83@pure_quanta.q_res(chips)',
 PATH='I83',
 DRAWING='@T6G_MB_LIB.T6G(SCH_1):PAGE168',
 WATTAGE='1/16W',
 TOLERANCE='5%',
 MATERIAL='CHIP',
 PHYS_PAGE='193',
 XY='(-5500,5050)',
 ROT='0',
 VER='1',
 PACK_TYPE='0402LF',
 LOCATION='R8310',
 CDS_LIB='pure_quanta',
 CDS_PART_NAME='Q_RES_0402LF-33,5%,1/16W,CHIP,CS03302JB10',
 PART_NUMBER='CS03302JB10',
 VALUE='33',
 PRIM_FILE='./archive_libs/logical/q_res/chips/chips.prt';

PART_NAME
 R8311 'Q_RES_0402LF-33,5%,1/16W,CHIP,CS03302JB10':;

SECTION_NUMBER 1
 '@T6G_MB_LIB.T6G(SCH_1):PAGE168_I89@PURE_QUANTA.Q_RES(CHIPS)':
 C_PATH='@t6g_mb_lib.t6g(sch_1):page168_i89@pure_quanta.q_res(chips)',
 P_PATH='@t6g_mb_lib.t6g(sch_1):page193_i89@pure_quanta.q_res(chips)',
 PATH='I89',
 DRAWING='@T6G_MB_LIB.T6G(SCH_1):PAGE168',
 WATTAGE='1/16W',
 TOLERANCE='5%',
 MATERIAL='CHIP',
 PHYS_PAGE='193',
 XY='(-5475,6500)',
 ROT='0',
 VER='1',
 PACK_TYPE='0402LF',
 LOCATION='R8311',
 CDS_LIB='pure_quanta',
 CDS_PART_NAME='Q_RES_0402LF-33,5%,1/16W,CHIP,CS03302JB10',
 PART_NUMBER='CS03302JB10',
 VALUE='33',
 PRIM_FILE='./archive_libs/logical/q_res/chips/chips.prt';

PART_NAME
 R8312 'Q_RES_0402LF-0,5%,1/16W,CHIP,CS00002JB13':;

SECTION_NUMBER 1
 '@T6G_MB_LIB.T6G(SCH_1):PAGE168_I88@PURE_QUANTA.Q_RES(CHIPS)':
 C_PATH='@t6g_mb_lib.t6g(sch_1):page168_i88@pure_quanta.q_res(chips)',
 P_PATH='@t6g_mb_lib.t6g(sch_1):page193_i88@pure_quanta.q_res(chips)',
 PATH='I88',
 DRAWING='@T6G_MB_LIB.T6G(SCH_1):PAGE168',
 WATTAGE='1/16W',
 TOLERANCE='5%',
 MATERIAL='CHIP',
 PHYS_PAGE='193',
 XY='(-5475,6350)',
 ROT='0',
 VER='1',
 PACK_TYPE='0402LF',
 LOCATION='R8312',
 CDS_LIB='pure_quanta',
 CDS_PART_NAME='Q_RES_0402LF-0,5%,1/16W,CHIP,CS00002JB13',
 PART_NUMBER='CS00002JB13',
 VALUE='0',
 PRIM_FILE='./archive_libs/logical/q_res/chips/chips.prt';

PART_NAME
 R8313 'Q_RES_0402LF-1K,1%,1/16W,CHIP,CS21002FB06':;

SECTION_NUMBER 1
 '@T6G_MB_LIB.T6G(SCH_1):PAGE168_I54@PURE_QUANTA.Q_RES(CHIPS)':
 C_PATH='@t6g_mb_lib.t6g(sch_1):page168_i54@pure_quanta.q_res(chips)',
 P_PATH='@t6g_mb_lib.t6g(sch_1):page193_i54@pure_quanta.q_res(chips)',
 PATH='I54',
 DRAWING='@T6G_MB_LIB.T6G(SCH_1):PAGE168',
 WATTAGE='1/16W',
 TOLERANCE='1%',
 MATERIAL='CHIP',
 PHYS_PAGE='193',
 XY='(-5000,2375)',
 ROT='0',
 VER='1',
 PACK_TYPE='0402LF',
 LOCATION='R8313',
 CDS_LIB='pure_quanta',
 CDS_PART_NAME='Q_RES_0402LF-1K,1%,1/16W,CHIP,CS21002FB06',
 PART_NUMBER='CS21002FB06',
 VALUE='1K',
 PRIM_FILE='./archive_libs/logical/q_res/chips/chips.prt';

PART_NAME
 R8317 'Q_RES_0402LF-1K,1%,1/16W,CHIP,CS21002FB06':;

SECTION_NUMBER 1
 '@T6G_MB_LIB.T6G(SCH_1):PAGE168_I42@PURE_QUANTA.Q_RES(CHIPS)':
 C_PATH='@t6g_mb_lib.t6g(sch_1):page168_i42@pure_quanta.q_res(chips)',
 P_PATH='@t6g_mb_lib.t6g(sch_1):page193_i42@pure_quanta.q_res(chips)',
 PATH='I42',
 DRAWING='@T6G_MB_LIB.T6G(SCH_1):PAGE168',
 WATTAGE='1/16W',
 TOLERANCE='1%',
 MATERIAL='CHIP',
 PHYS_PAGE='193',
 XY='(-5700,2800)',
 ROT='0',
 VER='1',
 PACK_TYPE='0402LF',
 LOCATION='R8317',
 CDS_LIB='pure_quanta',
 CDS_PART_NAME='Q_RES_0402LF-1K,1%,1/16W,CHIP,CS21002FB06',
 PART_NUMBER='CS21002FB06',
 VALUE='1K',
 PRIM_FILE='./archive_libs/logical/q_res/chips/chips.prt';

PART_NAME
 R8350 'Q_RES_0402LF-0,5%,1/16W,CHIP,CS00002JB13':;

SECTION_NUMBER 1
 '@T6G_MB_LIB.T6G(SCH_1):PAGE55_I397@PURE_QUANTA.Q_RES(CHIPS)':
 C_PATH='@t6g_mb_lib.t6g(sch_1):page55_i397@pure_quanta.q_res(chips)',
 P_PATH='@t6g_mb_lib.t6g(sch_1):page55_i397@pure_quanta.q_res(chips)',
 PATH='I397',
 DRAWING='@T6G_MB_LIB.T6G(SCH_1):PAGE55',
 WATTAGE='1/16W',
 TOLERANCE='5%',
 MATERIAL='CHIP',
 PHYS_PAGE='55',
 XY='(-2000,3875)',
 ROT='0',
 VER='1',
 PACK_TYPE='0402LF',
 LOCATION='R8350',
 CDS_LIB='pure_quanta',
 CDS_PART_NAME='Q_RES_0402LF-0,5%,1/16W,CHIP,CS00002JB13',
 PART_NUMBER='CS00002JB13',
 VALUE='0',
 PRIM_FILE='./archive_libs/logical/q_res/chips/chips.prt';

PART_NAME
 R8351 'Q_RES_0402LF-0,5%,1/16W,CHIP,CS00002JB13':;

SECTION_NUMBER 1
 '@T6G_MB_LIB.T6G(SCH_1):PAGE55_I394@PURE_QUANTA.Q_RES(CHIPS)':
 C_PATH='@t6g_mb_lib.t6g(sch_1):page55_i394@pure_quanta.q_res(chips)',
 P_PATH='@t6g_mb_lib.t6g(sch_1):page55_i394@pure_quanta.q_res(chips)',
 PATH='I394',
 DRAWING='@T6G_MB_LIB.T6G(SCH_1):PAGE55',
 WATTAGE='1/16W',
 TOLERANCE='5%',
 MATERIAL='CHIP',
 PHYS_PAGE='55',
 XY='(-2000,3825)',
 ROT='0',
 VER='1',
 PACK_TYPE='0402LF',
 LOCATION='R8351',
 CDS_LIB='pure_quanta',
 CDS_PART_NAME='Q_RES_0402LF-0,5%,1/16W,CHIP,CS00002JB13',
 PART_NUMBER='CS00002JB13',
 VALUE='0',
 PRIM_FILE='./archive_libs/logical/q_res/chips/chips.prt';

PART_NAME
 R8380 'Q_RES_0402LF-1K,1%,1/16W,CHIP,CS21002FB06':;

SECTION_NUMBER 1
 '@T6G_MB_LIB.T6G(SCH_1):PAGE199_I37@PURE_QUANTA.Q_RES(CHIPS)':
 C_PATH='@t6g_mb_lib.t6g(sch_1):page199_i37@pure_quanta.q_res(chips)',
 P_PATH='@t6g_mb_lib.t6g(sch_1):page224_i37@pure_quanta.q_res(chips)',
 PATH='I37',
 DRAWING='@T6G_MB_LIB.T6G(SCH_1):PAGE199',
 WATTAGE='1/16W',
 TOLERANCE='1%',
 MATERIAL='CHIP',
 PHYS_PAGE='224',
 XY='(-6200,6400)',
 ROT='0',
 VER='1',
 PACK_TYPE='0402LF',
 LOCATION='R8380',
 CDS_LIB='pure_quanta',
 CDS_PART_NAME='Q_RES_0402LF-1K,1%,1/16W,CHIP,CS21002FB06',
 PART_NUMBER='CS21002FB06',
 VALUE='1K',
 PRIM_FILE='./archive_libs/logical/q_res/chips/chips.prt';

PART_NAME
 R8381 'Q_RES_0402LF-0,5%,1/16W,CHIP,CS00002JB13':;

SECTION_NUMBER 1
 '@T6G_MB_LIB.T6G(SCH_1):PAGE199_I40@PURE_QUANTA.Q_RES(CHIPS)':
 C_PATH='@t6g_mb_lib.t6g(sch_1):page199_i40@pure_quanta.q_res(chips)',
 P_PATH='@t6g_mb_lib.t6g(sch_1):page224_i40@pure_quanta.q_res(chips)',
 PATH='I40',
 DRAWING='@T6G_MB_LIB.T6G(SCH_1):PAGE199',
 WATTAGE='1/16W',
 TOLERANCE='5%',
 MATERIAL='CHIP',
 PHYS_PAGE='224',
 XY='(-6050,4975)',
 ROT='0',
 VER='1',
 PACK_TYPE='0402LF',
 LOCATION='R8381',
 CDS_LIB='pure_quanta',
 CDS_PART_NAME='Q_RES_0402LF-0,5%,1/16W,CHIP,CS00002JB13',
 PART_NUMBER='CS00002JB13',
 VALUE='0',
 PRIM_FILE='./archive_libs/logical/q_res/chips/chips.prt';

PART_NAME
 R8382 'Q_RES_0402LF-0,5%,1/16W,CHIP,CS00002JB13':;

SECTION_NUMBER 1
 '@T6G_MB_LIB.T6G(SCH_1):PAGE199_I39@PURE_QUANTA.Q_RES(CHIPS)':
 C_PATH='@t6g_mb_lib.t6g(sch_1):page199_i39@pure_quanta.q_res(chips)',
 P_PATH='@t6g_mb_lib.t6g(sch_1):page224_i39@pure_quanta.q_res(chips)',
 PATH='I39',
 DRAWING='@T6G_MB_LIB.T6G(SCH_1):PAGE199',
 WATTAGE='1/16W',
 TOLERANCE='5%',
 MATERIAL='CHIP',
 PHYS_PAGE='224',
 XY='(-6050,4825)',
 ROT='0',
 VER='1',
 PACK_TYPE='0402LF',
 LOCATION='R8382',
 CDS_LIB='pure_quanta',
 CDS_PART_NAME='Q_RES_0402LF-0,5%,1/16W,CHIP,CS00002JB13',
 PART_NUMBER='CS00002JB13',
 VALUE='0',
 PRIM_FILE='./archive_libs/logical/q_res/chips/chips.prt';

PART_NAME
 R8383 'Q_RES_0402LF-33,5%,1/16W,CHIP,CS03302JB10':;

SECTION_NUMBER 1
 '@T6G_MB_LIB.T6G(SCH_1):PAGE199_I38@PURE_QUANTA.Q_RES(CHIPS)':
 C_PATH='@t6g_mb_lib.t6g(sch_1):page199_i38@pure_quanta.q_res(chips)',
 P_PATH='@t6g_mb_lib.t6g(sch_1):page224_i38@pure_quanta.q_res(chips)',
 PATH='I38',
 DRAWING='@T6G_MB_LIB.T6G(SCH_1):PAGE199',
 WATTAGE='1/16W',
 TOLERANCE='5%',
 MATERIAL='CHIP',
 PHYS_PAGE='224',
 XY='(-6050,4675)',
 ROT='0',
 VER='1',
 PACK_TYPE='0402LF',
 LOCATION='R8383',
 CDS_LIB='pure_quanta',
 CDS_PART_NAME='Q_RES_0402LF-33,5%,1/16W,CHIP,CS03302JB10',
 PART_NUMBER='CS03302JB10',
 VALUE='33',
 PRIM_FILE='./archive_libs/logical/q_res/chips/chips.prt';

PART_NAME
 R8385 'Q_RES_0402LF-0,5%,1/16W,CHIP,CS00002JB13':;

SECTION_NUMBER 1
 '@T6G_MB_LIB.T6G(SCH_1):PAGE199_I43@PURE_QUANTA.Q_RES(CHIPS)':
 C_PATH='@t6g_mb_lib.t6g(sch_1):page199_i43@pure_quanta.q_res(chips)',
 P_PATH='@t6g_mb_lib.t6g(sch_1):page224_i43@pure_quanta.q_res(chips)',
 PATH='I43',
 DRAWING='@T6G_MB_LIB.T6G(SCH_1):PAGE199',
 WATTAGE='1/16W',
 TOLERANCE='5%',
 MATERIAL='CHIP',
 PHYS_PAGE='224',
 XY='(-5975,6125)',
 ROT='0',
 VER='1',
 PACK_TYPE='0402LF',
 LOCATION='R8385',
 CDS_LIB='pure_quanta',
 CDS_PART_NAME='Q_RES_0402LF-0,5%,1/16W,CHIP,CS00002JB13',
 PART_NUMBER='CS00002JB13',
 VALUE='0',
 PRIM_FILE='./archive_libs/logical/q_res/chips/chips.prt';

PART_NAME
 R8386 'Q_RES_0402LF-0,5%,1/16W,CHIP,CS00002JB13':;

SECTION_NUMBER 1
 '@T6G_MB_LIB.T6G(SCH_1):PAGE199_I42@PURE_QUANTA.Q_RES(CHIPS)':
 C_PATH='@t6g_mb_lib.t6g(sch_1):page199_i42@pure_quanta.q_res(chips)',
 P_PATH='@t6g_mb_lib.t6g(sch_1):page224_i42@pure_quanta.q_res(chips)',
 PATH='I42',
 DRAWING='@T6G_MB_LIB.T6G(SCH_1):PAGE199',
 WATTAGE='1/16W',
 TOLERANCE='5%',
 MATERIAL='CHIP',
 PHYS_PAGE='224',
 XY='(-5975,5975)',
 ROT='0',
 VER='1',
 PACK_TYPE='0402LF',
 LOCATION='R8386',
 CDS_LIB='pure_quanta',
 CDS_PART_NAME='Q_RES_0402LF-0,5%,1/16W,CHIP,CS00002JB13',
 PART_NUMBER='CS00002JB13',
 VALUE='0',
 PRIM_FILE='./archive_libs/logical/q_res/chips/chips.prt';

PART_NAME
 R8413 'Q_RES_0402LF-100K,1%,1/16W,CHIP,CS41002FB09':;

SECTION_NUMBER 1
 '@T6G_MB_LIB.T6G(SCH_1):PAGE341_I33@PURE_QUANTA.Q_RES(CHIPS)':
 C_PATH='@t6g_mb_lib.t6g(sch_1):page341_i33@pure_quanta.q_res(chips)',
 P_PATH='@t6g_mb_lib.t6g(sch_1):page137_i33@pure_quanta.q_res(chips)',
 PATH='I33',
 DRAWING='@T6G_MB_LIB.T6G(SCH_1):PAGE341',
 WATTAGE='1/16W',
 TOLERANCE='1%',
 MATERIAL='CHIP',
 PHYS_PAGE='137',
 XY='(775,2550)',
 ROT='0',
 VER='1',
 PACK_TYPE='0402LF',
 LOCATION='R8413',
 CDS_LIB='pure_quanta',
 CDS_PART_NAME='Q_RES_0402LF-100K,1%,1/16W,CHIP,CS41002FB09',
 PART_NUMBER='CS41002FB09',
 VALUE='100K',
 PRIM_FILE='./archive_libs/logical/q_res/chips/chips.prt';

PART_NAME
 R8420 'Q_RES_0402LF-1K,1%,1/16W,CHIP,CS21002FB06':;

SECTION_NUMBER 1
 '@T6G_MB_LIB.T6G(SCH_1):PAGE335_I22@PURE_QUANTA.Q_RES(CHIPS)':
 C_PATH='@t6g_mb_lib.t6g(sch_1):page335_i22@pure_quanta.q_res(chips)',
 P_PATH='@t6g_mb_lib.t6g(sch_1):page131_i22@pure_quanta.q_res(chips)',
 PATH='I22',
 DRAWING='@T6G_MB_LIB.T6G(SCH_1):PAGE335',
 WATTAGE='1/16W',
 TOLERANCE='1%',
 MATERIAL='CHIP',
 PHYS_PAGE='131',
 XY='(-750,1975)',
 ROT='0',
 VER='1',
 PACK_TYPE='0402LF',
 LOCATION='R8420',
 CDS_LIB='pure_quanta',
 CDS_PART_NAME='Q_RES_0402LF-1K,1%,1/16W,CHIP,CS21002FB06',
 PART_NUMBER='CS21002FB06',
 VALUE='1K',
 PRIM_FILE='./archive_libs/logical/q_res/chips/chips.prt';

PART_NAME
 R8421 'Q_RES_0402LF-10K,1%,1/16W,CHIP,CS31002FB08':;

SECTION_NUMBER 1
 '@T6G_MB_LIB.T6G(SCH_1):PAGE335_I21@PURE_QUANTA.Q_RES(CHIPS)':
 C_PATH='@t6g_mb_lib.t6g(sch_1):page335_i21@pure_quanta.q_res(chips)',
 P_PATH='@t6g_mb_lib.t6g(sch_1):page131_i21@pure_quanta.q_res(chips)',
 PATH='I21',
 DRAWING='@T6G_MB_LIB.T6G(SCH_1):PAGE335',
 WATTAGE='1/16W',
 TOLERANCE='1%',
 MATERIAL='CHIP',
 PHYS_PAGE='131',
 XY='(-750,1800)',
 ROT='0',
 VER='1',
 PACK_TYPE='0402LF',
 LOCATION='R8421',
 CDS_LIB='pure_quanta',
 CDS_PART_NAME='Q_RES_0402LF-10K,1%,1/16W,CHIP,CS31002FB08',
 PART_NUMBER='CS31002FB08',
 VALUE='10K',
 PRIM_FILE='./archive_libs/logical/q_res/chips/chips.prt';

PART_NAME
 R8422 'Q_RES_0402LF-10K,1%,1/16W,CHIP,CS31002FB08':;

SECTION_NUMBER 1
 '@T6G_MB_LIB.T6G(SCH_1):PAGE335_I19@PURE_QUANTA.Q_RES(CHIPS)':
 C_PATH='@t6g_mb_lib.t6g(sch_1):page335_i19@pure_quanta.q_res(chips)',
 P_PATH='@t6g_mb_lib.t6g(sch_1):page131_i19@pure_quanta.q_res(chips)',
 PATH='I19',
 DRAWING='@T6G_MB_LIB.T6G(SCH_1):PAGE335',
 WATTAGE='1/16W',
 TOLERANCE='1%',
 MATERIAL='CHIP',
 PHYS_PAGE='131',
 XY='(-750,1450)',
 ROT='0',
 VER='1',
 PACK_TYPE='0402LF',
 LOCATION='R8422',
 CDS_LIB='pure_quanta',
 CDS_PART_NAME='Q_RES_0402LF-10K,1%,1/16W,CHIP,CS31002FB08',
 PART_NUMBER='CS31002FB08',
 VALUE='10K',
 PRIM_FILE='./archive_libs/logical/q_res/chips/chips.prt';

PART_NAME
 R8423 'Q_RES_0402LF-1K,1%,1/16W,CHIP,CS21002FB06':;

SECTION_NUMBER 1
 '@T6G_MB_LIB.T6G(SCH_1):PAGE335_I20@PURE_QUANTA.Q_RES(CHIPS)':
 C_PATH='@t6g_mb_lib.t6g(sch_1):page335_i20@pure_quanta.q_res(chips)',
 P_PATH='@t6g_mb_lib.t6g(sch_1):page131_i20@pure_quanta.q_res(chips)',
 PATH='I20',
 DRAWING='@T6G_MB_LIB.T6G(SCH_1):PAGE335',
 WATTAGE='1/16W',
 TOLERANCE='1%',
 MATERIAL='CHIP',
 PHYS_PAGE='131',
 XY='(-750,1625)',
 ROT='0',
 VER='1',
 PACK_TYPE='0402LF',
 LOCATION='R8423',
 CDS_LIB='pure_quanta',
 CDS_PART_NAME='Q_RES_0402LF-1K,1%,1/16W,CHIP,CS21002FB06',
 PART_NUMBER='CS21002FB06',
 VALUE='1K',
 PRIM_FILE='./archive_libs/logical/q_res/chips/chips.prt';

PART_NAME
 R8458 'Q_RES_0402LF-0,5%,1/16W,EMPTY,CS00002JB13':;

SECTION_NUMBER 1
 '@T6G_MB_LIB.T6G(SCH_1):PAGE182_I9@PURE_QUANTA.Q_RES(CHIPS)':
 C_PATH='@t6g_mb_lib.t6g(sch_1):page182_i9@pure_quanta.q_res(chips)',
 P_PATH='@t6g_mb_lib.t6g(sch_1):page207_i9@pure_quanta.q_res(chips)',
 PATH='I9',
 DRAWING='@T6G_MB_LIB.T6G(SCH_1):PAGE182',
 WATTAGE='1/16W',
 TOLERANCE='5%',
 MATERIAL='EMPTY',
 PHYS_PAGE='207',
 XY='(-6200,1725)',
 ROT='0',
 VER='1',
 PACK_TYPE='0402LF',
 LOCATION='R8458',
 CDS_LIB='pure_quanta',
 CDS_PART_NAME='Q_RES_0402LF-0,5%,1/16W,EMPTY,CS00002JB13',
 PART_NUMBER='CS00002JB13',
 VALUE='0',
 PRIM_FILE='./archive_libs/logical/q_res/chips/chips.prt';

PART_NAME
 R8465 'Q_RES_0402LF-10K,5%,1/16W,CHIP,CS31002JB08':;

SECTION_NUMBER 1
 '@T6G_MB_LIB.T6G(SCH_1):PAGE184_I29@PURE_QUANTA.Q_RES(CHIPS)':
 C_PATH='@t6g_mb_lib.t6g(sch_1):page184_i29@pure_quanta.q_res(chips)',
 P_PATH='@t6g_mb_lib.t6g(sch_1):page209_i29@pure_quanta.q_res(chips)',
 PATH='I29',
 DRAWING='@T6G_MB_LIB.T6G(SCH_1):PAGE184',
 SEC_TYPE='0402LF',
 WATTAGE='1/16W',
 TOLERANCE='5%',
 MATERIAL='CHIP',
 PHYS_PAGE='209',
 XY='(-4700,4375)',
 ROT='0',
 VER='2',
 PACK_TYPE='0402LF',
 LOCATION='R8465',
 SEC='1',
 CDS_LIB='pure_quanta',
 CDS_PART_NAME='Q_RES_0402LF-10K,5%,1/16W,CHIP,CS31002JB08',
 PART_NUMBER='CS31002JB08',
 VALUE='10K',
 PRIM_FILE='./archive_libs/logical/q_res/chips/chips.prt';

PART_NAME
 R8563 'Q_RES_0402LF-0,5%,1/16W,CHIP,CS00002JB13':;

SECTION_NUMBER 1
 '@T6G_MB_LIB.T6G(SCH_1):PAGE28_I157@PURE_QUANTA.Q_RES(CHIPS)':
 C_PATH='@t6g_mb_lib.t6g(sch_1):page28_i157@pure_quanta.q_res(chips)',
 P_PATH='@t6g_mb_lib.t6g(sch_1):page28_i157@pure_quanta.q_res(chips)',
 PATH='I157',
 DRAWING='@T6G_MB_LIB.T6G(SCH_1):PAGE28',
 WATTAGE='1/16W',
 TOLERANCE='5%',
 MATERIAL='CHIP',
 PHYS_PAGE='28',
 XY='(-2025,11675)',
 ROT='0',
 VER='1',
 PACK_TYPE='0402LF',
 LOCATION='R8563',
 CDS_LIB='pure_quanta',
 CDS_PART_NAME='Q_RES_0402LF-0,5%,1/16W,CHIP,CS00002JB13',
 PART_NUMBER='CS00002JB13',
 VALUE='0',
 PRIM_FILE='./archive_libs/logical/q_res/chips/chips.prt';

PART_NAME
 R8564 'Q_RES_0402LF-0,5%,1/16W,CHIP,CS00002JB13':;

SECTION_NUMBER 1
 '@T6G_MB_LIB.T6G(SCH_1):PAGE28_I156@PURE_QUANTA.Q_RES(CHIPS)':
 C_PATH='@t6g_mb_lib.t6g(sch_1):page28_i156@pure_quanta.q_res(chips)',
 P_PATH='@t6g_mb_lib.t6g(sch_1):page28_i156@pure_quanta.q_res(chips)',
 PATH='I156',
 DRAWING='@T6G_MB_LIB.T6G(SCH_1):PAGE28',
 WATTAGE='1/16W',
 TOLERANCE='5%',
 MATERIAL='CHIP',
 PHYS_PAGE='28',
 XY='(-2025,11625)',
 ROT='0',
 VER='1',
 PACK_TYPE='0402LF',
 LOCATION='R8564',
 CDS_LIB='pure_quanta',
 CDS_PART_NAME='Q_RES_0402LF-0,5%,1/16W,CHIP,CS00002JB13',
 PART_NUMBER='CS00002JB13',
 VALUE='0',
 PRIM_FILE='./archive_libs/logical/q_res/chips/chips.prt';

PART_NAME
 R8565 'Q_RES_0402LF-0,5%,1/16W,CHIP,CS00002JB13':;

SECTION_NUMBER 1
 '@T6G_MB_LIB.T6G(SCH_1):PAGE28_I158@PURE_QUANTA.Q_RES(CHIPS)':
 C_PATH='@t6g_mb_lib.t6g(sch_1):page28_i158@pure_quanta.q_res(chips)',
 P_PATH='@t6g_mb_lib.t6g(sch_1):page28_i158@pure_quanta.q_res(chips)',
 PATH='I158',
 DRAWING='@T6G_MB_LIB.T6G(SCH_1):PAGE28',
 WATTAGE='1/16W',
 TOLERANCE='5%',
 MATERIAL='CHIP',
 PHYS_PAGE='28',
 XY='(-2000,11525)',
 ROT='0',
 VER='1',
 PACK_TYPE='0402LF',
 LOCATION='R8565',
 CDS_LIB='pure_quanta',
 CDS_PART_NAME='Q_RES_0402LF-0,5%,1/16W,CHIP,CS00002JB13',
 PART_NUMBER='CS00002JB13',
 VALUE='0',
 PRIM_FILE='./archive_libs/logical/q_res/chips/chips.prt';

PART_NAME
 R8566 'Q_RES_0402LF-0,5%,1/16W,CHIP,CS00002JB13':;

SECTION_NUMBER 1
 '@T6G_MB_LIB.T6G(SCH_1):PAGE28_I155@PURE_QUANTA.Q_RES(CHIPS)':
 C_PATH='@t6g_mb_lib.t6g(sch_1):page28_i155@pure_quanta.q_res(chips)',
 P_PATH='@t6g_mb_lib.t6g(sch_1):page28_i155@pure_quanta.q_res(chips)',
 PATH='I155',
 DRAWING='@T6G_MB_LIB.T6G(SCH_1):PAGE28',
 WATTAGE='1/16W',
 TOLERANCE='5%',
 MATERIAL='CHIP',
 PHYS_PAGE='28',
 XY='(-2000,11475)',
 ROT='0',
 VER='1',
 PACK_TYPE='0402LF',
 LOCATION='R8566',
 CDS_LIB='pure_quanta',
 CDS_PART_NAME='Q_RES_0402LF-0,5%,1/16W,CHIP,CS00002JB13',
 PART_NUMBER='CS00002JB13',
 VALUE='0',
 PRIM_FILE='./archive_libs/logical/q_res/chips/chips.prt';

PART_NAME
 R9000 'Q_RES_0402LF-1K,1%,1/16W,CHIP,CS21002FB06':;

SECTION_NUMBER 1
 '@T6G_MB_LIB.T6G(SCH_1):PAGE363_I472@PURE_QUANTA.Q_RES(CHIPS)':
 C_PATH='@t6g_mb_lib.t6g(sch_1):page363_i472@pure_quanta.q_res(chips)',
 P_PATH='@t6g_mb_lib.t6g(sch_1):page240_i472@pure_quanta.q_res(chips)',
 PATH='I472',
 DRAWING='@T6G_MB_LIB.T6G(SCH_1):PAGE363',
 WATTAGE='1/16W',
 TOLERANCE='1%',
 MATERIAL='CHIP',
 PHYS_PAGE='240',
 XY='(-1100,1050)',
 ROT='0',
 VER='2',
 PACK_TYPE='0402LF',
 LOCATION='R9000',
 CDS_LIB='pure_quanta',
 CDS_PART_NAME='Q_RES_0402LF-1K,1%,1/16W,CHIP,CS21002FB06',
 PART_NUMBER='CS21002FB06',
 VALUE='1K',
 PRIM_FILE='./archive_libs/logical/q_res/chips/chips.prt';

PART_NAME
 R9001 'Q_RES_0402LF-0,5%,1/16W,CHIP,CS00002JB13':;

SECTION_NUMBER 1
 '@T6G_MB_LIB.T6G(SCH_1):PAGE246_I46@PURE_QUANTA.Q_RES(CHIPS)':
 C_PATH='@t6g_mb_lib.t6g(sch_1):page246_i46@pure_quanta.q_res(chips)',
 P_PATH='@t6g_mb_lib.t6g(sch_1):page245_i46@pure_quanta.q_res(chips)',
 PATH='I46',
 DRAWING='@T6G_MB_LIB.T6G(SCH_1):PAGE246',
 WATTAGE='1/16W',
 TOLERANCE='5%',
 MATERIAL='CHIP',
 PHYS_PAGE='245',
 XY='(-3525,1825)',
 ROT='0',
 VER='1',
 PACK_TYPE='0402LF',
 LOCATION='R9001',
 CDS_LIB='pure_quanta',
 CDS_PART_NAME='Q_RES_0402LF-0,5%,1/16W,CHIP,CS00002JB13',
 PART_NUMBER='CS00002JB13',
 VALUE='0',
 PRIM_FILE='./archive_libs/logical/q_res/chips/chips.prt';

PART_NAME
 R9002 'Q_RES_0402LF-10K,1%,1/16W,CHIP,CS31002FB08':;

SECTION_NUMBER 1
 '@T6G_MB_LIB.T6G(SCH_1):PAGE330_I8@PURE_QUANTA.Q_RES(CHIPS)':
 C_PATH='@t6g_mb_lib.t6g(sch_1):page330_i8@pure_quanta.q_res(chips)',
 P_PATH='@t6g_mb_lib.t6g(sch_1):page123_i8@pure_quanta.q_res(chips)',
 PATH='I8',
 DRAWING='@T6G_MB_LIB.T6G(SCH_1):PAGE330',
 SEC_TYPE='0402LF',
 WATTAGE='1/16W',
 TOLERANCE='1%',
 MATERIAL='CHIP',
 PHYS_PAGE='123',
 XY='(-6100,6375)',
 ROT='2',
 VER='2',
 PACK_TYPE='0402LF',
 LOCATION='R9002',
 SEC='1',
 CDS_LIB='pure_quanta',
 CDS_PART_NAME='Q_RES_0402LF-10K,1%,1/16W,CHIP,CS31002FB08',
 PART_NUMBER='CS31002FB08',
 VALUE='10K',
 PRIM_FILE='./archive_libs/logical/q_res/chips/chips.prt';

PART_NAME
 R9003 'Q_RES_0402LF-100K,1%,1/16W,EMPTY,CS41002FB09':;

SECTION_NUMBER 1
 '@T6G_MB_LIB.T6G(SCH_1):PAGE330_I20@PURE_QUANTA.Q_RES(CHIPS)':
 C_PATH='@t6g_mb_lib.t6g(sch_1):page330_i20@pure_quanta.q_res(chips)',
 P_PATH='@t6g_mb_lib.t6g(sch_1):page123_i20@pure_quanta.q_res(chips)',
 PATH='I20',
 DRAWING='@T6G_MB_LIB.T6G(SCH_1):PAGE330',
 SEC_TYPE='0402LF',
 WATTAGE='1/16W',
 TOLERANCE='1%',
 MATERIAL='EMPTY',
 PHYS_PAGE='123',
 XY='(-6075,5750)',
 ROT='2',
 VER='2',
 PACK_TYPE='0402LF',
 LOCATION='R9003',
 SEC='1',
 CDS_LIB='pure_quanta',
 CDS_PART_NAME='Q_RES_0402LF-100K,1%,1/16W,EMPTY,CS41002FB09',
 PART_NUMBER='CS41002FB09',
 VALUE='100K',
 PRIM_FILE='./archive_libs/logical/q_res/chips/chips.prt';

PART_NAME
 R9004 'Q_RES_0402LF-4.7K,5%,1/16W,CHIP,CS24702JB10':;

SECTION_NUMBER 1
 '@T6G_MB_LIB.T6G(SCH_1):PAGE330_I26@PURE_QUANTA.Q_RES(CHIPS)':
 C_PATH='@t6g_mb_lib.t6g(sch_1):page330_i26@pure_quanta.q_res(chips)',
 P_PATH='@t6g_mb_lib.t6g(sch_1):page123_i26@pure_quanta.q_res(chips)',
 PATH='I26',
 DRAWING='@T6G_MB_LIB.T6G(SCH_1):PAGE330',
 WATTAGE='1/16W',
 TOLERANCE='5%',
 MATERIAL='CHIP',
 PHYS_PAGE='123',
 XY='(-5700,6700)',
 ROT='2',
 VER='2',
 PACK_TYPE='0402LF',
 LOCATION='R9004',
 CDS_LIB='pure_quanta',
 CDS_PART_NAME='Q_RES_0402LF-4.7K,5%,1/16W,CHIP,CS24702JB10',
 PART_NUMBER='CS24702JB10',
 VALUE='4.7K',
 PRIM_FILE='./archive_libs/logical/q_res/chips/chips.prt';

PART_NAME
 R9005 'Q_RES_0402LF-4.7K,5%,1/16W,CHIP,CS24702JB10':;

SECTION_NUMBER 1
 '@T6G_MB_LIB.T6G(SCH_1):PAGE330_I32@PURE_QUANTA.Q_RES(CHIPS)':
 C_PATH='@t6g_mb_lib.t6g(sch_1):page330_i32@pure_quanta.q_res(chips)',
 P_PATH='@t6g_mb_lib.t6g(sch_1):page123_i32@pure_quanta.q_res(chips)',
 PATH='I32',
 DRAWING='@T6G_MB_LIB.T6G(SCH_1):PAGE330',
 WATTAGE='1/16W',
 TOLERANCE='5%',
 MATERIAL='CHIP',
 PHYS_PAGE='123',
 XY='(-4700,6950)',
 ROT='2',
 VER='2',
 PACK_TYPE='0402LF',
 LOCATION='R9005',
 CDS_LIB='pure_quanta',
 CDS_PART_NAME='Q_RES_0402LF-4.7K,5%,1/16W,CHIP,CS24702JB10',
 PART_NUMBER='CS24702JB10',
 VALUE='4.7K',
 PRIM_FILE='./archive_libs/logical/q_res/chips/chips.prt';

PART_NAME
 R9006 'Q_RES_0402LF-10K,1%,1/16W,CHIP,CS31002FB08':;

SECTION_NUMBER 1
 '@T6G_MB_LIB.T6G(SCH_1):PAGE330_I15@PURE_QUANTA.Q_RES(CHIPS)':
 C_PATH='@t6g_mb_lib.t6g(sch_1):page330_i15@pure_quanta.q_res(chips)',
 P_PATH='@t6g_mb_lib.t6g(sch_1):page123_i15@pure_quanta.q_res(chips)',
 PATH='I15',
 DRAWING='@T6G_MB_LIB.T6G(SCH_1):PAGE330',
 WATTAGE='1/16W',
 TOLERANCE='1%',
 MATERIAL='CHIP',
 PHYS_PAGE='123',
 XY='(-6050,4575)',
 ROT='2',
 VER='2',
 PACK_TYPE='0402LF',
 LOCATION='R9006',
 CDS_LIB='pure_quanta',
 CDS_PART_NAME='Q_RES_0402LF-10K,1%,1/16W,CHIP,CS31002FB08',
 PART_NUMBER='CS31002FB08',
 VALUE='10K',
 PRIM_FILE='./archive_libs/logical/q_res/chips/chips.prt';

PART_NAME
 R9007 'Q_RES_0402LF-100K,1%,1/16W,EMPTY,CS41002FB09':;

SECTION_NUMBER 1
 '@T6G_MB_LIB.T6G(SCH_1):PAGE330_I2@PURE_QUANTA.Q_RES(CHIPS)':
 C_PATH='@t6g_mb_lib.t6g(sch_1):page330_i2@pure_quanta.q_res(chips)',
 P_PATH='@t6g_mb_lib.t6g(sch_1):page123_i2@pure_quanta.q_res(chips)',
 PATH='I2',
 DRAWING='@T6G_MB_LIB.T6G(SCH_1):PAGE330',
 WATTAGE='1/16W',
 TOLERANCE='1%',
 MATERIAL='EMPTY',
 PHYS_PAGE='123',
 XY='(-6025,3950)',
 ROT='2',
 VER='2',
 PACK_TYPE='0402LF',
 LOCATION='R9007',
 CDS_LIB='pure_quanta',
 CDS_PART_NAME='Q_RES_0402LF-100K,1%,1/16W,EMPTY,CS41002FB09',
 PART_NUMBER='CS41002FB09',
 VALUE='100K',
 PRIM_FILE='./archive_libs/logical/q_res/chips/chips.prt';

PART_NAME
 R9008 'Q_RES_0402LF-4.7K,5%,1/16W,CHIP,CS24702JB10':;

SECTION_NUMBER 1
 '@T6G_MB_LIB.T6G(SCH_1):PAGE330_I17@PURE_QUANTA.Q_RES(CHIPS)':
 C_PATH='@t6g_mb_lib.t6g(sch_1):page330_i17@pure_quanta.q_res(chips)',
 P_PATH='@t6g_mb_lib.t6g(sch_1):page123_i17@pure_quanta.q_res(chips)',
 PATH='I17',
 DRAWING='@T6G_MB_LIB.T6G(SCH_1):PAGE330',
 WATTAGE='1/16W',
 TOLERANCE='5%',
 MATERIAL='CHIP',
 PHYS_PAGE='123',
 XY='(-5650,4900)',
 ROT='2',
 VER='2',
 PACK_TYPE='0402LF',
 LOCATION='R9008',
 CDS_LIB='pure_quanta',
 CDS_PART_NAME='Q_RES_0402LF-4.7K,5%,1/16W,CHIP,CS24702JB10',
 PART_NUMBER='CS24702JB10',
 VALUE='4.7K',
 PRIM_FILE='./archive_libs/logical/q_res/chips/chips.prt';

PART_NAME
 R9009 'Q_RES_0402LF-4.7K,5%,1/16W,CHIP,CS24702JB10':;

SECTION_NUMBER 1
 '@T6G_MB_LIB.T6G(SCH_1):PAGE330_I23@PURE_QUANTA.Q_RES(CHIPS)':
 C_PATH='@t6g_mb_lib.t6g(sch_1):page330_i23@pure_quanta.q_res(chips)',
 P_PATH='@t6g_mb_lib.t6g(sch_1):page123_i23@pure_quanta.q_res(chips)',
 PATH='I23',
 DRAWING='@T6G_MB_LIB.T6G(SCH_1):PAGE330',
 WATTAGE='1/16W',
 TOLERANCE='5%',
 MATERIAL='CHIP',
 PHYS_PAGE='123',
 XY='(-4650,5150)',
 ROT='2',
 VER='2',
 PACK_TYPE='0402LF',
 LOCATION='R9009',
 CDS_LIB='pure_quanta',
 CDS_PART_NAME='Q_RES_0402LF-4.7K,5%,1/16W,CHIP,CS24702JB10',
 PART_NUMBER='CS24702JB10',
 VALUE='4.7K',
 PRIM_FILE='./archive_libs/logical/q_res/chips/chips.prt';

PART_NAME
 R9010 'Q_RES_0402LF-0,5%,1/16W,CHIP,CS00002JB13':;

SECTION_NUMBER 1
 '@T6G_MB_LIB.T6G(SCH_1):PAGE246_I40@PURE_QUANTA.Q_RES(CHIPS)':
 C_PATH='@t6g_mb_lib.t6g(sch_1):page246_i40@pure_quanta.q_res(chips)',
 P_PATH='@t6g_mb_lib.t6g(sch_1):page245_i40@pure_quanta.q_res(chips)',
 PATH='I40',
 DRAWING='@T6G_MB_LIB.T6G(SCH_1):PAGE246',
 WATTAGE='1/16W',
 TOLERANCE='5%',
 MATERIAL='CHIP',
 PHYS_PAGE='245',
 XY='(-3525,975)',
 ROT='0',
 VER='1',
 PACK_TYPE='0402LF',
 LOCATION='R9010',
 CDS_LIB='pure_quanta',
 CDS_PART_NAME='Q_RES_0402LF-0,5%,1/16W,CHIP,CS00002JB13',
 PART_NUMBER='CS00002JB13',
 VALUE='0',
 PRIM_FILE='./archive_libs/logical/q_res/chips/chips.prt';

PART_NAME
 R9011 'Q_RES_0402LF-0,5%,1/16W,CHIP,CS00002JB13':;

SECTION_NUMBER 1
 '@T6G_MB_LIB.T6G(SCH_1):PAGE246_I45@PURE_QUANTA.Q_RES(CHIPS)':
 C_PATH='@t6g_mb_lib.t6g(sch_1):page246_i45@pure_quanta.q_res(chips)',
 P_PATH='@t6g_mb_lib.t6g(sch_1):page245_i45@pure_quanta.q_res(chips)',
 PATH='I45',
 DRAWING='@T6G_MB_LIB.T6G(SCH_1):PAGE246',
 WATTAGE='1/16W',
 TOLERANCE='5%',
 MATERIAL='CHIP',
 PHYS_PAGE='245',
 XY='(-3525,1700)',
 ROT='0',
 VER='1',
 PACK_TYPE='0402LF',
 LOCATION='R9011',
 CDS_LIB='pure_quanta',
 CDS_PART_NAME='Q_RES_0402LF-0,5%,1/16W,CHIP,CS00002JB13',
 PART_NUMBER='CS00002JB13',
 VALUE='0',
 PRIM_FILE='./archive_libs/logical/q_res/chips/chips.prt';

PART_NAME
 R9012 'Q_RES_0402LF-0,5%,1/16W,CHIP,CS00002JB13':;

SECTION_NUMBER 1
 '@T6G_MB_LIB.T6G(SCH_1):PAGE246_I39@PURE_QUANTA.Q_RES(CHIPS)':
 C_PATH='@t6g_mb_lib.t6g(sch_1):page246_i39@pure_quanta.q_res(chips)',
 P_PATH='@t6g_mb_lib.t6g(sch_1):page245_i39@pure_quanta.q_res(chips)',
 PATH='I39',
 DRAWING='@T6G_MB_LIB.T6G(SCH_1):PAGE246',
 WATTAGE='1/16W',
 TOLERANCE='5%',
 MATERIAL='CHIP',
 PHYS_PAGE='245',
 XY='(-3525,875)',
 ROT='0',
 VER='1',
 PACK_TYPE='0402LF',
 LOCATION='R9012',
 CDS_LIB='pure_quanta',
 CDS_PART_NAME='Q_RES_0402LF-0,5%,1/16W,CHIP,CS00002JB13',
 PART_NUMBER='CS00002JB13',
 VALUE='0',
 PRIM_FILE='./archive_libs/logical/q_res/chips/chips.prt';

PART_NAME
 R9013 'Q_RES_0402LF-0,5%,1/16W,CHIP,CS00002JB13':;

SECTION_NUMBER 1
 '@T6G_MB_LIB.T6G(SCH_1):PAGE246_I43@PURE_QUANTA.Q_RES(CHIPS)':
 C_PATH='@t6g_mb_lib.t6g(sch_1):page246_i43@pure_quanta.q_res(chips)',
 P_PATH='@t6g_mb_lib.t6g(sch_1):page245_i43@pure_quanta.q_res(chips)',
 PATH='I43',
 DRAWING='@T6G_MB_LIB.T6G(SCH_1):PAGE246',
 WATTAGE='1/16W',
 TOLERANCE='5%',
 MATERIAL='CHIP',
 PHYS_PAGE='245',
 XY='(-3525,1500)',
 ROT='0',
 VER='1',
 PACK_TYPE='0402LF',
 LOCATION='R9013',
 CDS_LIB='pure_quanta',
 CDS_PART_NAME='Q_RES_0402LF-0,5%,1/16W,CHIP,CS00002JB13',
 PART_NUMBER='CS00002JB13',
 VALUE='0',
 PRIM_FILE='./archive_libs/logical/q_res/chips/chips.prt';

PART_NAME
 R9014 'Q_RES_0402LF-10K,1%,1/16W,CHIP,CS31002FB08':;

SECTION_NUMBER 1
 '@T6G_MB_LIB.T6G(SCH_1):PAGE330_I51@PURE_QUANTA.Q_RES(CHIPS)':
 C_PATH='@t6g_mb_lib.t6g(sch_1):page330_i51@pure_quanta.q_res(chips)',
 P_PATH='@t6g_mb_lib.t6g(sch_1):page123_i51@pure_quanta.q_res(chips)',
 PATH='I51',
 DRAWING='@T6G_MB_LIB.T6G(SCH_1):PAGE330',
 WATTAGE='1/16W',
 TOLERANCE='1%',
 MATERIAL='CHIP',
 PHYS_PAGE='123',
 XY='(-1325,8150)',
 ROT='2',
 VER='2',
 PACK_TYPE='0402LF',
 LOCATION='R9014',
 CDS_LIB='pure_quanta',
 CDS_PART_NAME='Q_RES_0402LF-10K,1%,1/16W,CHIP,CS31002FB08',
 PART_NUMBER='CS31002FB08',
 VALUE='10K',
 PRIM_FILE='./archive_libs/logical/q_res/chips/chips.prt';

PART_NAME
 R9015 'Q_RES_0402LF-100K,1%,1/16W,EMPTY,CS41002FB09':;

SECTION_NUMBER 1
 '@T6G_MB_LIB.T6G(SCH_1):PAGE330_I50@PURE_QUANTA.Q_RES(CHIPS)':
 C_PATH='@t6g_mb_lib.t6g(sch_1):page330_i50@pure_quanta.q_res(chips)',
 P_PATH='@t6g_mb_lib.t6g(sch_1):page123_i50@pure_quanta.q_res(chips)',
 PATH='I50',
 DRAWING='@T6G_MB_LIB.T6G(SCH_1):PAGE330',
 WATTAGE='1/16W',
 TOLERANCE='1%',
 MATERIAL='EMPTY',
 PHYS_PAGE='123',
 XY='(-1300,7525)',
 ROT='2',
 VER='2',
 PACK_TYPE='0402LF',
 LOCATION='R9015',
 CDS_LIB='pure_quanta',
 CDS_PART_NAME='Q_RES_0402LF-100K,1%,1/16W,EMPTY,CS41002FB09',
 PART_NUMBER='CS41002FB09',
 VALUE='100K',
 PRIM_FILE='./archive_libs/logical/q_res/chips/chips.prt';

PART_NAME
 R9016 'Q_RES_0402LF-4.7K,5%,1/16W,CHIP,CS24702JB10':;

SECTION_NUMBER 1
 '@T6G_MB_LIB.T6G(SCH_1):PAGE330_I61@PURE_QUANTA.Q_RES(CHIPS)':
 C_PATH='@t6g_mb_lib.t6g(sch_1):page330_i61@pure_quanta.q_res(chips)',
 P_PATH='@t6g_mb_lib.t6g(sch_1):page123_i61@pure_quanta.q_res(chips)',
 PATH='I61',
 DRAWING='@T6G_MB_LIB.T6G(SCH_1):PAGE330',
 WATTAGE='1/16W',
 TOLERANCE='5%',
 MATERIAL='CHIP',
 PHYS_PAGE='123',
 XY='(-925,8475)',
 ROT='2',
 VER='2',
 PACK_TYPE='0402LF',
 LOCATION='R9016',
 CDS_LIB='pure_quanta',
 CDS_PART_NAME='Q_RES_0402LF-4.7K,5%,1/16W,CHIP,CS24702JB10',
 PART_NUMBER='CS24702JB10',
 VALUE='4.7K',
 PRIM_FILE='./archive_libs/logical/q_res/chips/chips.prt';

PART_NAME
 R9017 'Q_RES_0402LF-4.7K,5%,1/16W,CHIP,CS24702JB10':;

SECTION_NUMBER 1
 '@T6G_MB_LIB.T6G(SCH_1):PAGE330_I72@PURE_QUANTA.Q_RES(CHIPS)':
 C_PATH='@t6g_mb_lib.t6g(sch_1):page330_i72@pure_quanta.q_res(chips)',
 P_PATH='@t6g_mb_lib.t6g(sch_1):page123_i72@pure_quanta.q_res(chips)',
 PATH='I72',
 DRAWING='@T6G_MB_LIB.T6G(SCH_1):PAGE330',
 WATTAGE='1/16W',
 TOLERANCE='5%',
 MATERIAL='CHIP',
 PHYS_PAGE='123',
 XY='(75,8725)',
 ROT='2',
 VER='2',
 PACK_TYPE='0402LF',
 LOCATION='R9017',
 CDS_LIB='pure_quanta',
 CDS_PART_NAME='Q_RES_0402LF-4.7K,5%,1/16W,CHIP,CS24702JB10',
 PART_NUMBER='CS24702JB10',
 VALUE='4.7K',
 PRIM_FILE='./archive_libs/logical/q_res/chips/chips.prt';

PART_NAME
 R9018 'Q_RES_0402LF-0,5%,1/16W,CHIP,CS00002JB13':;

SECTION_NUMBER 1
 '@T6G_MB_LIB.T6G(SCH_1):PAGE246_I44@PURE_QUANTA.Q_RES(CHIPS)':
 C_PATH='@t6g_mb_lib.t6g(sch_1):page246_i44@pure_quanta.q_res(chips)',
 P_PATH='@t6g_mb_lib.t6g(sch_1):page245_i44@pure_quanta.q_res(chips)',
 PATH='I44',
 DRAWING='@T6G_MB_LIB.T6G(SCH_1):PAGE246',
 WATTAGE='1/16W',
 TOLERANCE='5%',
 MATERIAL='CHIP',
 PHYS_PAGE='245',
 XY='(-3525,1600)',
 ROT='0',
 VER='1',
 PACK_TYPE='0402LF',
 LOCATION='R9018',
 CDS_LIB='pure_quanta',
 CDS_PART_NAME='Q_RES_0402LF-0,5%,1/16W,CHIP,CS00002JB13',
 PART_NUMBER='CS00002JB13',
 VALUE='0',
 PRIM_FILE='./archive_libs/logical/q_res/chips/chips.prt';

PART_NAME
 R9019 'Q_RES_0402LF-0,5%,1/16W,CHIP,CS00002JB13':;

SECTION_NUMBER 1
 '@T6G_MB_LIB.T6G(SCH_1):PAGE246_I42@PURE_QUANTA.Q_RES(CHIPS)':
 C_PATH='@t6g_mb_lib.t6g(sch_1):page246_i42@pure_quanta.q_res(chips)',
 P_PATH='@t6g_mb_lib.t6g(sch_1):page245_i42@pure_quanta.q_res(chips)',
 PATH='I42',
 DRAWING='@T6G_MB_LIB.T6G(SCH_1):PAGE246',
 WATTAGE='1/16W',
 TOLERANCE='5%',
 MATERIAL='CHIP',
 PHYS_PAGE='245',
 XY='(-3525,1400)',
 ROT='0',
 VER='1',
 PACK_TYPE='0402LF',
 LOCATION='R9019',
 CDS_LIB='pure_quanta',
 CDS_PART_NAME='Q_RES_0402LF-0,5%,1/16W,CHIP,CS00002JB13',
 PART_NUMBER='CS00002JB13',
 VALUE='0',
 PRIM_FILE='./archive_libs/logical/q_res/chips/chips.prt';

PART_NAME
 R9020 'Q_RES_0402LF-1K,1%,1/16W,EMPTY,CS21002FB06':
 ROOM='HSC BOM2';

SECTION_NUMBER 1
 '@T6G_MB_LIB.T6G(SCH_1):PAGE371_I108@PURE_QUANTA.Q_RES(CHIPS)':
 C_PATH='@t6g_mb_lib.t6g(sch_1):page371_i108@pure_quanta.q_res(chips)',
 P_PATH='@t6g_mb_lib.t6g(sch_1):page267_i108@pure_quanta.q_res(chips)',
 PATH='I108',
 DRAWING='@T6G_MB_LIB.T6G(SCH_1):PAGE371',
 WATTAGE='1/16W',
 TOLERANCE='1%',
 MATERIAL='EMPTY',
 PHYS_PAGE='267',
 XY='(-6375,6625)',
 ROT='0',
 VER='2',
 PACK_TYPE='0402LF',
 LOCATION='R9020',
 CDS_LIB='pure_quanta',
 CDS_PART_NAME='Q_RES_0402LF-1K,1%,1/16W,EMPTY,CS21002FB06',
 ROOM='HSC BOM2',
 PART_NUMBER='CS21002FB06',
 VALUE='1K',
 PRIM_FILE='./archive_libs/logical/q_res/chips/chips.prt';

PART_NAME
 R9021 'Q_RES_0402LF-1K,1%,1/16W,EMPTY,CS21002FB06':;

SECTION_NUMBER 1
 '@T6G_MB_LIB.T6G(SCH_1):PAGE372_I97@PURE_QUANTA.Q_RES(CHIPS)':
 C_PATH='@t6g_mb_lib.t6g(sch_1):page372_i97@pure_quanta.q_res(chips)',
 P_PATH='@t6g_mb_lib.t6g(sch_1):page268_i97@pure_quanta.q_res(chips)',
 PATH='I97',
 DRAWING='@T6G_MB_LIB.T6G(SCH_1):PAGE372',
 WATTAGE='1/16W',
 TOLERANCE='1%',
 MATERIAL='EMPTY',
 PHYS_PAGE='268',
 XY='(-4650,5925)',
 ROT='0',
 VER='2',
 PACK_TYPE='0402LF',
 LOCATION='R9021',
 CDS_LIB='pure_quanta',
 CDS_PART_NAME='Q_RES_0402LF-1K,1%,1/16W,EMPTY,CS21002FB06',
 PART_NUMBER='CS21002FB06',
 VALUE='1K',
 PRIM_FILE='./archive_libs/logical/q_res/chips/chips.prt';

PART_NAME
 R9022 'Q_RES_0402LF-33.2,1%,1/16W,CHIP,CS03322FB03':;

SECTION_NUMBER 1
 '@T6G_MB_LIB.T6G(SCH_1):PAGE340_I13@PURE_QUANTA.Q_RES(CHIPS)':
 C_PATH='@t6g_mb_lib.t6g(sch_1):page340_i13@pure_quanta.q_res(chips)',
 P_PATH='@t6g_mb_lib.t6g(sch_1):page136_i13@pure_quanta.q_res(chips)',
 PATH='I13',
 DRAWING='@T6G_MB_LIB.T6G(SCH_1):PAGE340',
 WATTAGE='1/16W',
 TOLERANCE='1%',
 MATERIAL='CHIP',
 PHYS_PAGE='136',
 XY='(-1000,6600)',
 ROT='0',
 VER='1',
 PACK_TYPE='0402LF',
 LOCATION='R9022',
 CDS_LIB='pure_quanta',
 CDS_PART_NAME='Q_RES_0402LF-33.2,1%,1/16W,CHIP,CS03322FB03',
 PART_NUMBER='CS03322FB03',
 VALUE='33.2',
 PRIM_FILE='./archive_libs/logical/q_res/chips/chips.prt';

PART_NAME
 R9023 'Q_RES_0402LF-33.2,1%,1/16W,CHIP,CS03322FB03':;

SECTION_NUMBER 1
 '@T6G_MB_LIB.T6G(SCH_1):PAGE340_I14@PURE_QUANTA.Q_RES(CHIPS)':
 C_PATH='@t6g_mb_lib.t6g(sch_1):page340_i14@pure_quanta.q_res(chips)',
 P_PATH='@t6g_mb_lib.t6g(sch_1):page136_i14@pure_quanta.q_res(chips)',
 PATH='I14',
 DRAWING='@T6G_MB_LIB.T6G(SCH_1):PAGE340',
 WATTAGE='1/16W',
 TOLERANCE='1%',
 MATERIAL='CHIP',
 PHYS_PAGE='136',
 XY='(-1000,6700)',
 ROT='0',
 VER='1',
 PACK_TYPE='0402LF',
 LOCATION='R9023',
 CDS_LIB='pure_quanta',
 CDS_PART_NAME='Q_RES_0402LF-33.2,1%,1/16W,CHIP,CS03322FB03',
 PART_NUMBER='CS03322FB03',
 VALUE='33.2',
 PRIM_FILE='./archive_libs/logical/q_res/chips/chips.prt';

PART_NAME
 R9024 'Q_RES_0402LF-54.9K,1%,1/16W,CHIP,CS35492FB03':
 ROOM='HSC BOM2';

SECTION_NUMBER 1
 '@T6G_MB_LIB.T6G(SCH_1):PAGE371_I113@PURE_QUANTA.Q_RES(CHIPS)':
 C_PATH='@t6g_mb_lib.t6g(sch_1):page371_i113@pure_quanta.q_res(chips)',
 P_PATH='@t6g_mb_lib.t6g(sch_1):page267_i113@pure_quanta.q_res(chips)',
 PATH='I113',
 DRAWING='@T6G_MB_LIB.T6G(SCH_1):PAGE371',
 SEC_TYPE='0402LF',
 WATTAGE='1/16W',
 TOLERANCE='1%',
 MATERIAL='CHIP',
 PHYS_PAGE='267',
 XY='(-2700,4625)',
 ROT='2',
 VER='2',
 PACK_TYPE='0402LF',
 LOCATION='R9024',
 SEC='1',
 CDS_LIB='pure_quanta',
 CDS_PART_NAME='Q_RES_0402LF-54.9K,1%,1/16W,CHIP,CS35492FB03',
 ROOM='HSC BOM2',
 PART_NUMBER='CS35492FB03',
 VALUE='54.9K',
 PRIM_FILE='./archive_libs/logical/q_res/chips/chips.prt';

PART_NAME
 R9025 'Q_RES_0402LF-100K,1%,1/16W,EMPTY,CS41002FB09':;

SECTION_NUMBER 1
 '@T6G_MB_LIB.T6G(SCH_1):PAGE84_I106@PURE_QUANTA.Q_RES(CHIPS)':
 C_PATH='@t6g_mb_lib.t6g(sch_1):page84_i106@pure_quanta.q_res(chips)',
 P_PATH='@t6g_mb_lib.t6g(sch_1):page85_i106@pure_quanta.q_res(chips)',
 PATH='I106',
 DRAWING='@T6G_MB_LIB.T6G(SCH_1):PAGE84',
 WATTAGE='1/16W',
 TOLERANCE='1%',
 MATERIAL='EMPTY',
 PHYS_PAGE='85',
 XY='(-8625,3650)',
 ROT='0',
 VER='2',
 PACK_TYPE='0402LF',
 LOCATION='R9025',
 CDS_LIB='pure_quanta',
 CDS_PART_NAME='Q_RES_0402LF-100K,1%,1/16W,EMPTY,CS41002FB09',
 PART_NUMBER='CS41002FB09',
 VALUE='100K',
 PRIM_FILE='./archive_libs/logical/q_res/chips/chips.prt';

PART_NAME
 R9026 'Q_RES_0402LF-4.7K,5%,1/16W,CHIP,CS24702JB10':;

SECTION_NUMBER 1
 '@T6G_MB_LIB.T6G(SCH_1):PAGE84_I112@PURE_QUANTA.Q_RES(CHIPS)':
 C_PATH='@t6g_mb_lib.t6g(sch_1):page84_i112@pure_quanta.q_res(chips)',
 P_PATH='@t6g_mb_lib.t6g(sch_1):page85_i112@pure_quanta.q_res(chips)',
 PATH='I112',
 DRAWING='@T6G_MB_LIB.T6G(SCH_1):PAGE84',
 WATTAGE='1/16W',
 TOLERANCE='5%',
 MATERIAL='CHIP',
 PHYS_PAGE='85',
 XY='(-7475,4500)',
 ROT='0',
 VER='2',
 PACK_TYPE='0402LF',
 LOCATION='R9026',
 CDS_LIB='pure_quanta',
 CDS_PART_NAME='Q_RES_0402LF-4.7K,5%,1/16W,CHIP,CS24702JB10',
 PART_NUMBER='CS24702JB10',
 VALUE='4.7K',
 PRIM_FILE='./archive_libs/logical/q_res/chips/chips.prt';

PART_NAME
 R9027 'Q_RES_0402LF-100K,1%,1/16W,CHIP,CS41002FB09':;

SECTION_NUMBER 1
 '@T6G_MB_LIB.T6G(SCH_1):PAGE84_I114@PURE_QUANTA.Q_RES(CHIPS)':
 C_PATH='@t6g_mb_lib.t6g(sch_1):page84_i114@pure_quanta.q_res(chips)',
 P_PATH='@t6g_mb_lib.t6g(sch_1):page85_i114@pure_quanta.q_res(chips)',
 PATH='I114',
 DRAWING='@T6G_MB_LIB.T6G(SCH_1):PAGE84',
 WATTAGE='1/16W',
 TOLERANCE='1%',
 MATERIAL='CHIP',
 PHYS_PAGE='85',
 XY='(-6325,4625)',
 ROT='0',
 VER='2',
 PACK_TYPE='0402LF',
 LOCATION='R9027',
 CDS_LIB='pure_quanta',
 CDS_PART_NAME='Q_RES_0402LF-100K,1%,1/16W,CHIP,CS41002FB09',
 PART_NUMBER='CS41002FB09',
 VALUE='100K',
 PRIM_FILE='./archive_libs/logical/q_res/chips/chips.prt';

PART_NAME
 R9028 'Q_RES_0402LF-0,5%,1/16W,EMPTY,CS00002JB13':;

SECTION_NUMBER 1
 '@T6G_MB_LIB.T6G(SCH_1):PAGE84_I118@PURE_QUANTA.Q_RES(CHIPS)':
 C_PATH='@t6g_mb_lib.t6g(sch_1):page84_i118@pure_quanta.q_res(chips)',
 P_PATH='@t6g_mb_lib.t6g(sch_1):page85_i118@pure_quanta.q_res(chips)',
 PATH='I118',
 DRAWING='@T6G_MB_LIB.T6G(SCH_1):PAGE84',
 WATTAGE='1/16W',
 TOLERANCE='5%',
 MATERIAL='EMPTY',
 PHYS_PAGE='85',
 XY='(-7075,5075)',
 ROT='0',
 VER='1',
 PACK_TYPE='0402LF',
 LOCATION='R9028',
 CDS_LIB='pure_quanta',
 CDS_PART_NAME='Q_RES_0402LF-0,5%,1/16W,EMPTY,CS00002JB13',
 PART_NUMBER='CS00002JB13',
 VALUE='0',
 PRIM_FILE='./archive_libs/logical/q_res/chips/chips.prt';

PART_NAME
 R9029 'Q_RES_0402LF-0,5%,1/16W,EMPTY,CS00002JB13':;

SECTION_NUMBER 1
 '@T6G_MB_LIB.T6G(SCH_1):PAGE340_I18@PURE_QUANTA.Q_RES(CHIPS)':
 C_PATH='@t6g_mb_lib.t6g(sch_1):page340_i18@pure_quanta.q_res(chips)',
 P_PATH='@t6g_mb_lib.t6g(sch_1):page136_i18@pure_quanta.q_res(chips)',
 PATH='I18',
 DRAWING='@T6G_MB_LIB.T6G(SCH_1):PAGE340',
 BOM_COST='MEM',
 WATTAGE='1/16W',
 TOLERANCE='5%',
 MATERIAL='EMPTY',
 PHYS_PAGE='136',
 XY='(825,6075)',
 ROT='2',
 VER='1',
 PACK_TYPE='0402LF',
 LOCATION='R9029',
 CDS_LIB='pure_quanta',
 CDS_PART_NAME='Q_RES_0402LF-0,5%,1/16W,EMPTY,CS00002JB13',
 PART_NUMBER='CS00002JB13',
 VALUE='0',
 PRIM_FILE='./archive_libs/logical/q_res/chips/chips.prt';

PART_NAME
 R9030 'Q_RES_0402LF-0,5%,1/16W,EMPTY,CS00002JB13':;

SECTION_NUMBER 1
 '@T6G_MB_LIB.T6G(SCH_1):PAGE340_I15@PURE_QUANTA.Q_RES(CHIPS)':
 C_PATH='@t6g_mb_lib.t6g(sch_1):page340_i15@pure_quanta.q_res(chips)',
 P_PATH='@t6g_mb_lib.t6g(sch_1):page136_i15@pure_quanta.q_res(chips)',
 PATH='I15',
 DRAWING='@T6G_MB_LIB.T6G(SCH_1):PAGE340',
 BOM_COST='MEM',
 WATTAGE='1/16W',
 TOLERANCE='5%',
 MATERIAL='EMPTY',
 PHYS_PAGE='136',
 XY='(825,4575)',
 ROT='2',
 VER='1',
 PACK_TYPE='0402LF',
 LOCATION='R9030',
 CDS_LIB='pure_quanta',
 CDS_PART_NAME='Q_RES_0402LF-0,5%,1/16W,EMPTY,CS00002JB13',
 PART_NUMBER='CS00002JB13',
 VALUE='0',
 PRIM_FILE='./archive_libs/logical/q_res/chips/chips.prt';

PART_NAME
 R9031 'Q_RES_0402LF-33.2,1%,1/16W,CHIP,CS03322FB03':;

SECTION_NUMBER 1
 '@T6G_MB_LIB.T6G(SCH_1):PAGE340_I22@PURE_QUANTA.Q_RES(CHIPS)':
 C_PATH='@t6g_mb_lib.t6g(sch_1):page340_i22@pure_quanta.q_res(chips)',
 P_PATH='@t6g_mb_lib.t6g(sch_1):page136_i22@pure_quanta.q_res(chips)',
 PATH='I22',
 DRAWING='@T6G_MB_LIB.T6G(SCH_1):PAGE340',
 WATTAGE='1/16W',
 TOLERANCE='1%',
 MATERIAL='CHIP',
 PHYS_PAGE='136',
 XY='(1825,5375)',
 ROT='0',
 VER='1',
 PACK_TYPE='0402LF',
 LOCATION='R9031',
 CDS_LIB='pure_quanta',
 CDS_PART_NAME='Q_RES_0402LF-33.2,1%,1/16W,CHIP,CS03322FB03',
 PART_NUMBER='CS03322FB03',
 VALUE='33.2',
 PRIM_FILE='./archive_libs/logical/q_res/chips/chips.prt';

PART_NAME
 R9032 'Q_RES_0402LF-10K,1%,1/16W,CHIP,CS31002FB08':;

SECTION_NUMBER 1
 '@T6G_MB_LIB.T6G(SCH_1):PAGE340_I2@PURE_QUANTA.Q_RES(CHIPS)':
 C_PATH='@t6g_mb_lib.t6g(sch_1):page340_i2@pure_quanta.q_res(chips)',
 P_PATH='@t6g_mb_lib.t6g(sch_1):page136_i2@pure_quanta.q_res(chips)',
 PATH='I2',
 DRAWING='@T6G_MB_LIB.T6G(SCH_1):PAGE340',
 WATTAGE='1/16W',
 TOLERANCE='1%',
 MATERIAL='CHIP',
 PHYS_PAGE='136',
 XY='(-1625,5650)',
 ROT='2',
 VER='2',
 PACK_TYPE='0402LF',
 LOCATION='R9032',
 CDS_LIB='pure_quanta',
 CDS_PART_NAME='Q_RES_0402LF-10K,1%,1/16W,CHIP,CS31002FB08',
 PART_NUMBER='CS31002FB08',
 VALUE='10K',
 PRIM_FILE='./archive_libs/logical/q_res/chips/chips.prt';

PART_NAME
 R9033 'Q_RES_0402LF-33.2,1%,1/16W,CHIP,CS03322FB03':;

SECTION_NUMBER 1
 '@T6G_MB_LIB.T6G(SCH_1):PAGE340_I29@PURE_QUANTA.Q_RES(CHIPS)':
 C_PATH='@t6g_mb_lib.t6g(sch_1):page340_i29@pure_quanta.q_res(chips)',
 P_PATH='@t6g_mb_lib.t6g(sch_1):page136_i29@pure_quanta.q_res(chips)',
 PATH='I29',
 DRAWING='@T6G_MB_LIB.T6G(SCH_1):PAGE340',
 WATTAGE='1/16W',
 TOLERANCE='1%',
 MATERIAL='CHIP',
 PHYS_PAGE='136',
 XY='(2050,6550)',
 ROT='0',
 VER='1',
 PACK_TYPE='0402LF',
 LOCATION='R9033',
 CDS_LIB='pure_quanta',
 CDS_PART_NAME='Q_RES_0402LF-33.2,1%,1/16W,CHIP,CS03322FB03',
 PART_NUMBER='CS03322FB03',
 VALUE='33.2',
 PRIM_FILE='./archive_libs/logical/q_res/chips/chips.prt';

PART_NAME
 R9034 'Q_RES_0402LF-33.2,1%,1/16W,CHIP,CS03322FB03':;

SECTION_NUMBER 1
 '@T6G_MB_LIB.T6G(SCH_1):PAGE340_I3@PURE_QUANTA.Q_RES(CHIPS)':
 C_PATH='@t6g_mb_lib.t6g(sch_1):page340_i3@pure_quanta.q_res(chips)',
 P_PATH='@t6g_mb_lib.t6g(sch_1):page136_i3@pure_quanta.q_res(chips)',
 PATH='I3',
 DRAWING='@T6G_MB_LIB.T6G(SCH_1):PAGE340',
 WATTAGE='1/16W',
 TOLERANCE='1%',
 MATERIAL='CHIP',
 PHYS_PAGE='136',
 XY='(-1075,5425)',
 ROT='0',
 VER='1',
 PACK_TYPE='0402LF',
 LOCATION='R9034',
 CDS_LIB='pure_quanta',
 CDS_PART_NAME='Q_RES_0402LF-33.2,1%,1/16W,CHIP,CS03322FB03',
 PART_NUMBER='CS03322FB03',
 VALUE='33.2',
 PRIM_FILE='./archive_libs/logical/q_res/chips/chips.prt';

PART_NAME
 R9043 'Q_RES_0402LF-4.7K,5%,1/16W,CHIP,CS24702JB10':;

SECTION_NUMBER 1
 '@T6G_MB_LIB.T6G(SCH_1):PAGE299_I192@PURE_QUANTA.Q_RES(CHIPS)':
 C_PATH='@t6g_mb_lib.t6g(sch_1):page299_i192@pure_quanta.q_res(chips)',
 P_PATH='@t6g_mb_lib.t6g(sch_1):page126_i192@pure_quanta.q_res(chips)',
 PATH='I192',
 DRAWING='@T6G_MB_LIB.T6G(SCH_1):PAGE299',
 WATTAGE='1/16W',
 TOLERANCE='5%',
 MATERIAL='CHIP',
 PHYS_PAGE='126',
 XY='(2750,3875)',
 ROT='0',
 VER='2',
 PACK_TYPE='0402LF',
 LOCATION='R9043',
 CDS_LIB='pure_quanta',
 CDS_PART_NAME='Q_RES_0402LF-4.7K,5%,1/16W,CHIP,CS24702JB10',
 PART_NUMBER='CS24702JB10',
 VALUE='4.7K',
 PRIM_FILE='./archive_libs/logical/q_res/chips/chips.prt';

PART_NAME
 R9044 'Q_RES_0402LF-4.7K,1%,1/16W,EMPTY,CS24702FB06':;

SECTION_NUMBER 1
 '@T6G_MB_LIB.T6G(SCH_1):PAGE299_I195@PURE_QUANTA.Q_RES(CHIPS)':
 C_PATH='@t6g_mb_lib.t6g(sch_1):page299_i195@pure_quanta.q_res(chips)',
 P_PATH='@t6g_mb_lib.t6g(sch_1):page126_i195@pure_quanta.q_res(chips)',
 PATH='I195',
 DRAWING='@T6G_MB_LIB.T6G(SCH_1):PAGE299',
 WATTAGE='1/16W',
 TOLERANCE='1%',
 MATERIAL='EMPTY',
 PHYS_PAGE='126',
 XY='(3725,4175)',
 ROT='0',
 VER='2',
 PACK_TYPE='0402LF',
 LOCATION='R9044',
 CDS_LIB='pure_quanta',
 CDS_PART_NAME='Q_RES_0402LF-4.7K,1%,1/16W,EMPTY,CS24702FB06',
 PART_NUMBER='CS24702FB06',
 VALUE='4.7K',
 PRIM_FILE='./archive_libs/logical/q_res/chips/chips.prt';

PART_NAME
 R9273 'Q_RES_0402LF-0,5%,1/16W,CHIP,CS00002JB13':;

SECTION_NUMBER 1
 '@T6G_MB_LIB.T6G(SCH_1):PAGE28_I153@PURE_QUANTA.Q_RES(CHIPS)':
 C_PATH='@t6g_mb_lib.t6g(sch_1):page28_i153@pure_quanta.q_res(chips)',
 P_PATH='@t6g_mb_lib.t6g(sch_1):page28_i153@pure_quanta.q_res(chips)',
 PATH='I153',
 DRAWING='@T6G_MB_LIB.T6G(SCH_1):PAGE28',
 WATTAGE='1/16W',
 TOLERANCE='5%',
 MATERIAL='CHIP',
 PHYS_PAGE='28',
 XY='(-2000,11375)',
 ROT='0',
 VER='1',
 PACK_TYPE='0402LF',
 LOCATION='R9273',
 CDS_LIB='pure_quanta',
 CDS_PART_NAME='Q_RES_0402LF-0,5%,1/16W,CHIP,CS00002JB13',
 PART_NUMBER='CS00002JB13',
 VALUE='0',
 PRIM_FILE='./archive_libs/logical/q_res/chips/chips.prt';

PART_NAME
 R9274 'Q_RES_0402LF-0,5%,1/16W,CHIP,CS00002JB13':;

SECTION_NUMBER 1
 '@T6G_MB_LIB.T6G(SCH_1):PAGE28_I154@PURE_QUANTA.Q_RES(CHIPS)':
 C_PATH='@t6g_mb_lib.t6g(sch_1):page28_i154@pure_quanta.q_res(chips)',
 P_PATH='@t6g_mb_lib.t6g(sch_1):page28_i154@pure_quanta.q_res(chips)',
 PATH='I154',
 DRAWING='@T6G_MB_LIB.T6G(SCH_1):PAGE28',
 WATTAGE='1/16W',
 TOLERANCE='5%',
 MATERIAL='CHIP',
 PHYS_PAGE='28',
 XY='(-2000,11325)',
 ROT='0',
 VER='1',
 PACK_TYPE='0402LF',
 LOCATION='R9274',
 CDS_LIB='pure_quanta',
 CDS_PART_NAME='Q_RES_0402LF-0,5%,1/16W,CHIP,CS00002JB13',
 PART_NUMBER='CS00002JB13',
 VALUE='0',
 PRIM_FILE='./archive_libs/logical/q_res/chips/chips.prt';

PART_NAME
 R9275 'Q_RES_0402LF-0,5%,1/16W,CHIP,CS00002JB13':;

SECTION_NUMBER 1
 '@T6G_MB_LIB.T6G(SCH_1):PAGE28_I167@PURE_QUANTA.Q_RES(CHIPS)':
 C_PATH='@t6g_mb_lib.t6g(sch_1):page28_i167@pure_quanta.q_res(chips)',
 P_PATH='@t6g_mb_lib.t6g(sch_1):page28_i167@pure_quanta.q_res(chips)',
 PATH='I167',
 DRAWING='@T6G_MB_LIB.T6G(SCH_1):PAGE28',
 WATTAGE='1/16W',
 TOLERANCE='5%',
 MATERIAL='CHIP',
 PHYS_PAGE='28',
 XY='(-1975,11225)',
 ROT='0',
 VER='1',
 PACK_TYPE='0402LF',
 LOCATION='R9275',
 CDS_LIB='pure_quanta',
 CDS_PART_NAME='Q_RES_0402LF-0,5%,1/16W,CHIP,CS00002JB13',
 PART_NUMBER='CS00002JB13',
 VALUE='0',
 PRIM_FILE='./archive_libs/logical/q_res/chips/chips.prt';

PART_NAME
 R9276 'Q_RES_0402LF-0,5%,1/16W,CHIP,CS00002JB13':;

SECTION_NUMBER 1
 '@T6G_MB_LIB.T6G(SCH_1):PAGE28_I168@PURE_QUANTA.Q_RES(CHIPS)':
 C_PATH='@t6g_mb_lib.t6g(sch_1):page28_i168@pure_quanta.q_res(chips)',
 P_PATH='@t6g_mb_lib.t6g(sch_1):page28_i168@pure_quanta.q_res(chips)',
 PATH='I168',
 DRAWING='@T6G_MB_LIB.T6G(SCH_1):PAGE28',
 WATTAGE='1/16W',
 TOLERANCE='5%',
 MATERIAL='CHIP',
 PHYS_PAGE='28',
 XY='(-1975,11175)',
 ROT='0',
 VER='1',
 PACK_TYPE='0402LF',
 LOCATION='R9276',
 CDS_LIB='pure_quanta',
 CDS_PART_NAME='Q_RES_0402LF-0,5%,1/16W,CHIP,CS00002JB13',
 PART_NUMBER='CS00002JB13',
 VALUE='0',
 PRIM_FILE='./archive_libs/logical/q_res/chips/chips.prt';

PART_NAME
 R9446 'Q_RES_0402LF-33.2,1%,1/16W,CHIP,CS03322FB03':;

SECTION_NUMBER 1
 '@T6G_MB_LIB.T6G(SCH_1):PAGE368_I13@PURE_QUANTA.Q_RES(CHIPS)':
 C_PATH='@t6g_mb_lib.t6g(sch_1):page368_i13@pure_quanta.q_res(chips)',
 P_PATH='@t6g_mb_lib.t6g(sch_1):page253_i13@pure_quanta.q_res(chips)',
 PATH='I13',
 DRAWING='@T6G_MB_LIB.T6G(SCH_1):PAGE368',
 WATTAGE='1/16W',
 TOLERANCE='1%',
 MATERIAL='CHIP',
 PHYS_PAGE='253',
 XY='(-3500,4450)',
 ROT='0',
 VER='1',
 PACK_TYPE='0402LF',
 LOCATION='R9446',
 CDS_LIB='pure_quanta',
 CDS_PART_NAME='Q_RES_0402LF-33.2,1%,1/16W,CHIP,CS03322FB03',
 PART_NUMBER='CS03322FB03',
 VALUE='33.2',
 PRIM_FILE='./archive_libs/logical/q_res/chips/chips.prt';

PART_NAME
 R10287 'Q_RES_0402LF-10K,1%,1/16W,CHIP,CS31002FB08':;

SECTION_NUMBER 1
 '@T6G_MB_LIB.T6G(SCH_1):PAGE297_I79@PURE_QUANTA.Q_RES(CHIPS)':
 C_PATH='@t6g_mb_lib.t6g(sch_1):page297_i79@pure_quanta.q_res(chips)',
 P_PATH='@t6g_mb_lib.t6g(sch_1):page145_i79@pure_quanta.q_res(chips)',
 PATH='I79',
 DRAWING='@T6G_MB_LIB.T6G(SCH_1):PAGE297',
 WATTAGE='1/16W',
 TOLERANCE='1%',
 MATERIAL='CHIP',
 PHYS_PAGE='145',
 XY='(2900,4475)',
 ROT='0',
 VER='2',
 PACK_TYPE='0402LF',
 LOCATION='R10287',
 CDS_LIB='pure_quanta',
 CDS_PART_NAME='Q_RES_0402LF-10K,1%,1/16W,CHIP,CS31002FB08',
 PART_NUMBER='CS31002FB08',
 VALUE='10K',
 PRIM_FILE='./archive_libs/logical/q_res/chips/chips.prt';

PART_NAME
 R10296 'Q_RES_0402LF-1K,1%,1/16W,CHIP,CS21002FB06':;

SECTION_NUMBER 1
 '@T6G_MB_LIB.T6G(SCH_1):PAGE297_I6@PURE_QUANTA.Q_RES(CHIPS)':
 C_PATH='@t6g_mb_lib.t6g(sch_1):page297_i6@pure_quanta.q_res(chips)',
 P_PATH='@t6g_mb_lib.t6g(sch_1):page145_i6@pure_quanta.q_res(chips)',
 PATH='I6',
 DRAWING='@T6G_MB_LIB.T6G(SCH_1):PAGE297',
 WATTAGE='1/16W',
 TOLERANCE='1%',
 MATERIAL='CHIP',
 PHYS_PAGE='145',
 XY='(-2900,2150)',
 ROT='0',
 VER='2',
 PACK_TYPE='0402LF',
 LOCATION='R10296',
 CDS_LIB='pure_quanta',
 CDS_PART_NAME='Q_RES_0402LF-1K,1%,1/16W,CHIP,CS21002FB06',
 PART_NUMBER='CS21002FB06',
 VALUE='1K',
 PRIM_FILE='./archive_libs/logical/q_res/chips/chips.prt';

PART_NAME
 R11667 'Q_RES_0402LF-33.2,1%,1/16W,CHIP,CS03322FB03':;

SECTION_NUMBER 1
 '@T6G_MB_LIB.T6G(SCH_1):PAGE80_I274@PURE_QUANTA.Q_RES(CHIPS)':
 C_PATH='@t6g_mb_lib.t6g(sch_1):page80_i274@pure_quanta.q_res(chips)',
 P_PATH='@t6g_mb_lib.t6g(sch_1):page81_i274@pure_quanta.q_res(chips)',
 PATH='I274',
 DRAWING='@T6G_MB_LIB.T6G(SCH_1):PAGE80',
 WATTAGE='1/16W',
 TOLERANCE='1%',
 MATERIAL='CHIP',
 PHYS_PAGE='81',
 XY='(-2300,1475)',
 ROT='0',
 VER='1',
 PACK_TYPE='0402LF',
 LOCATION='R11667',
 CDS_LIB='pure_quanta',
 CDS_PART_NAME='Q_RES_0402LF-33.2,1%,1/16W,CHIP,CS03322FB03',
 PART_NUMBER='CS03322FB03',
 VALUE='33.2',
 PRIM_FILE='./archive_libs/logical/q_res/chips/chips.prt';

PART_NAME
 SW1 'SW20S_DHNF10FQTR-SW20S_DHNF-10F-Q-T/R,SMLF,MECH,DHA':;

SECTION_NUMBER 1
 '@T6G_MB_LIB.T6G(SCH_1):PAGE144_I90@PURE_QUANTA.SW20S_DHNF10FQTR(CHIPS)':
 C_PATH='@t6g_mb_lib.t6g(sch_1):page144_i90@pure_quanta.sw20s_dhnf10fqtr(chips)',
 P_PATH='@t6g_mb_lib.t6g(sch_1):page167_i90@pure_quanta.sw20s_dhnf10fqtr(chips)',
 PATH='I90',
 DRAWING='@T6G_MB_LIB.T6G(SCH_1):PAGE144',
 SEC_TYPE='',
 PART_TYPE='SMLF',
 MATERIAL='MECH',
 PHYS_PAGE='167',
 XY='(-7625,1075)',
 ROT='0',
 VER='1',
 LOCATION='SW1',
 SEC='1',
 CDS_LIB='pure_quanta',
 CDS_PART_NAME='SW20S_DHNF10FQTR-SW20S_DHNF-10F-Q-T/R,SMLF,MECH,DHA',
 PART_NUMBER='DHD00010F01',
 VALUE='SW20S_DHNF-10F-Q-T/R',
 PRIM_FILE='./archive_libs/logical/sw20s_dhnf10fqtr/chips/chips.prt';

PART_NAME
 TP1 'TP_TP-NA,TP26':;

SECTION_NUMBER 1
 '@T6G_MB_LIB.T6G(SCH_1):PAGE27_I404@PURE_QUANTA.TP(CHIPS)':
 C_PATH='@t6g_mb_lib.t6g(sch_1):page27_i404@pure_quanta.tp(chips)',
 P_PATH='@t6g_mb_lib.t6g(sch_1):page27_i404@pure_quanta.tp(chips)',
 PATH='I404',
 DRAWING='@T6G_MB_LIB.T6G(SCH_1):PAGE27',
 MATERIAL='NA',
 PHYS_PAGE='27',
 XY='(-6700,1625)',
 ROT='4',
 VER='1',
 PACK_TYPE='TP',
 LOCATION='TP1',
 CDS_LIB='pure_quanta',
 CDS_PART_NAME='TP_TP-NA,TP26',
 PART_NUMBER='TP26',
 PRIM_FILE='./archive_libs/logical/tp/chips/chips.prt';

PART_NAME
 TP2 'TP_TP-NA,TP30':;

SECTION_NUMBER 1
 '@T6G_MB_LIB.T6G(SCH_1):PAGE27_I362@PURE_QUANTA.TP(CHIPS)':
 C_PATH='@t6g_mb_lib.t6g(sch_1):page27_i362@pure_quanta.tp(chips)',
 P_PATH='@t6g_mb_lib.t6g(sch_1):page27_i362@pure_quanta.tp(chips)',
 PATH='I362',
 DRAWING='@T6G_MB_LIB.T6G(SCH_1):PAGE27',
 MATERIAL='NA',
 PHYS_PAGE='27',
 XY='(-6625,1625)',
 ROT='6',
 VER='1',
 PACK_TYPE='TP',
 LOCATION='TP2',
 CDS_LIB='pure_quanta',
 CDS_PART_NAME='TP_TP-NA,TP30',
 PART_NUMBER='TP30',
 PRIM_FILE='./archive_libs/logical/tp/chips/chips.prt';

PART_NAME
 TP3 'TP_TP-NA,TP30':;

SECTION_NUMBER 1
 '@T6G_MB_LIB.T6G(SCH_1):PAGE27_I361@PURE_QUANTA.TP(CHIPS)':
 C_PATH='@t6g_mb_lib.t6g(sch_1):page27_i361@pure_quanta.tp(chips)',
 P_PATH='@t6g_mb_lib.t6g(sch_1):page27_i361@pure_quanta.tp(chips)',
 PATH='I361',
 DRAWING='@T6G_MB_LIB.T6G(SCH_1):PAGE27',
 MATERIAL='NA',
 PHYS_PAGE='27',
 XY='(-6550,1625)',
 ROT='6',
 VER='1',
 PACK_TYPE='TP',
 LOCATION='TP3',
 CDS_LIB='pure_quanta',
 CDS_PART_NAME='TP_TP-NA,TP30',
 PART_NUMBER='TP30',
 PRIM_FILE='./archive_libs/logical/tp/chips/chips.prt';

PART_NAME
 TP4 'TP_TP-NA,TP30':;

SECTION_NUMBER 1
 '@T6G_MB_LIB.T6G(SCH_1):PAGE27_I360@PURE_QUANTA.TP(CHIPS)':
 C_PATH='@t6g_mb_lib.t6g(sch_1):page27_i360@pure_quanta.tp(chips)',
 P_PATH='@t6g_mb_lib.t6g(sch_1):page27_i360@pure_quanta.tp(chips)',
 PATH='I360',
 DRAWING='@T6G_MB_LIB.T6G(SCH_1):PAGE27',
 MATERIAL='NA',
 PHYS_PAGE='27',
 XY='(-6475,1625)',
 ROT='6',
 VER='1',
 PACK_TYPE='TP',
 LOCATION='TP4',
 CDS_LIB='pure_quanta',
 CDS_PART_NAME='TP_TP-NA,TP30',
 PART_NUMBER='TP30',
 PRIM_FILE='./archive_libs/logical/tp/chips/chips.prt';

PART_NAME
 TP5 'TP_TP-NA,TP30':;

SECTION_NUMBER 1
 '@T6G_MB_LIB.T6G(SCH_1):PAGE27_I359@PURE_QUANTA.TP(CHIPS)':
 C_PATH='@t6g_mb_lib.t6g(sch_1):page27_i359@pure_quanta.tp(chips)',
 P_PATH='@t6g_mb_lib.t6g(sch_1):page27_i359@pure_quanta.tp(chips)',
 PATH='I359',
 DRAWING='@T6G_MB_LIB.T6G(SCH_1):PAGE27',
 MATERIAL='NA',
 PHYS_PAGE='27',
 XY='(-6350,1625)',
 ROT='6',
 VER='1',
 PACK_TYPE='TP',
 LOCATION='TP5',
 CDS_LIB='pure_quanta',
 CDS_PART_NAME='TP_TP-NA,TP30',
 PART_NUMBER='TP30',
 PRIM_FILE='./archive_libs/logical/tp/chips/chips.prt';

PART_NAME
 TP6 'TP_TP-NA,TP30':;

SECTION_NUMBER 1
 '@T6G_MB_LIB.T6G(SCH_1):PAGE27_I358@PURE_QUANTA.TP(CHIPS)':
 C_PATH='@t6g_mb_lib.t6g(sch_1):page27_i358@pure_quanta.tp(chips)',
 P_PATH='@t6g_mb_lib.t6g(sch_1):page27_i358@pure_quanta.tp(chips)',
 PATH='I358',
 DRAWING='@T6G_MB_LIB.T6G(SCH_1):PAGE27',
 MATERIAL='NA',
 PHYS_PAGE='27',
 XY='(-6275,1625)',
 ROT='6',
 VER='1',
 PACK_TYPE='TP',
 LOCATION='TP6',
 CDS_LIB='pure_quanta',
 CDS_PART_NAME='TP_TP-NA,TP30',
 PART_NUMBER='TP30',
 PRIM_FILE='./archive_libs/logical/tp/chips/chips.prt';

PART_NAME
 TP7 'TP_TP-NA,TP30':;

SECTION_NUMBER 1
 '@T6G_MB_LIB.T6G(SCH_1):PAGE27_I357@PURE_QUANTA.TP(CHIPS)':
 C_PATH='@t6g_mb_lib.t6g(sch_1):page27_i357@pure_quanta.tp(chips)',
 P_PATH='@t6g_mb_lib.t6g(sch_1):page27_i357@pure_quanta.tp(chips)',
 PATH='I357',
 DRAWING='@T6G_MB_LIB.T6G(SCH_1):PAGE27',
 MATERIAL='NA',
 PHYS_PAGE='27',
 XY='(-6200,1625)',
 ROT='6',
 VER='1',
 PACK_TYPE='TP',
 LOCATION='TP7',
 CDS_LIB='pure_quanta',
 CDS_PART_NAME='TP_TP-NA,TP30',
 PART_NUMBER='TP30',
 PRIM_FILE='./archive_libs/logical/tp/chips/chips.prt';

PART_NAME
 TP8 'TP_TP-NA,TP30':;

SECTION_NUMBER 1
 '@T6G_MB_LIB.T6G(SCH_1):PAGE27_I356@PURE_QUANTA.TP(CHIPS)':
 C_PATH='@t6g_mb_lib.t6g(sch_1):page27_i356@pure_quanta.tp(chips)',
 P_PATH='@t6g_mb_lib.t6g(sch_1):page27_i356@pure_quanta.tp(chips)',
 PATH='I356',
 DRAWING='@T6G_MB_LIB.T6G(SCH_1):PAGE27',
 MATERIAL='NA',
 PHYS_PAGE='27',
 XY='(-6125,1625)',
 ROT='6',
 VER='1',
 PACK_TYPE='TP',
 LOCATION='TP8',
 CDS_LIB='pure_quanta',
 CDS_PART_NAME='TP_TP-NA,TP30',
 PART_NUMBER='TP30',
 PRIM_FILE='./archive_libs/logical/tp/chips/chips.prt';

PART_NAME
 TP9 'TP_TP-NA,TP30':;

SECTION_NUMBER 1
 '@T6G_MB_LIB.T6G(SCH_1):PAGE27_I355@PURE_QUANTA.TP(CHIPS)':
 C_PATH='@t6g_mb_lib.t6g(sch_1):page27_i355@pure_quanta.tp(chips)',
 P_PATH='@t6g_mb_lib.t6g(sch_1):page27_i355@pure_quanta.tp(chips)',
 PATH='I355',
 DRAWING='@T6G_MB_LIB.T6G(SCH_1):PAGE27',
 MATERIAL='NA',
 PHYS_PAGE='27',
 XY='(-5975,1625)',
 ROT='6',
 VER='1',
 PACK_TYPE='TP',
 LOCATION='TP9',
 CDS_LIB='pure_quanta',
 CDS_PART_NAME='TP_TP-NA,TP30',
 PART_NUMBER='TP30',
 PRIM_FILE='./archive_libs/logical/tp/chips/chips.prt';

PART_NAME
 TP10 'TP_TP-NA,TP26':;

SECTION_NUMBER 1
 '@T6G_MB_LIB.T6G(SCH_1):PAGE27_I403@PURE_QUANTA.TP(CHIPS)':
 C_PATH='@t6g_mb_lib.t6g(sch_1):page27_i403@pure_quanta.tp(chips)',
 P_PATH='@t6g_mb_lib.t6g(sch_1):page27_i403@pure_quanta.tp(chips)',
 PATH='I403',
 DRAWING='@T6G_MB_LIB.T6G(SCH_1):PAGE27',
 MATERIAL='NA',
 PHYS_PAGE='27',
 XY='(-5900,1625)',
 ROT='4',
 VER='1',
 PACK_TYPE='TP',
 LOCATION='TP10',
 CDS_LIB='pure_quanta',
 CDS_PART_NAME='TP_TP-NA,TP26',
 PART_NUMBER='TP26',
 PRIM_FILE='./archive_libs/logical/tp/chips/chips.prt';

PART_NAME
 TP11 'TP_TP-NA,TP30':;

SECTION_NUMBER 1
 '@T6G_MB_LIB.T6G(SCH_1):PAGE54_I273@PURE_QUANTA.TP(CHIPS)':
 C_PATH='@t6g_mb_lib.t6g(sch_1):page54_i273@pure_quanta.tp(chips)',
 P_PATH='@t6g_mb_lib.t6g(sch_1):page54_i273@pure_quanta.tp(chips)',
 PATH='I273',
 DRAWING='@T6G_MB_LIB.T6G(SCH_1):PAGE54',
 MATERIAL='NA',
 PHYS_PAGE='54',
 XY='(-6900,1900)',
 ROT='6',
 VER='1',
 PACK_TYPE='TP',
 LOCATION='TP11',
 CDS_LIB='pure_quanta',
 CDS_PART_NAME='TP_TP-NA,TP30',
 PART_NUMBER='TP30',
 PRIM_FILE='./archive_libs/logical/tp/chips/chips.prt';

PART_NAME
 TP12 'TP_TP-NA,TP30':;

SECTION_NUMBER 1
 '@T6G_MB_LIB.T6G(SCH_1):PAGE54_I272@PURE_QUANTA.TP(CHIPS)':
 C_PATH='@t6g_mb_lib.t6g(sch_1):page54_i272@pure_quanta.tp(chips)',
 P_PATH='@t6g_mb_lib.t6g(sch_1):page54_i272@pure_quanta.tp(chips)',
 PATH='I272',
 DRAWING='@T6G_MB_LIB.T6G(SCH_1):PAGE54',
 MATERIAL='NA',
 PHYS_PAGE='54',
 XY='(-6825,1900)',
 ROT='6',
 VER='1',
 PACK_TYPE='TP',
 LOCATION='TP12',
 CDS_LIB='pure_quanta',
 CDS_PART_NAME='TP_TP-NA,TP30',
 PART_NUMBER='TP30',
 PRIM_FILE='./archive_libs/logical/tp/chips/chips.prt';

PART_NAME
 TP13 'TP_TP-NA,TP30':;

SECTION_NUMBER 1
 '@T6G_MB_LIB.T6G(SCH_1):PAGE54_I245@PURE_QUANTA.TP(CHIPS)':
 C_PATH='@t6g_mb_lib.t6g(sch_1):page54_i245@pure_quanta.tp(chips)',
 P_PATH='@t6g_mb_lib.t6g(sch_1):page54_i245@pure_quanta.tp(chips)',
 PATH='I245',
 DRAWING='@T6G_MB_LIB.T6G(SCH_1):PAGE54',
 MATERIAL='NA',
 PHYS_PAGE='54',
 XY='(-6750,1900)',
 ROT='6',
 VER='1',
 PACK_TYPE='TP',
 LOCATION='TP13',
 CDS_LIB='pure_quanta',
 CDS_PART_NAME='TP_TP-NA,TP30',
 PART_NUMBER='TP30',
 PRIM_FILE='./archive_libs/logical/tp/chips/chips.prt';

PART_NAME
 TP14 'TP_TP-NA,TP30':;

SECTION_NUMBER 1
 '@T6G_MB_LIB.T6G(SCH_1):PAGE54_I244@PURE_QUANTA.TP(CHIPS)':
 C_PATH='@t6g_mb_lib.t6g(sch_1):page54_i244@pure_quanta.tp(chips)',
 P_PATH='@t6g_mb_lib.t6g(sch_1):page54_i244@pure_quanta.tp(chips)',
 PATH='I244',
 DRAWING='@T6G_MB_LIB.T6G(SCH_1):PAGE54',
 MATERIAL='NA',
 PHYS_PAGE='54',
 XY='(-6675,1900)',
 ROT='6',
 VER='1',
 PACK_TYPE='TP',
 LOCATION='TP14',
 CDS_LIB='pure_quanta',
 CDS_PART_NAME='TP_TP-NA,TP30',
 PART_NUMBER='TP30',
 PRIM_FILE='./archive_libs/logical/tp/chips/chips.prt';

PART_NAME
 TP15 'TP_TP-NA,TP30':;

SECTION_NUMBER 1
 '@T6G_MB_LIB.T6G(SCH_1):PAGE54_I243@PURE_QUANTA.TP(CHIPS)':
 C_PATH='@t6g_mb_lib.t6g(sch_1):page54_i243@pure_quanta.tp(chips)',
 P_PATH='@t6g_mb_lib.t6g(sch_1):page54_i243@pure_quanta.tp(chips)',
 PATH='I243',
 DRAWING='@T6G_MB_LIB.T6G(SCH_1):PAGE54',
 MATERIAL='NA',
 PHYS_PAGE='54',
 XY='(-6550,1900)',
 ROT='6',
 VER='1',
 PACK_TYPE='TP',
 LOCATION='TP15',
 CDS_LIB='pure_quanta',
 CDS_PART_NAME='TP_TP-NA,TP30',
 PART_NUMBER='TP30',
 PRIM_FILE='./archive_libs/logical/tp/chips/chips.prt';

PART_NAME
 TP16 'TP_TP-NA,TP30':;

SECTION_NUMBER 1
 '@T6G_MB_LIB.T6G(SCH_1):PAGE54_I242@PURE_QUANTA.TP(CHIPS)':
 C_PATH='@t6g_mb_lib.t6g(sch_1):page54_i242@pure_quanta.tp(chips)',
 P_PATH='@t6g_mb_lib.t6g(sch_1):page54_i242@pure_quanta.tp(chips)',
 PATH='I242',
 DRAWING='@T6G_MB_LIB.T6G(SCH_1):PAGE54',
 MATERIAL='NA',
 PHYS_PAGE='54',
 XY='(-6475,1900)',
 ROT='6',
 VER='1',
 PACK_TYPE='TP',
 LOCATION='TP16',
 CDS_LIB='pure_quanta',
 CDS_PART_NAME='TP_TP-NA,TP30',
 PART_NUMBER='TP30',
 PRIM_FILE='./archive_libs/logical/tp/chips/chips.prt';

PART_NAME
 TP17 'TP_TP-NA,TP30':;

SECTION_NUMBER 1
 '@T6G_MB_LIB.T6G(SCH_1):PAGE54_I241@PURE_QUANTA.TP(CHIPS)':
 C_PATH='@t6g_mb_lib.t6g(sch_1):page54_i241@pure_quanta.tp(chips)',
 P_PATH='@t6g_mb_lib.t6g(sch_1):page54_i241@pure_quanta.tp(chips)',
 PATH='I241',
 DRAWING='@T6G_MB_LIB.T6G(SCH_1):PAGE54',
 MATERIAL='NA',
 PHYS_PAGE='54',
 XY='(-6400,1900)',
 ROT='6',
 VER='1',
 PACK_TYPE='TP',
 LOCATION='TP17',
 CDS_LIB='pure_quanta',
 CDS_PART_NAME='TP_TP-NA,TP30',
 PART_NUMBER='TP30',
 PRIM_FILE='./archive_libs/logical/tp/chips/chips.prt';

PART_NAME
 TP18 'TP_TP-NA,TP30':;

SECTION_NUMBER 1
 '@T6G_MB_LIB.T6G(SCH_1):PAGE54_I240@PURE_QUANTA.TP(CHIPS)':
 C_PATH='@t6g_mb_lib.t6g(sch_1):page54_i240@pure_quanta.tp(chips)',
 P_PATH='@t6g_mb_lib.t6g(sch_1):page54_i240@pure_quanta.tp(chips)',
 PATH='I240',
 DRAWING='@T6G_MB_LIB.T6G(SCH_1):PAGE54',
 MATERIAL='NA',
 PHYS_PAGE='54',
 XY='(-6325,1900)',
 ROT='6',
 VER='1',
 PACK_TYPE='TP',
 LOCATION='TP18',
 CDS_LIB='pure_quanta',
 CDS_PART_NAME='TP_TP-NA,TP30',
 PART_NUMBER='TP30',
 PRIM_FILE='./archive_libs/logical/tp/chips/chips.prt';

PART_NAME
 TP19 'TP_TP-NA,TP30':;

SECTION_NUMBER 1
 '@T6G_MB_LIB.T6G(SCH_1):PAGE54_I238@PURE_QUANTA.TP(CHIPS)':
 C_PATH='@t6g_mb_lib.t6g(sch_1):page54_i238@pure_quanta.tp(chips)',
 P_PATH='@t6g_mb_lib.t6g(sch_1):page54_i238@pure_quanta.tp(chips)',
 PATH='I238',
 DRAWING='@T6G_MB_LIB.T6G(SCH_1):PAGE54',
 MATERIAL='NA',
 PHYS_PAGE='54',
 XY='(-6225,1900)',
 ROT='6',
 VER='1',
 PACK_TYPE='TP',
 LOCATION='TP19',
 CDS_LIB='pure_quanta',
 CDS_PART_NAME='TP_TP-NA,TP30',
 PART_NUMBER='TP30',
 PRIM_FILE='./archive_libs/logical/tp/chips/chips.prt';

PART_NAME
 TP20 'TP_TP-NA,TP30':;

SECTION_NUMBER 1
 '@T6G_MB_LIB.T6G(SCH_1):PAGE54_I237@PURE_QUANTA.TP(CHIPS)':
 C_PATH='@t6g_mb_lib.t6g(sch_1):page54_i237@pure_quanta.tp(chips)',
 P_PATH='@t6g_mb_lib.t6g(sch_1):page54_i237@pure_quanta.tp(chips)',
 PATH='I237',
 DRAWING='@T6G_MB_LIB.T6G(SCH_1):PAGE54',
 MATERIAL='NA',
 PHYS_PAGE='54',
 XY='(-6150,1900)',
 ROT='6',
 VER='1',
 PACK_TYPE='TP',
 LOCATION='TP20',
 CDS_LIB='pure_quanta',
 CDS_PART_NAME='TP_TP-NA,TP30',
 PART_NUMBER='TP30',
 PRIM_FILE='./archive_libs/logical/tp/chips/chips.prt';

PART_NAME
 U1 'M24128BWMN6TP-M24128-BWMN6TP,SMLF,IC,AKE30Z00613':;

SECTION_NUMBER 1
 '@T6G_MB_LIB.T6G(SCH_1):PAGE361_I97@PURE_QUANTA.M24128BWMN6TP(CHIPS)':
 C_PATH='@t6g_mb_lib.t6g(sch_1):page361_i97@pure_quanta.m24128bwmn6tp(chips)',
 P_PATH='@t6g_mb_lib.t6g(sch_1):page238_i97@pure_quanta.m24128bwmn6tp(chips)',
 PATH='I97',
 DRAWING='@T6G_MB_LIB.T6G(SCH_1):PAGE361',
 PART_TYPE='SMLF',
 MATERIAL='IC',
 PHYS_PAGE='238',
 XY='(-225,1075)',
 ROT='0',
 VER='1',
 LOCATION='U1',
 CDS_LIB='pure_quanta',
 CDS_PART_NAME='M24128BWMN6TP-M24128-BWMN6TP,SMLF,IC,AKE30Z00613',
 PART_NUMBER='AKE30Z00613',
 VALUE='M24128-BWMN6TP',
 PRIM_FILE='./archive_libs/logical/m24128bwmn6tp/chips/chips.prt';

PART_NAME
 U2 'PCA9617ADP-PCA9617ADP,SMLF,IC,AL009617K02':;

SECTION_NUMBER 1
 '@T6G_MB_LIB.T6G(SCH_1):PAGE137_I99@PURE_QUANTA.PCA9617ADP(CHIPS)':
 C_PATH='@t6g_mb_lib.t6g(sch_1):page137_i99@pure_quanta.pca9617adp(chips)',
 P_PATH='@t6g_mb_lib.t6g(sch_1):page160_i99@pure_quanta.pca9617adp(chips)',
 PATH='I99',
 DRAWING='@T6G_MB_LIB.T6G(SCH_1):PAGE137',
 SEC_TYPE='',
 PART_TYPE='SMLF',
 MATERIAL='IC',
 PHYS_PAGE='160',
 XY='(-6000,750)',
 ROT='2',
 VER='1',
 LOCATION='U2',
 SEC='1',
 CDS_LIB='pure_quanta',
 CDS_PART_NAME='PCA9617ADP-PCA9617ADP,SMLF,IC,AL009617K02',
 PART_NUMBER='AL009617K02',
 VALUE='PCA9617ADP',
 PRIM_FILE='./archive_libs/logical/pca9617adp/chips/chips.prt';

PART_NAME
 U3 'SN74LVC1G07DBVR_SMLF-SN74LVC1G07DBVR,IC,AL1G0007024':;

SECTION_NUMBER 1
 '@T6G_MB_LIB.T6G(SCH_1):PAGE29_I373@PURE_QUANTA.SN74LVC1G07DBVR(CHIPS)':
 C_PATH='@t6g_mb_lib.t6g(sch_1):page29_i373@pure_quanta.sn74lvc1g07dbvr(chips)',
 P_PATH='@t6g_mb_lib.t6g(sch_1):page29_i373@pure_quanta.sn74lvc1g07dbvr(chips)',
 PATH='I373',
 DRAWING='@T6G_MB_LIB.T6G(SCH_1):PAGE29',
 MATERIAL='IC',
 PHYS_PAGE='29',
 XY='(-3375,2175)',
 ROT='0',
 VER='1',
 PACK_TYPE='SMLF',
 LOCATION='U3',
 CDS_LIB='pure_quanta',
 CDS_PART_NAME='SN74LVC1G07DBVR_SMLF-SN74LVC1G07DBVR,IC,AL1G0007024',
 PART_NUMBER='AL1G0007024',
 VALUE='SN74LVC1G07DBVR',
 PRIM_FILE='./archive_libs/logical/sn74lvc1g07dbvr/chips/chips.prt';

PART_NAME
 U4 'PI3CSW12ZUAEX-PI3CSW12ZUAEX,SMLF,IC,AL3CSW12000':;

SECTION_NUMBER 1
 '@T6G_MB_LIB.T6G(SCH_1):PAGE138_I114@PURE_QUANTA.PI3CSW12ZUAEX(CHIPS)':
 C_PATH='@t6g_mb_lib.t6g(sch_1):page138_i114@pure_quanta.pi3csw12zuaex(chips)',
 P_PATH='@t6g_mb_lib.t6g(sch_1):page161_i114@pure_quanta.pi3csw12zuaex(chips)',
 PATH='I114',
 DRAWING='@T6G_MB_LIB.T6G(SCH_1):PAGE138',
 SEC_TYPE='',
 PART_TYPE='SMLF',
 MATERIAL='IC',
 PHYS_PAGE='161',
 XY='(4600,5450)',
 ROT='2',
 VER='1',
 LOCATION='U4',
 SEC='1',
 CDS_LIB='pure_quanta',
 CDS_PART_NAME='PI3CSW12ZUAEX-PI3CSW12ZUAEX,SMLF,IC,AL3CSW12000',
 PART_NUMBER='AL3CSW12000',
 VALUE='PI3CSW12ZUAEX',
 PRIM_FILE='./archive_libs/logical/pi3csw12zuaex/chips/chips.prt';

PART_NAME
 U5 'PCA9617ADP-PCA9617ADP,SMLF,EMPTY,AL009617K02':;

SECTION_NUMBER 1
 '@T6G_MB_LIB.T6G(SCH_1):PAGE137_I48@PURE_QUANTA.PCA9617ADP(CHIPS)':
 C_PATH='@t6g_mb_lib.t6g(sch_1):page137_i48@pure_quanta.pca9617adp(chips)',
 P_PATH='@t6g_mb_lib.t6g(sch_1):page160_i48@pure_quanta.pca9617adp(chips)',
 PATH='I48',
 DRAWING='@T6G_MB_LIB.T6G(SCH_1):PAGE137',
 PART_TYPE='SMLF',
 MATERIAL='EMPTY',
 PHYS_PAGE='160',
 XY='(-5975,2300)',
 ROT='0',
 VER='1',
 LOCATION='U5',
 CDS_LIB='pure_quanta',
 CDS_PART_NAME='PCA9617ADP-PCA9617ADP,SMLF,EMPTY,AL009617K02',
 PART_NUMBER='AL009617K02',
 VALUE='PCA9617ADP',
 PRIM_FILE='./archive_libs/logical/pca9617adp/chips/chips.prt';

PART_NAME
 U6 'PI3CSW12ZUAEX-PI3CSW12ZUAEX,SMLF,IC,AL3CSW12000':;

SECTION_NUMBER 1
 '@T6G_MB_LIB.T6G(SCH_1):PAGE138_I67@PURE_QUANTA.PI3CSW12ZUAEX(CHIPS)':
 C_PATH='@t6g_mb_lib.t6g(sch_1):page138_i67@pure_quanta.pi3csw12zuaex(chips)',
 P_PATH='@t6g_mb_lib.t6g(sch_1):page161_i67@pure_quanta.pi3csw12zuaex(chips)',
 PATH='I67',
 DRAWING='@T6G_MB_LIB.T6G(SCH_1):PAGE138',
 SEC_TYPE='',
 PART_TYPE='SMLF',
 MATERIAL='IC',
 PHYS_PAGE='161',
 XY='(1625,1925)',
 ROT='2',
 VER='1',
 LOCATION='U6',
 SEC='1',
 CDS_LIB='pure_quanta',
 CDS_PART_NAME='PI3CSW12ZUAEX-PI3CSW12ZUAEX,SMLF,IC,AL3CSW12000',
 PART_NUMBER='AL3CSW12000',
 VALUE='PI3CSW12ZUAEX',
 PRIM_FILE='./archive_libs/logical/pi3csw12zuaex/chips/chips.prt';

PART_NAME
 U7 '74CBTLV3126PW-74CBTLV3126PW,SMLF,IC,AL003126K08':;

SECTION_NUMBER 1
 '@T6G_MB_LIB.T6G(SCH_1):PAGE336_I2@PURE_QUANTA.74CBTLV3126PW(CHIPS)':
 C_PATH='@t6g_mb_lib.t6g(sch_1):page336_i2@pure_quanta.\74cbtlv3126pw\(chips)',
 P_PATH='@t6g_mb_lib.t6g(sch_1):page132_i2@pure_quanta.\74cbtlv3126pw\(chips)',
 PATH='I2',
 DRAWING='@T6G_MB_LIB.T6G(SCH_1):PAGE336',
 PART_TYPE='SMLF',
 MATERIAL='IC',
 PHYS_PAGE='132',
 XY='(-225,5275)',
 ROT='2',
 VER='1',
 LOCATION='U7',
 CDS_LIB='pure_quanta',
 CDS_PART_NAME='74CBTLV3126PW-74CBTLV3126PW,SMLF,IC,AL003126K08',
 PART_NUMBER='AL003126K08',
 VALUE='74CBTLV3126PW',
 PRIM_FILE='./archive_libs/logical/74cbtlv3126pw/chips/chips.prt';

PART_NAME
 U8 '74LVC2G07DW7-74LVC2G07DW-7,SMLF,IC,AL002G07003':;

SECTION_NUMBER 1
 '@T6G_MB_LIB.T6G(SCH_1):PAGE338_I26@PURE_QUANTA.74LVC2G07DW7(CHIPS)':
 C_PATH='@t6g_mb_lib.t6g(sch_1):page338_i26@pure_quanta.\74lvc2g07dw7\(chips)',
 P_PATH='@t6g_mb_lib.t6g(sch_1):page134_i26@pure_quanta.\74lvc2g07dw7\(chips)',
 PATH='I26',
 DRAWING='@T6G_MB_LIB.T6G(SCH_1):PAGE338',
 PART_TYPE='SMLF',
 MATERIAL='IC',
 PHYS_PAGE='134',
 XY='(5275,8550)',
 ROT='0',
 VER='1',
 LOCATION='U8',
 CDS_LIB='pure_quanta',
 CDS_PART_NAME='74LVC2G07DW7-74LVC2G07DW-7,SMLF,IC,AL002G07003',
 PART_NUMBER='AL002G07003',
 VALUE='74LVC2G07DW-7',
 PRIM_FILE='./archive_libs/logical/74lvc2g07dw7/chips/chips.prt';

PART_NAME
 U9 'TPS71715DCKR-TPS71715DCKR,SMLF,EMPTY,AL071715001':;

SECTION_NUMBER 1
 '@T6G_MB_LIB.T6G(SCH_1):PAGE156_I91@PURE_QUANTA.TPS71715DCKR(CHIPS)':
 C_PATH='@t6g_mb_lib.t6g(sch_1):page156_i91@pure_quanta.tps71715dckr(chips)',
 P_PATH='@t6g_mb_lib.t6g(sch_1):page187_i91@pure_quanta.tps71715dckr(chips)',
 PATH='I91',
 DRAWING='@T6G_MB_LIB.T6G(SCH_1):PAGE156',
 SEC_TYPE='',
 PART_TYPE='SMLF',
 MATERIAL='EMPTY',
 PHYS_PAGE='187',
 XY='(-4725,3650)',
 ROT='0',
 VER='1',
 LOCATION='U9',
 SEC='1',
 CDS_LIB='pure_quanta',
 CDS_PART_NAME='TPS71715DCKR-TPS71715DCKR,SMLF,EMPTY,AL071715001',
 PART_NUMBER='AL071715001',
 VALUE='TPS71715DCKR',
 PRIM_FILE='./archive_libs/logical/tps71715dckr/chips/chips.prt';

PART_NAME
 U10 '9ZXL0451EKILFT-9ZXL0451EKILFT,SMLF,IC,AL000451003':;

SECTION_NUMBER 1
 '@T6G_MB_LIB.T6G(SCH_1):PAGE379_I63@PURE_QUANTA.9ZXL0451EKILFT(CHIPS)':
 C_PATH='@t6g_mb_lib.t6g(sch_1):page379_i63@pure_quanta.\9zxl0451ekilft\(chips)',
 P_PATH='@t6g_mb_lib.t6g(sch_1):page183_i63@pure_quanta.\9zxl0451ekilft\(chips)',
 PATH='I63',
 DRAWING='@T6G_MB_LIB.T6G(SCH_1):PAGE379',
 PART_TYPE='SMLF',
 MATERIAL='IC',
 PHYS_PAGE='183',
 XY='(-4525,3475)',
 ROT='0',
 VER='1',
 LOCATION='U10',
 CDS_LIB='pure_quanta',
 CDS_PART_NAME='9ZXL0451EKILFT-9ZXL0451EKILFT,SMLF,IC,AL000451003',
 PART_NUMBER='AL000451003',
 VALUE='9ZXL0451EKILFT',
 PRIM_FILE='./archive_libs/logical/9zxl0451ekilft/chips/chips.prt';

PART_NAME
 U11 'M24M02DRMN6TP-M24M02-DRMN6TP,SMLF,IC,AKE33Z00600':;

SECTION_NUMBER 1
 '@T6G_MB_LIB.T6G(SCH_1):PAGE387_I3@PURE_QUANTA.M24M02DRMN6TP(CHIPS)':
 C_PATH='@t6g_mb_lib.t6g(sch_1):page387_i3@pure_quanta.m24m02drmn6tp(chips)',
 P_PATH='@t6g_mb_lib.t6g(sch_1):page278_i3@pure_quanta.m24m02drmn6tp(chips)',
 PATH='I3',
 DRAWING='@T6G_MB_LIB.T6G(SCH_1):PAGE387',
 PART_TYPE='SMLF',
 MATERIAL='IC',
 PHYS_PAGE='278',
 XY='(-4425,4550)',
 ROT='0',
 VER='1',
 LOCATION='U11',
 CDS_LIB='pure_quanta',
 CDS_PART_NAME='M24M02DRMN6TP-M24M02-DRMN6TP,SMLF,IC,AKE33Z00600',
 PART_NUMBER='AKE33Z00600',
 VALUE='M24M02-DRMN6TP',
 PRIM_FILE='./archive_libs/logical/m24m02drmn6tp/chips/chips.prt';

PART_NAME
 U12 'M24M02DRMN6TP-M24M02-DRMN6TP,SMLF,IC,AKE33Z00600':;

SECTION_NUMBER 1
 '@T6G_MB_LIB.T6G(SCH_1):PAGE399_I5@PURE_QUANTA.M24M02DRMN6TP(CHIPS)':
 C_PATH='@t6g_mb_lib.t6g(sch_1):page399_i5@pure_quanta.m24m02drmn6tp(chips)',
 P_PATH='@t6g_mb_lib.t6g(sch_1):page322_i5@pure_quanta.m24m02drmn6tp(chips)',
 PATH='I5',
 DRAWING='@T6G_MB_LIB.T6G(SCH_1):PAGE399',
 PART_TYPE='SMLF',
 MATERIAL='IC',
 PHYS_PAGE='322',
 XY='(-4025,5125)',
 ROT='0',
 VER='1',
 LOCATION='U12',
 CDS_LIB='pure_quanta',
 CDS_PART_NAME='M24M02DRMN6TP-M24M02-DRMN6TP,SMLF,IC,AKE33Z00600',
 PART_NUMBER='AKE33Z00600',
 VALUE='M24M02-DRMN6TP',
 PRIM_FILE='./archive_libs/logical/m24m02drmn6tp/chips/chips.prt';

PART_NAME
 U13 'SN74AUC2G66DCTR-SN74AUC2G66DCTR,SMLF,IC,AL2G0066C00':;

SECTION_NUMBER 1
 '@T6G_MB_LIB.T6G(SCH_1):PAGE151_I17@PURE_QUANTA.SN74AUC2G66DCTR(CHIPS)':
 C_PATH='@t6g_mb_lib.t6g(sch_1):page151_i17@pure_quanta.sn74auc2g66dctr(chips)',
 P_PATH='@t6g_mb_lib.t6g(sch_1):page174_i17@pure_quanta.sn74auc2g66dctr(chips)',
 PATH='I17',
 DRAWING='@T6G_MB_LIB.T6G(SCH_1):PAGE151',
 SEC_TYPE='',
 PART_TYPE='SMLF',
 MATERIAL='IC',
 PHYS_PAGE='174',
 XY='(-4975,4450)',
 ROT='0',
 VER='1',
 LOCATION='U13',
 SEC='1',
 CDS_LIB='pure_quanta',
 CDS_PART_NAME='SN74AUC2G66DCTR-SN74AUC2G66DCTR,SMLF,IC,AL2G0066C00',
 PART_NUMBER='AL2G0066C00',
 VALUE='SN74AUC2G66DCTR',
 PRIM_FILE='./archive_libs/logical/sn74auc2g66dctr/chips/chips.prt';

PART_NAME
 U14 'SN74AUC2G66DCTR-SN74AUC2G66DCTR,SMLF,IC,AL2G0066C00':;

SECTION_NUMBER 1
 '@T6G_MB_LIB.T6G(SCH_1):PAGE151_I23@PURE_QUANTA.SN74AUC2G66DCTR(CHIPS)':
 C_PATH='@t6g_mb_lib.t6g(sch_1):page151_i23@pure_quanta.sn74auc2g66dctr(chips)',
 P_PATH='@t6g_mb_lib.t6g(sch_1):page174_i23@pure_quanta.sn74auc2g66dctr(chips)',
 PATH='I23',
 DRAWING='@T6G_MB_LIB.T6G(SCH_1):PAGE151',
 SEC_TYPE='',
 PART_TYPE='SMLF',
 MATERIAL='IC',
 PHYS_PAGE='174',
 XY='(-3125,4400)',
 ROT='0',
 VER='1',
 LOCATION='U14',
 SEC='1',
 CDS_LIB='pure_quanta',
 CDS_PART_NAME='SN74AUC2G66DCTR-SN74AUC2G66DCTR,SMLF,IC,AL2G0066C00',
 PART_NUMBER='AL2G0066C00',
 VALUE='SN74AUC2G66DCTR',
 PRIM_FILE='./archive_libs/logical/sn74auc2g66dctr/chips/chips.prt';

PART_NAME
 U15 'M24M02DRMN6TP-M24M02-DRMN6TP,SMLF,IC,AKE33Z00600':;

SECTION_NUMBER 1
 '@T6G_MB_LIB.T6G(SCH_1):PAGE410_I5@PURE_QUANTA.M24M02DRMN6TP(CHIPS)':
 C_PATH='@t6g_mb_lib.t6g(sch_1):page410_i5@pure_quanta.m24m02drmn6tp(chips)',
 P_PATH='@t6g_mb_lib.t6g(sch_1):page289_i5@pure_quanta.m24m02drmn6tp(chips)',
 PATH='I5',
 DRAWING='@T6G_MB_LIB.T6G(SCH_1):PAGE410',
 PART_TYPE='SMLF',
 MATERIAL='IC',
 PHYS_PAGE='289',
 XY='(-3750,5575)',
 ROT='0',
 VER='1',
 LOCATION='U15',
 CDS_LIB='pure_quanta',
 CDS_PART_NAME='M24M02DRMN6TP-M24M02-DRMN6TP,SMLF,IC,AKE33Z00600',
 PART_NUMBER='AKE33Z00600',
 VALUE='M24M02-DRMN6TP',
 PRIM_FILE='./archive_libs/logical/m24m02drmn6tp/chips/chips.prt';

PART_NAME
 U16 'M24M02DRMN6TP-M24M02-DRMN6TP,SMLF,IC,AKE33Z00600':;

SECTION_NUMBER 1
 '@T6G_MB_LIB.T6G(SCH_1):PAGE421_I5@PURE_QUANTA.M24M02DRMN6TP(CHIPS)':
 C_PATH='@t6g_mb_lib.t6g(sch_1):page421_i5@pure_quanta.m24m02drmn6tp(chips)',
 P_PATH='@t6g_mb_lib.t6g(sch_1):page300_i5@pure_quanta.m24m02drmn6tp(chips)',
 PATH='I5',
 DRAWING='@T6G_MB_LIB.T6G(SCH_1):PAGE421',
 PART_TYPE='SMLF',
 MATERIAL='IC',
 PHYS_PAGE='300',
 XY='(-4775,5650)',
 ROT='0',
 VER='1',
 LOCATION='U16',
 CDS_LIB='pure_quanta',
 CDS_PART_NAME='M24M02DRMN6TP-M24M02-DRMN6TP,SMLF,IC,AKE33Z00600',
 PART_NUMBER='AKE33Z00600',
 VALUE='M24M02-DRMN6TP',
 PRIM_FILE='./archive_libs/logical/m24m02drmn6tp/chips/chips.prt';

PART_NAME
 U17 'M24M02DRMN6TP-M24M02-DRMN6TP,SMLF,IC,AKE33Z00600':;

SECTION_NUMBER 1
 '@T6G_MB_LIB.T6G(SCH_1):PAGE432_I5@PURE_QUANTA.M24M02DRMN6TP(CHIPS)':
 C_PATH='@t6g_mb_lib.t6g(sch_1):page432_i5@pure_quanta.m24m02drmn6tp(chips)',
 P_PATH='@t6g_mb_lib.t6g(sch_1):page311_i5@pure_quanta.m24m02drmn6tp(chips)',
 PATH='I5',
 DRAWING='@T6G_MB_LIB.T6G(SCH_1):PAGE432',
 PART_TYPE='SMLF',
 MATERIAL='IC',
 PHYS_PAGE='311',
 XY='(-4850,5625)',
 ROT='0',
 VER='1',
 LOCATION='U17',
 CDS_LIB='pure_quanta',
 CDS_PART_NAME='M24M02DRMN6TP-M24M02-DRMN6TP,SMLF,IC,AKE33Z00600',
 PART_NUMBER='AKE33Z00600',
 VALUE='M24M02-DRMN6TP',
 PRIM_FILE='./archive_libs/logical/m24m02drmn6tp/chips/chips.prt';

PART_NAME
 U18 'LCMXO3LF9400C5BG484C-LCMXO3LF-9400C-5BG484C,SMLF,IA':;

SECTION_NUMBER 1
 '@T6G_MB_LIB.T6G(SCH_1):PAGE81_I143@PURE_QUANTA.LCMXO3LF9400C5BG484C(CHIPS)':
 C_PATH='@t6g_mb_lib.t6g(sch_1):page81_i143@pure_quanta.lcmxo3lf9400c5bg484c(chi~
ps)',
 P_PATH='@t6g_mb_lib.t6g(sch_1):page82_i143@pure_quanta.lcmxo3lf9400c5bg484c(chi~
ps)',
 PATH='I143',
 DRAWING='@T6G_MB_LIB.T6G(SCH_1):PAGE81',
 SEC_TYPE='',
 PART_TYPE='SMLF',
 MATERIAL='IC',
 PHYS_PAGE='82',
 XY='(-4850,4775)',
 ROT='0',
 VER='1',
 LOCATION='U18',
 SEC='1',
 CDS_LIB='pure_quanta',
 CDS_PART_NAME='LCMXO3LF9400C5BG484C-LCMXO3LF-9400C-5BG484C,SMLF,IA',
 PART_NUMBER='AJ094000T08',
 VALUE='LCMXO3LF-9400C-5BG484C',
 PRIM_FILE='./archive_libs/logical/lcmxo3lf9400c5bg484c/chips/chips.prt';

SECTION_NUMBER 2
 '@T6G_MB_LIB.T6G(SCH_1):PAGE80_I216@PURE_QUANTA.LCMXO3LF9400C5BG484C(CHIPS)':
 C_PATH='@t6g_mb_lib.t6g(sch_1):page80_i216@pure_quanta.lcmxo3lf9400c5bg484c(chi~
ps)',
 P_PATH='@t6g_mb_lib.t6g(sch_1):page81_i216@pure_quanta.lcmxo3lf9400c5bg484c(chi~
ps)',
 PATH='I216',
 DRAWING='@T6G_MB_LIB.T6G(SCH_1):PAGE80',
 PART_TYPE='SMLF',
 MATERIAL='IC',
 PHYS_PAGE='81',
 XY='(-4500,1850)',
 ROT='0',
 VER='2',
 LOCATION='U18',
 CDS_LIB='pure_quanta',
 CDS_PART_NAME='LCMXO3LF9400C5BG484C-LCMXO3LF-9400C-5BG484C,SMLF,IA',
 PART_NUMBER='AJ094000T08',
 VALUE='LCMXO3LF-9400C-5BG484C',
 PRIM_FILE='./archive_libs/logical/lcmxo3lf9400c5bg484c/chips/chips.prt';

SECTION_NUMBER 3
 '@T6G_MB_LIB.T6G(SCH_1):PAGE79_I94@PURE_QUANTA.LCMXO3LF9400C5BG484C(CHIPS)':
 C_PATH='@t6g_mb_lib.t6g(sch_1):page79_i94@pure_quanta.lcmxo3lf9400c5bg484c(chip~
s)',
 P_PATH='@t6g_mb_lib.t6g(sch_1):page80_i94@pure_quanta.lcmxo3lf9400c5bg484c(chip~
s)',
 PATH='I94',
 DRAWING='@T6G_MB_LIB.T6G(SCH_1):PAGE79',
 PART_TYPE='SMLF',
 MATERIAL='IC',
 PHYS_PAGE='80',
 XY='(-4825,3850)',
 ROT='0',
 VER='3',
 LOCATION='U18',
 CDS_LIB='pure_quanta',
 CDS_PART_NAME='LCMXO3LF9400C5BG484C-LCMXO3LF-9400C-5BG484C,SMLF,IA',
 PART_NUMBER='AJ094000T08',
 VALUE='LCMXO3LF-9400C-5BG484C',
 PRIM_FILE='./archive_libs/logical/lcmxo3lf9400c5bg484c/chips/chips.prt';

SECTION_NUMBER 4
 '@T6G_MB_LIB.T6G(SCH_1):PAGE79_I25@PURE_QUANTA.LCMXO3LF9400C5BG484C(CHIPS)':
 C_PATH='@t6g_mb_lib.t6g(sch_1):page79_i25@pure_quanta.lcmxo3lf9400c5bg484c(chip~
s)',
 P_PATH='@t6g_mb_lib.t6g(sch_1):page80_i25@pure_quanta.lcmxo3lf9400c5bg484c(chip~
s)',
 PATH='I25',
 DRAWING='@T6G_MB_LIB.T6G(SCH_1):PAGE79',
 PART_TYPE='SMLF',
 MATERIAL='IC',
 PHYS_PAGE='80',
 XY='(-5375,1250)',
 ROT='0',
 VER='4',
 LOCATION='U18',
 CDS_LIB='pure_quanta',
 CDS_PART_NAME='LCMXO3LF9400C5BG484C-LCMXO3LF-9400C-5BG484C,SMLF,IA',
 PART_NUMBER='AJ094000T08',
 VALUE='LCMXO3LF-9400C-5BG484C',
 PRIM_FILE='./archive_libs/logical/lcmxo3lf9400c5bg484c/chips/chips.prt';

SECTION_NUMBER 5
 '@T6G_MB_LIB.T6G(SCH_1):PAGE81_I141@PURE_QUANTA.LCMXO3LF9400C5BG484C(CHIPS)':
 C_PATH='@t6g_mb_lib.t6g(sch_1):page81_i141@pure_quanta.lcmxo3lf9400c5bg484c(chi~
ps)',
 P_PATH='@t6g_mb_lib.t6g(sch_1):page82_i141@pure_quanta.lcmxo3lf9400c5bg484c(chi~
ps)',
 PATH='I141',
 DRAWING='@T6G_MB_LIB.T6G(SCH_1):PAGE81',
 SEC_TYPE='',
 PART_TYPE='SMLF',
 MATERIAL='IC',
 PHYS_PAGE='82',
 XY='(-2325,1525)',
 ROT='0',
 VER='5',
 LOCATION='U18',
 SEC='5',
 CDS_LIB='pure_quanta',
 CDS_PART_NAME='LCMXO3LF9400C5BG484C-LCMXO3LF-9400C-5BG484C,SMLF,IA',
 PART_NUMBER='AJ094000T08',
 VALUE='LCMXO3LF-9400C-5BG484C',
 PRIM_FILE='./archive_libs/logical/lcmxo3lf9400c5bg484c/chips/chips.prt';

SECTION_NUMBER 6
 '@T6G_MB_LIB.T6G(SCH_1):PAGE81_I1@PURE_QUANTA.LCMXO3LF9400C5BG484C(CHIPS)':
 C_PATH='@t6g_mb_lib.t6g(sch_1):page81_i1@pure_quanta.lcmxo3lf9400c5bg484c(chips~
)',
 P_PATH='@t6g_mb_lib.t6g(sch_1):page82_i1@pure_quanta.lcmxo3lf9400c5bg484c(chips~
)',
 PATH='I1',
 DRAWING='@T6G_MB_LIB.T6G(SCH_1):PAGE81',
 SEC_TYPE='',
 PART_TYPE='SMLF',
 MATERIAL='IC',
 PHYS_PAGE='82',
 XY='(-6800,1600)',
 ROT='0',
 VER='6',
 LOCATION='U18',
 SEC='6',
 CDS_LIB='pure_quanta',
 CDS_PART_NAME='LCMXO3LF9400C5BG484C-LCMXO3LF-9400C-5BG484C,SMLF,IA',
 PART_NUMBER='AJ094000T08',
 VALUE='LCMXO3LF-9400C-5BG484C',
 PRIM_FILE='./archive_libs/logical/lcmxo3lf9400c5bg484c/chips/chips.prt';

SECTION_NUMBER 7
 '@T6G_MB_LIB.T6G(SCH_1):PAGE80_I217@PURE_QUANTA.LCMXO3LF9400C5BG484C(CHIPS)':
 C_PATH='@t6g_mb_lib.t6g(sch_1):page80_i217@pure_quanta.lcmxo3lf9400c5bg484c(chi~
ps)',
 P_PATH='@t6g_mb_lib.t6g(sch_1):page81_i217@pure_quanta.lcmxo3lf9400c5bg484c(chi~
ps)',
 PATH='I217',
 DRAWING='@T6G_MB_LIB.T6G(SCH_1):PAGE80',
 PART_TYPE='SMLF',
 MATERIAL='IC',
 PHYS_PAGE='81',
 XY='(-4825,5000)',
 ROT='0',
 VER='7',
 LOCATION='U18',
 CDS_LIB='pure_quanta',
 CDS_PART_NAME='LCMXO3LF9400C5BG484C-LCMXO3LF-9400C-5BG484C,SMLF,IA',
 PART_NUMBER='AJ094000T08',
 VALUE='LCMXO3LF-9400C-5BG484C',
 PRIM_FILE='./archive_libs/logical/lcmxo3lf9400c5bg484c/chips/chips.prt';

PART_NAME
 U19 'M24M02DRMN6TP-M24M02-DRMN6TP,SMLF,IC,AKE33Z00600':;

SECTION_NUMBER 1
 '@T6G_MB_LIB.T6G(SCH_1):PAGE442_I5@PURE_QUANTA.M24M02DRMN6TP(CHIPS)':
 C_PATH='@t6g_mb_lib.t6g(sch_1):page442_i5@pure_quanta.m24m02drmn6tp(chips)',
 P_PATH='@t6g_mb_lib.t6g(sch_1):page333_i5@pure_quanta.m24m02drmn6tp(chips)',
 PATH='I5',
 DRAWING='@T6G_MB_LIB.T6G(SCH_1):PAGE442',
 PART_TYPE='SMLF',
 MATERIAL='IC',
 PHYS_PAGE='333',
 XY='(-3850,5100)',
 ROT='0',
 VER='1',
 LOCATION='U19',
 CDS_LIB='pure_quanta',
 CDS_PART_NAME='M24M02DRMN6TP-M24M02-DRMN6TP,SMLF,IC,AKE33Z00600',
 PART_NUMBER='AKE33Z00600',
 VALUE='M24M02-DRMN6TP',
 PRIM_FILE='./archive_libs/logical/m24m02drmn6tp/chips/chips.prt';

PART_NAME
 U20 'M24M02DRMN6TP-M24M02-DRMN6TP,SMLF,IC,AKE33Z00600':;

SECTION_NUMBER 1
 '@T6G_MB_LIB.T6G(SCH_1):PAGE453_I5@PURE_QUANTA.M24M02DRMN6TP(CHIPS)':
 C_PATH='@t6g_mb_lib.t6g(sch_1):page453_i5@pure_quanta.m24m02drmn6tp(chips)',
 P_PATH='@t6g_mb_lib.t6g(sch_1):page344_i5@pure_quanta.m24m02drmn6tp(chips)',
 PATH='I5',
 DRAWING='@T6G_MB_LIB.T6G(SCH_1):PAGE453',
 PART_TYPE='SMLF',
 MATERIAL='IC',
 PHYS_PAGE='344',
 XY='(-4875,5600)',
 ROT='0',
 VER='1',
 LOCATION='U20',
 CDS_LIB='pure_quanta',
 CDS_PART_NAME='M24M02DRMN6TP-M24M02-DRMN6TP,SMLF,IC,AKE33Z00600',
 PART_NUMBER='AKE33Z00600',
 VALUE='M24M02-DRMN6TP',
 PRIM_FILE='./archive_libs/logical/m24m02drmn6tp/chips/chips.prt';

PART_NAME
 U21 'M24M02DRMN6TP-M24M02-DRMN6TP,SMLF,IC,AKE33Z00600':;

SECTION_NUMBER 1
 '@T6G_MB_LIB.T6G(SCH_1):PAGE464_I5@PURE_QUANTA.M24M02DRMN6TP(CHIPS)':
 C_PATH='@t6g_mb_lib.t6g(sch_1):page464_i5@pure_quanta.m24m02drmn6tp(chips)',
 P_PATH='@t6g_mb_lib.t6g(sch_1):page355_i5@pure_quanta.m24m02drmn6tp(chips)',
 PATH='I5',
 DRAWING='@T6G_MB_LIB.T6G(SCH_1):PAGE464',
 PART_TYPE='SMLF',
 MATERIAL='IC',
 PHYS_PAGE='355',
 XY='(-4225,5425)',
 ROT='0',
 VER='1',
 LOCATION='U21',
 CDS_LIB='pure_quanta',
 CDS_PART_NAME='M24M02DRMN6TP-M24M02-DRMN6TP,SMLF,IC,AKE33Z00600',
 PART_NUMBER='AKE33Z00600',
 VALUE='M24M02-DRMN6TP',
 PRIM_FILE='./archive_libs/logical/m24m02drmn6tp/chips/chips.prt';

PART_NAME
 U22 'TCA9548APWR-TCA9548APWR,SMLF,IC,AL009548K02':;

SECTION_NUMBER 1
 '@T6G_MB_LIB.T6G(SCH_1):PAGE377_I94@PURE_QUANTA.TCA9548APWR(CHIPS)':
 C_PATH='@t6g_mb_lib.t6g(sch_1):page377_i94@pure_quanta.tca9548apwr(chips)',
 P_PATH='@t6g_mb_lib.t6g(sch_1):page185_i94@pure_quanta.tca9548apwr(chips)',
 PATH='I94',
 DRAWING='@T6G_MB_LIB.T6G(SCH_1):PAGE377',
 PART_TYPE='SMLF',
 MATERIAL='IC',
 PHYS_PAGE='185',
 XY='(-4825,5425)',
 ROT='0',
 VER='1',
 LOCATION='U22',
 CDS_LIB='pure_quanta',
 CDS_PART_NAME='TCA9548APWR-TCA9548APWR,SMLF,IC,AL009548K02',
 PART_NUMBER='AL009548K02',
 VALUE='TCA9548APWR',
 PRIM_FILE='./archive_libs/logical/tca9548apwr/chips/chips.prt';

PART_NAME
 U23 '74LVC1G08W57-74LVC1G08W5-7,SMLF,IC,AL1G0008020':;

SECTION_NUMBER 1
 '@T6G_MB_LIB.T6G(SCH_1):PAGE340_I36@PURE_QUANTA.74LVC1G08W57(CHIPS)':
 C_PATH='@t6g_mb_lib.t6g(sch_1):page340_i36@pure_quanta.\74lvc1g08w57\(chips)',
 P_PATH='@t6g_mb_lib.t6g(sch_1):page136_i36@pure_quanta.\74lvc1g08w57\(chips)',
 PATH='I36',
 DRAWING='@T6G_MB_LIB.T6G(SCH_1):PAGE340',
 SEC_TYPE='',
 PART_TYPE='SMLF',
 MATERIAL='IC',
 PHYS_PAGE='136',
 XY='(-750,9200)',
 ROT='0',
 VER='1',
 LOCATION='U23',
 SEC='1',
 CDS_LIB='pure_quanta',
 CDS_PART_NAME='74LVC1G08W57-74LVC1G08W5-7,SMLF,IC,AL1G0008020',
 PART_NUMBER='AL1G0008020',
 VALUE='74LVC1G08W5-7',
 PRIM_FILE='./archive_libs/logical/74lvc1g08w57/chips/chips.prt';

PART_NAME
 U24 'MOSFET_N_SMLF-BSS138K,BSS138K,IC,BAM138K0000':;

SECTION_NUMBER 1
 '@T6G_MB_LIB.T6G(SCH_1):PAGE340_I31@PURE_QUANTA.MOSFET_N(CHIPS)':
 C_PATH='@t6g_mb_lib.t6g(sch_1):page340_i31@pure_quanta.mosfet_n(chips)',
 P_PATH='@t6g_mb_lib.t6g(sch_1):page136_i31@pure_quanta.mosfet_n(chips)',
 PATH='I31',
 DRAWING='@T6G_MB_LIB.T6G(SCH_1):PAGE340',
 MANUF_PN='BSS138K',
 MATERIAL='IC',
 PHYS_PAGE='136',
 XY='(-3925,8950)',
 ROT='0',
 VER='1',
 PACK_TYPE='SMLF',
 LOCATION='U24',
 CDS_LIB='pure_quanta',
 CDS_PART_NAME='MOSFET_N_SMLF-BSS138K,BSS138K,IC,BAM138K0000',
 PART_NUMBER='BAM138K0000',
 VALUE='BSS138K',
 PRIM_FILE='./archive_libs/logical/mosfet_n/chips/chips.prt';

PART_NAME
 U25 'GENOA_SP5-SOCKET6096_13568-001,SMLF,IO,DGA^6000030':;

SECTION_NUMBER 1
 '@T6G_MB_LIB.T6G(SCH_1):PAGE10_I200@PURE_QUANTA.GENOA_SP5(CHIPS)':
 C_PATH='@t6g_mb_lib.t6g(sch_1):page10_i200@pure_quanta.genoa_sp5(chips)',
 P_PATH='@t6g_mb_lib.t6g(sch_1):page10_i200@pure_quanta.genoa_sp5(chips)',
 PATH='I200',
 DRAWING='@T6G_MB_LIB.T6G(SCH_1):PAGE10',
 PART_TYPE='SMLF',
 MATERIAL='IO',
 PHYS_PAGE='10',
 XY='(-4350,3700)',
 ROT='0',
 VER='1',
 LOCATION='U25',
 CDS_LIB='pure_quanta',
 CDS_PART_NAME='GENOA_SP5-SOCKET6096_13568-001,SMLF,IO,DGA^6000030',
 PART_NUMBER='DGA^6000030',
 VALUE='SOCKET6096_13568-001',
 PRIM_FILE='./archive_libs/logical/genoa_sp5/chips/chips.prt';

SECTION_NUMBER 2
 '@T6G_MB_LIB.T6G(SCH_1):PAGE11_I171@PURE_QUANTA.GENOA_SP5(CHIPS)':
 C_PATH='@t6g_mb_lib.t6g(sch_1):page11_i171@pure_quanta.genoa_sp5(chips)',
 P_PATH='@t6g_mb_lib.t6g(sch_1):page11_i171@pure_quanta.genoa_sp5(chips)',
 PATH='I171',
 DRAWING='@T6G_MB_LIB.T6G(SCH_1):PAGE11',
 PART_TYPE='SMLF',
 MATERIAL='IO',
 PHYS_PAGE='11',
 XY='(-4550,3475)',
 ROT='0',
 VER='2',
 LOCATION='U25',
 CDS_LIB='pure_quanta',
 CDS_PART_NAME='GENOA_SP5-SOCKET6096_13568-001,SMLF,IO,DGA^6000030',
 PART_NUMBER='DGA^6000030',
 VALUE='SOCKET6096_13568-001',
 PRIM_FILE='./archive_libs/logical/genoa_sp5/chips/chips.prt';

SECTION_NUMBER 3
 '@T6G_MB_LIB.T6G(SCH_1):PAGE12_I159@PURE_QUANTA.GENOA_SP5(CHIPS)':
 C_PATH='@t6g_mb_lib.t6g(sch_1):page12_i159@pure_quanta.genoa_sp5(chips)',
 P_PATH='@t6g_mb_lib.t6g(sch_1):page12_i159@pure_quanta.genoa_sp5(chips)',
 PATH='I159',
 DRAWING='@T6G_MB_LIB.T6G(SCH_1):PAGE12',
 PART_TYPE='SMLF',
 MATERIAL='IO',
 PHYS_PAGE='12',
 XY='(-4775,3575)',
 ROT='0',
 VER='3',
 LOCATION='U25',
 CDS_LIB='pure_quanta',
 CDS_PART_NAME='GENOA_SP5-SOCKET6096_13568-001,SMLF,IO,DGA^6000030',
 PART_NUMBER='DGA^6000030',
 VALUE='SOCKET6096_13568-001',
 PRIM_FILE='./archive_libs/logical/genoa_sp5/chips/chips.prt';

SECTION_NUMBER 4
 '@T6G_MB_LIB.T6G(SCH_1):PAGE13_I159@PURE_QUANTA.GENOA_SP5(CHIPS)':
 C_PATH='@t6g_mb_lib.t6g(sch_1):page13_i159@pure_quanta.genoa_sp5(chips)',
 P_PATH='@t6g_mb_lib.t6g(sch_1):page13_i159@pure_quanta.genoa_sp5(chips)',
 PATH='I159',
 DRAWING='@T6G_MB_LIB.T6G(SCH_1):PAGE13',
 PART_TYPE='SMLF',
 MATERIAL='IO',
 PHYS_PAGE='13',
 XY='(-4600,3650)',
 ROT='0',
 VER='4',
 LOCATION='U25',
 CDS_LIB='pure_quanta',
 CDS_PART_NAME='GENOA_SP5-SOCKET6096_13568-001,SMLF,IO,DGA^6000030',
 PART_NUMBER='DGA^6000030',
 VALUE='SOCKET6096_13568-001',
 PRIM_FILE='./archive_libs/logical/genoa_sp5/chips/chips.prt';

SECTION_NUMBER 5
 '@T6G_MB_LIB.T6G(SCH_1):PAGE14_I159@PURE_QUANTA.GENOA_SP5(CHIPS)':
 C_PATH='@t6g_mb_lib.t6g(sch_1):page14_i159@pure_quanta.genoa_sp5(chips)',
 P_PATH='@t6g_mb_lib.t6g(sch_1):page14_i159@pure_quanta.genoa_sp5(chips)',
 PATH='I159',
 DRAWING='@T6G_MB_LIB.T6G(SCH_1):PAGE14',
 PART_TYPE='SMLF',
 MATERIAL='IO',
 PHYS_PAGE='14',
 XY='(-4675,3675)',
 ROT='0',
 VER='5',
 LOCATION='U25',
 CDS_LIB='pure_quanta',
 CDS_PART_NAME='GENOA_SP5-SOCKET6096_13568-001,SMLF,IO,DGA^6000030',
 PART_NUMBER='DGA^6000030',
 VALUE='SOCKET6096_13568-001',
 PRIM_FILE='./archive_libs/logical/genoa_sp5/chips/chips.prt';

SECTION_NUMBER 6
 '@T6G_MB_LIB.T6G(SCH_1):PAGE15_I159@PURE_QUANTA.GENOA_SP5(CHIPS)':
 C_PATH='@t6g_mb_lib.t6g(sch_1):page15_i159@pure_quanta.genoa_sp5(chips)',
 P_PATH='@t6g_mb_lib.t6g(sch_1):page15_i159@pure_quanta.genoa_sp5(chips)',
 PATH='I159',
 DRAWING='@T6G_MB_LIB.T6G(SCH_1):PAGE15',
 PART_TYPE='SMLF',
 MATERIAL='IO',
 PHYS_PAGE='15',
 XY='(-4650,3600)',
 ROT='0',
 VER='6',
 LOCATION='U25',
 CDS_LIB='pure_quanta',
 CDS_PART_NAME='GENOA_SP5-SOCKET6096_13568-001,SMLF,IO,DGA^6000030',
 PART_NUMBER='DGA^6000030',
 VALUE='SOCKET6096_13568-001',
 PRIM_FILE='./archive_libs/logical/genoa_sp5/chips/chips.prt';

SECTION_NUMBER 7
 '@T6G_MB_LIB.T6G(SCH_1):PAGE16_I167@PURE_QUANTA.GENOA_SP5(CHIPS)':
 C_PATH='@t6g_mb_lib.t6g(sch_1):page16_i167@pure_quanta.genoa_sp5(chips)',
 P_PATH='@t6g_mb_lib.t6g(sch_1):page16_i167@pure_quanta.genoa_sp5(chips)',
 PATH='I167',
 DRAWING='@T6G_MB_LIB.T6G(SCH_1):PAGE16',
 PART_TYPE='SMLF',
 MATERIAL='IO',
 PHYS_PAGE='16',
 XY='(-4700,3675)',
 ROT='0',
 VER='7',
 LOCATION='U25',
 CDS_LIB='pure_quanta',
 CDS_PART_NAME='GENOA_SP5-SOCKET6096_13568-001,SMLF,IO,DGA^6000030',
 PART_NUMBER='DGA^6000030',
 VALUE='SOCKET6096_13568-001',
 PRIM_FILE='./archive_libs/logical/genoa_sp5/chips/chips.prt';

SECTION_NUMBER 8
 '@T6G_MB_LIB.T6G(SCH_1):PAGE17_I159@PURE_QUANTA.GENOA_SP5(CHIPS)':
 C_PATH='@t6g_mb_lib.t6g(sch_1):page17_i159@pure_quanta.genoa_sp5(chips)',
 P_PATH='@t6g_mb_lib.t6g(sch_1):page17_i159@pure_quanta.genoa_sp5(chips)',
 PATH='I159',
 DRAWING='@T6G_MB_LIB.T6G(SCH_1):PAGE17',
 PART_TYPE='SMLF',
 MATERIAL='IO',
 PHYS_PAGE='17',
 XY='(-4600,3600)',
 ROT='0',
 VER='8',
 LOCATION='U25',
 CDS_LIB='pure_quanta',
 CDS_PART_NAME='GENOA_SP5-SOCKET6096_13568-001,SMLF,IO,DGA^6000030',
 PART_NUMBER='DGA^6000030',
 VALUE='SOCKET6096_13568-001',
 PRIM_FILE='./archive_libs/logical/genoa_sp5/chips/chips.prt';

SECTION_NUMBER 9
 '@T6G_MB_LIB.T6G(SCH_1):PAGE18_I159@PURE_QUANTA.GENOA_SP5(CHIPS)':
 C_PATH='@t6g_mb_lib.t6g(sch_1):page18_i159@pure_quanta.genoa_sp5(chips)',
 P_PATH='@t6g_mb_lib.t6g(sch_1):page18_i159@pure_quanta.genoa_sp5(chips)',
 PATH='I159',
 DRAWING='@T6G_MB_LIB.T6G(SCH_1):PAGE18',
 PART_TYPE='SMLF',
 MATERIAL='IO',
 PHYS_PAGE='18',
 XY='(-4525,3600)',
 ROT='0',
 VER='9',
 LOCATION='U25',
 CDS_LIB='pure_quanta',
 CDS_PART_NAME='GENOA_SP5-SOCKET6096_13568-001,SMLF,IO,DGA^6000030',
 PART_NUMBER='DGA^6000030',
 VALUE='SOCKET6096_13568-001',
 PRIM_FILE='./archive_libs/logical/genoa_sp5/chips/chips.prt';

SECTION_NUMBER 10
 '@T6G_MB_LIB.T6G(SCH_1):PAGE19_I159@PURE_QUANTA.GENOA_SP5(CHIPS)':
 C_PATH='@t6g_mb_lib.t6g(sch_1):page19_i159@pure_quanta.genoa_sp5(chips)',
 P_PATH='@t6g_mb_lib.t6g(sch_1):page19_i159@pure_quanta.genoa_sp5(chips)',
 PATH='I159',
 DRAWING='@T6G_MB_LIB.T6G(SCH_1):PAGE19',
 PART_TYPE='SMLF',
 MATERIAL='IO',
 PHYS_PAGE='19',
 XY='(-4525,3625)',
 ROT='0',
 VER='10',
 LOCATION='U25',
 CDS_LIB='pure_quanta',
 CDS_PART_NAME='GENOA_SP5-SOCKET6096_13568-001,SMLF,IO,DGA^6000030',
 PART_NUMBER='DGA^6000030',
 VALUE='SOCKET6096_13568-001',
 PRIM_FILE='./archive_libs/logical/genoa_sp5/chips/chips.prt';

SECTION_NUMBER 11
 '@T6G_MB_LIB.T6G(SCH_1):PAGE22_I207@PURE_QUANTA.GENOA_SP5(CHIPS)':
 C_PATH='@t6g_mb_lib.t6g(sch_1):page22_i207@pure_quanta.genoa_sp5(chips)',
 P_PATH='@t6g_mb_lib.t6g(sch_1):page22_i207@pure_quanta.genoa_sp5(chips)',
 PATH='I207',
 DRAWING='@T6G_MB_LIB.T6G(SCH_1):PAGE22',
 PART_TYPE='SMLF',
 MATERIAL='IO',
 PHYS_PAGE='22',
 XY='(-4775,4925)',
 ROT='0',
 VER='11',
 LOCATION='U25',
 CDS_LIB='pure_quanta',
 CDS_PART_NAME='GENOA_SP5-SOCKET6096_13568-001,SMLF,IO,DGA^6000030',
 PART_NUMBER='DGA^6000030',
 VALUE='SOCKET6096_13568-001',
 PRIM_FILE='./archive_libs/logical/genoa_sp5/chips/chips.prt';

SECTION_NUMBER 12
 '@T6G_MB_LIB.T6G(SCH_1):PAGE22_I208@PURE_QUANTA.GENOA_SP5(CHIPS)':
 C_PATH='@t6g_mb_lib.t6g(sch_1):page22_i208@pure_quanta.genoa_sp5(chips)',
 P_PATH='@t6g_mb_lib.t6g(sch_1):page22_i208@pure_quanta.genoa_sp5(chips)',
 PATH='I208',
 DRAWING='@T6G_MB_LIB.T6G(SCH_1):PAGE22',
 PART_TYPE='SMLF',
 MATERIAL='IO',
 PHYS_PAGE='22',
 XY='(-4775,2200)',
 ROT='0',
 VER='12',
 LOCATION='U25',
 CDS_LIB='pure_quanta',
 CDS_PART_NAME='GENOA_SP5-SOCKET6096_13568-001,SMLF,IO,DGA^6000030',
 PART_NUMBER='DGA^6000030',
 VALUE='SOCKET6096_13568-001',
 PRIM_FILE='./archive_libs/logical/genoa_sp5/chips/chips.prt';

SECTION_NUMBER 13
 '@T6G_MB_LIB.T6G(SCH_1):PAGE23_I215@PURE_QUANTA.GENOA_SP5(CHIPS)':
 C_PATH='@t6g_mb_lib.t6g(sch_1):page23_i215@pure_quanta.genoa_sp5(chips)',
 P_PATH='@t6g_mb_lib.t6g(sch_1):page23_i215@pure_quanta.genoa_sp5(chips)',
 PATH='I215',
 DRAWING='@T6G_MB_LIB.T6G(SCH_1):PAGE23',
 PART_TYPE='SMLF',
 MATERIAL='IO',
 PHYS_PAGE='23',
 XY='(-4775,5075)',
 ROT='0',
 VER='13',
 LOCATION='U25',
 CDS_LIB='pure_quanta',
 CDS_PART_NAME='GENOA_SP5-SOCKET6096_13568-001,SMLF,IO,DGA^6000030',
 PART_NUMBER='DGA^6000030',
 VALUE='SOCKET6096_13568-001',
 PRIM_FILE='./archive_libs/logical/genoa_sp5/chips/chips.prt';

SECTION_NUMBER 14
 '@T6G_MB_LIB.T6G(SCH_1):PAGE23_I216@PURE_QUANTA.GENOA_SP5(CHIPS)':
 C_PATH='@t6g_mb_lib.t6g(sch_1):page23_i216@pure_quanta.genoa_sp5(chips)',
 P_PATH='@t6g_mb_lib.t6g(sch_1):page23_i216@pure_quanta.genoa_sp5(chips)',
 PATH='I216',
 DRAWING='@T6G_MB_LIB.T6G(SCH_1):PAGE23',
 PART_TYPE='SMLF',
 MATERIAL='IO',
 PHYS_PAGE='23',
 XY='(-4750,2200)',
 ROT='0',
 VER='14',
 LOCATION='U25',
 CDS_LIB='pure_quanta',
 CDS_PART_NAME='GENOA_SP5-SOCKET6096_13568-001,SMLF,IO,DGA^6000030',
 PART_NUMBER='DGA^6000030',
 VALUE='SOCKET6096_13568-001',
 PRIM_FILE='./archive_libs/logical/genoa_sp5/chips/chips.prt';

SECTION_NUMBER 15
 '@T6G_MB_LIB.T6G(SCH_1):PAGE24_I148@PURE_QUANTA.GENOA_SP5(CHIPS)':
 C_PATH='@t6g_mb_lib.t6g(sch_1):page24_i148@pure_quanta.genoa_sp5(chips)',
 P_PATH='@t6g_mb_lib.t6g(sch_1):page24_i148@pure_quanta.genoa_sp5(chips)',
 PATH='I148',
 DRAWING='@T6G_MB_LIB.T6G(SCH_1):PAGE24',
 PART_TYPE='SMLF',
 MATERIAL='IO',
 PHYS_PAGE='24',
 XY='(-4925,5000)',
 ROT='0',
 VER='15',
 LOCATION='U25',
 CDS_LIB='pure_quanta',
 CDS_PART_NAME='GENOA_SP5-SOCKET6096_13568-001,SMLF,IO,DGA^6000030',
 PART_NUMBER='DGA^6000030',
 VALUE='SOCKET6096_13568-001',
 PRIM_FILE='./archive_libs/logical/genoa_sp5/chips/chips.prt';

SECTION_NUMBER 16
 '@T6G_MB_LIB.T6G(SCH_1):PAGE24_I149@PURE_QUANTA.GENOA_SP5(CHIPS)':
 C_PATH='@t6g_mb_lib.t6g(sch_1):page24_i149@pure_quanta.genoa_sp5(chips)',
 P_PATH='@t6g_mb_lib.t6g(sch_1):page24_i149@pure_quanta.genoa_sp5(chips)',
 PATH='I149',
 DRAWING='@T6G_MB_LIB.T6G(SCH_1):PAGE24',
 PART_TYPE='SMLF',
 MATERIAL='IO',
 PHYS_PAGE='24',
 XY='(-5000,1525)',
 ROT='0',
 VER='16',
 LOCATION='U25',
 CDS_LIB='pure_quanta',
 CDS_PART_NAME='GENOA_SP5-SOCKET6096_13568-001,SMLF,IO,DGA^6000030',
 PART_NUMBER='DGA^6000030',
 VALUE='SOCKET6096_13568-001',
 PRIM_FILE='./archive_libs/logical/genoa_sp5/chips/chips.prt';

SECTION_NUMBER 17
 '@T6G_MB_LIB.T6G(SCH_1):PAGE25_I147@PURE_QUANTA.GENOA_SP5(CHIPS)':
 C_PATH='@t6g_mb_lib.t6g(sch_1):page25_i147@pure_quanta.genoa_sp5(chips)',
 P_PATH='@t6g_mb_lib.t6g(sch_1):page25_i147@pure_quanta.genoa_sp5(chips)',
 PATH='I147',
 DRAWING='@T6G_MB_LIB.T6G(SCH_1):PAGE25',
 PART_TYPE='SMLF',
 MATERIAL='IO',
 PHYS_PAGE='25',
 XY='(-5025,5075)',
 ROT='0',
 VER='17',
 LOCATION='U25',
 CDS_LIB='pure_quanta',
 CDS_PART_NAME='GENOA_SP5-SOCKET6096_13568-001,SMLF,IO,DGA^6000030',
 PART_NUMBER='DGA^6000030',
 VALUE='SOCKET6096_13568-001',
 PRIM_FILE='./archive_libs/logical/genoa_sp5/chips/chips.prt';

SECTION_NUMBER 18
 '@T6G_MB_LIB.T6G(SCH_1):PAGE25_I148@PURE_QUANTA.GENOA_SP5(CHIPS)':
 C_PATH='@t6g_mb_lib.t6g(sch_1):page25_i148@pure_quanta.genoa_sp5(chips)',
 P_PATH='@t6g_mb_lib.t6g(sch_1):page25_i148@pure_quanta.genoa_sp5(chips)',
 PATH='I148',
 DRAWING='@T6G_MB_LIB.T6G(SCH_1):PAGE25',
 PART_TYPE='SMLF',
 MATERIAL='IO',
 PHYS_PAGE='25',
 XY='(-5025,2250)',
 ROT='0',
 VER='18',
 LOCATION='U25',
 CDS_LIB='pure_quanta',
 CDS_PART_NAME='GENOA_SP5-SOCKET6096_13568-001,SMLF,IO,DGA^6000030',
 PART_NUMBER='DGA^6000030',
 VALUE='SOCKET6096_13568-001',
 PRIM_FILE='./archive_libs/logical/genoa_sp5/chips/chips.prt';

SECTION_NUMBER 19
 '@T6G_MB_LIB.T6G(SCH_1):PAGE26_I59@PURE_QUANTA.GENOA_SP5(CHIPS)':
 C_PATH='@t6g_mb_lib.t6g(sch_1):page26_i59@pure_quanta.genoa_sp5(chips)',
 P_PATH='@t6g_mb_lib.t6g(sch_1):page26_i59@pure_quanta.genoa_sp5(chips)',
 PATH='I59',
 DRAWING='@T6G_MB_LIB.T6G(SCH_1):PAGE26',
 PART_TYPE='SMLF',
 MATERIAL='IO',
 PHYS_PAGE='26',
 XY='(-4575,4800)',
 ROT='0',
 VER='19',
 LOCATION='U25',
 CDS_LIB='pure_quanta',
 CDS_PART_NAME='GENOA_SP5-SOCKET6096_13568-001,SMLF,IO,DGA^6000030',
 PART_NUMBER='DGA^6000030',
 VALUE='SOCKET6096_13568-001',
 PRIM_FILE='./archive_libs/logical/genoa_sp5/chips/chips.prt';

SECTION_NUMBER 20
 '@T6G_MB_LIB.T6G(SCH_1):PAGE27_I227@PURE_QUANTA.GENOA_SP5(CHIPS)':
 C_PATH='@t6g_mb_lib.t6g(sch_1):page27_i227@pure_quanta.genoa_sp5(chips)',
 P_PATH='@t6g_mb_lib.t6g(sch_1):page27_i227@pure_quanta.genoa_sp5(chips)',
 PATH='I227',
 DRAWING='@T6G_MB_LIB.T6G(SCH_1):PAGE27',
 PART_TYPE='SMLF',
 MATERIAL='IO',
 PHYS_PAGE='27',
 XY='(-4275,3500)',
 ROT='0',
 VER='20',
 LOCATION='U25',
 CDS_LIB='pure_quanta',
 CDS_PART_NAME='GENOA_SP5-SOCKET6096_13568-001,SMLF,IO,DGA^6000030',
 PART_NUMBER='DGA^6000030',
 VALUE='SOCKET6096_13568-001',
 PRIM_FILE='./archive_libs/logical/genoa_sp5/chips/chips.prt';

SECTION_NUMBER 21
 '@T6G_MB_LIB.T6G(SCH_1):PAGE28_I188@PURE_QUANTA.GENOA_SP5(CHIPS)':
 C_PATH='@t6g_mb_lib.t6g(sch_1):page28_i188@pure_quanta.genoa_sp5(chips)',
 P_PATH='@t6g_mb_lib.t6g(sch_1):page28_i188@pure_quanta.genoa_sp5(chips)',
 PATH='I188',
 DRAWING='@T6G_MB_LIB.T6G(SCH_1):PAGE28',
 PART_TYPE='SMLF',
 MATERIAL='IO',
 PHYS_PAGE='28',
 XY='(-4350,11375)',
 ROT='0',
 VER='21',
 LOCATION='U25',
 CDS_LIB='pure_quanta',
 CDS_PART_NAME='GENOA_SP5-SOCKET6096_13568-001,SMLF,IO,DGA^6000030',
 PART_NUMBER='DGA^6000030',
 VALUE='SOCKET6096_13568-001',
 PRIM_FILE='./archive_libs/logical/genoa_sp5/chips/chips.prt';

SECTION_NUMBER 22
 '@T6G_MB_LIB.T6G(SCH_1):PAGE29_I287@PURE_QUANTA.GENOA_SP5(CHIPS)':
 C_PATH='@t6g_mb_lib.t6g(sch_1):page29_i287@pure_quanta.genoa_sp5(chips)',
 P_PATH='@t6g_mb_lib.t6g(sch_1):page29_i287@pure_quanta.genoa_sp5(chips)',
 PATH='I287',
 DRAWING='@T6G_MB_LIB.T6G(SCH_1):PAGE29',
 PART_TYPE='SMLF',
 MATERIAL='IO',
 PHYS_PAGE='29',
 XY='(-4675,4825)',
 ROT='0',
 VER='22',
 LOCATION='U25',
 CDS_LIB='pure_quanta',
 CDS_PART_NAME='GENOA_SP5-SOCKET6096_13568-001,SMLF,IO,DGA^6000030',
 PART_NUMBER='DGA^6000030',
 VALUE='SOCKET6096_13568-001',
 PRIM_FILE='./archive_libs/logical/genoa_sp5/chips/chips.prt';

SECTION_NUMBER 23
 '@T6G_MB_LIB.T6G(SCH_1):PAGE30_I29@PURE_QUANTA.GENOA_SP5(CHIPS)':
 C_PATH='@t6g_mb_lib.t6g(sch_1):page30_i29@pure_quanta.genoa_sp5(chips)',
 P_PATH='@t6g_mb_lib.t6g(sch_1):page30_i29@pure_quanta.genoa_sp5(chips)',
 PATH='I29',
 DRAWING='@T6G_MB_LIB.T6G(SCH_1):PAGE30',
 PART_TYPE='SMLF',
 MATERIAL='IO',
 PHYS_PAGE='30',
 XY='(-725,4350)',
 ROT='0',
 VER='23',
 LOCATION='U25',
 CDS_LIB='pure_quanta',
 CDS_PART_NAME='GENOA_SP5-SOCKET6096_13568-001,SMLF,IO,DGA^6000030',
 PART_NUMBER='DGA^6000030',
 VALUE='SOCKET6096_13568-001',
 PRIM_FILE='./archive_libs/logical/genoa_sp5/chips/chips.prt';

SECTION_NUMBER 24
 '@T6G_MB_LIB.T6G(SCH_1):PAGE30_I42@PURE_QUANTA.GENOA_SP5(CHIPS)':
 C_PATH='@t6g_mb_lib.t6g(sch_1):page30_i42@pure_quanta.genoa_sp5(chips)',
 P_PATH='@t6g_mb_lib.t6g(sch_1):page30_i42@pure_quanta.genoa_sp5(chips)',
 PATH='I42',
 DRAWING='@T6G_MB_LIB.T6G(SCH_1):PAGE30',
 PART_TYPE='SMLF',
 MATERIAL='IO',
 PHYS_PAGE='30',
 XY='(-8050,3325)',
 ROT='0',
 VER='24',
 LOCATION='U25',
 CDS_LIB='pure_quanta',
 CDS_PART_NAME='GENOA_SP5-SOCKET6096_13568-001,SMLF,IO,DGA^6000030',
 PART_NUMBER='DGA^6000030',
 VALUE='SOCKET6096_13568-001',
 PRIM_FILE='./archive_libs/logical/genoa_sp5/chips/chips.prt';

SECTION_NUMBER 25
 '@T6G_MB_LIB.T6G(SCH_1):PAGE30_I45@PURE_QUANTA.GENOA_SP5(CHIPS)':
 C_PATH='@t6g_mb_lib.t6g(sch_1):page30_i45@pure_quanta.genoa_sp5(chips)',
 P_PATH='@t6g_mb_lib.t6g(sch_1):page30_i45@pure_quanta.genoa_sp5(chips)',
 PATH='I45',
 DRAWING='@T6G_MB_LIB.T6G(SCH_1):PAGE30',
 PART_TYPE='SMLF',
 MATERIAL='IO',
 PHYS_PAGE='30',
 XY='(-6075,3350)',
 ROT='0',
 VER='25',
 LOCATION='U25',
 CDS_LIB='pure_quanta',
 CDS_PART_NAME='GENOA_SP5-SOCKET6096_13568-001,SMLF,IO,DGA^6000030',
 PART_NUMBER='DGA^6000030',
 VALUE='SOCKET6096_13568-001',
 PRIM_FILE='./archive_libs/logical/genoa_sp5/chips/chips.prt';

SECTION_NUMBER 26
 '@T6G_MB_LIB.T6G(SCH_1):PAGE30_I50@PURE_QUANTA.GENOA_SP5(CHIPS)':
 C_PATH='@t6g_mb_lib.t6g(sch_1):page30_i50@pure_quanta.genoa_sp5(chips)',
 P_PATH='@t6g_mb_lib.t6g(sch_1):page30_i50@pure_quanta.genoa_sp5(chips)',
 PATH='I50',
 DRAWING='@T6G_MB_LIB.T6G(SCH_1):PAGE30',
 PART_TYPE='SMLF',
 MATERIAL='IO',
 PHYS_PAGE='30',
 XY='(-4250,4575)',
 ROT='0',
 VER='26',
 LOCATION='U25',
 CDS_LIB='pure_quanta',
 CDS_PART_NAME='GENOA_SP5-SOCKET6096_13568-001,SMLF,IO,DGA^6000030',
 PART_NUMBER='DGA^6000030',
 VALUE='SOCKET6096_13568-001',
 PRIM_FILE='./archive_libs/logical/genoa_sp5/chips/chips.prt';

SECTION_NUMBER 27
 '@T6G_MB_LIB.T6G(SCH_1):PAGE30_I28@PURE_QUANTA.GENOA_SP5(CHIPS)':
 C_PATH='@t6g_mb_lib.t6g(sch_1):page30_i28@pure_quanta.genoa_sp5(chips)',
 P_PATH='@t6g_mb_lib.t6g(sch_1):page30_i28@pure_quanta.genoa_sp5(chips)',
 PATH='I28',
 DRAWING='@T6G_MB_LIB.T6G(SCH_1):PAGE30',
 PART_TYPE='SMLF',
 MATERIAL='IO',
 PHYS_PAGE='30',
 XY='(-2475,3550)',
 ROT='0',
 VER='27',
 LOCATION='U25',
 CDS_LIB='pure_quanta',
 CDS_PART_NAME='GENOA_SP5-SOCKET6096_13568-001,SMLF,IO,DGA^6000030',
 PART_NUMBER='DGA^6000030',
 VALUE='SOCKET6096_13568-001',
 PRIM_FILE='./archive_libs/logical/genoa_sp5/chips/chips.prt';

SECTION_NUMBER 28
 '@T6G_MB_LIB.T6G(SCH_1):PAGE31_I19@PURE_QUANTA.GENOA_SP5(CHIPS)':
 C_PATH='@t6g_mb_lib.t6g(sch_1):page31_i19@pure_quanta.genoa_sp5(chips)',
 P_PATH='@t6g_mb_lib.t6g(sch_1):page31_i19@pure_quanta.genoa_sp5(chips)',
 PATH='I19',
 DRAWING='@T6G_MB_LIB.T6G(SCH_1):PAGE31',
 PART_TYPE='SMLF',
 MATERIAL='IO',
 PHYS_PAGE='31',
 XY='(-8600,3400)',
 ROT='0',
 VER='28',
 LOCATION='U25',
 CDS_LIB='pure_quanta',
 CDS_PART_NAME='GENOA_SP5-SOCKET6096_13568-001,SMLF,IO,DGA^6000030',
 PART_NUMBER='DGA^6000030',
 VALUE='SOCKET6096_13568-001',
 PRIM_FILE='./archive_libs/logical/genoa_sp5/chips/chips.prt';

SECTION_NUMBER 29
 '@T6G_MB_LIB.T6G(SCH_1):PAGE31_I20@PURE_QUANTA.GENOA_SP5(CHIPS)':
 C_PATH='@t6g_mb_lib.t6g(sch_1):page31_i20@pure_quanta.genoa_sp5(chips)',
 P_PATH='@t6g_mb_lib.t6g(sch_1):page31_i20@pure_quanta.genoa_sp5(chips)',
 PATH='I20',
 DRAWING='@T6G_MB_LIB.T6G(SCH_1):PAGE31',
 PART_TYPE='SMLF',
 MATERIAL='IO',
 PHYS_PAGE='31',
 XY='(-7075,3425)',
 ROT='0',
 VER='29',
 LOCATION='U25',
 CDS_LIB='pure_quanta',
 CDS_PART_NAME='GENOA_SP5-SOCKET6096_13568-001,SMLF,IO,DGA^6000030',
 PART_NUMBER='DGA^6000030',
 VALUE='SOCKET6096_13568-001',
 PRIM_FILE='./archive_libs/logical/genoa_sp5/chips/chips.prt';

SECTION_NUMBER 30
 '@T6G_MB_LIB.T6G(SCH_1):PAGE31_I21@PURE_QUANTA.GENOA_SP5(CHIPS)':
 C_PATH='@t6g_mb_lib.t6g(sch_1):page31_i21@pure_quanta.genoa_sp5(chips)',
 P_PATH='@t6g_mb_lib.t6g(sch_1):page31_i21@pure_quanta.genoa_sp5(chips)',
 PATH='I21',
 DRAWING='@T6G_MB_LIB.T6G(SCH_1):PAGE31',
 PART_TYPE='SMLF',
 MATERIAL='IO',
 PHYS_PAGE='31',
 XY='(-5600,3450)',
 ROT='0',
 VER='30',
 LOCATION='U25',
 CDS_LIB='pure_quanta',
 CDS_PART_NAME='GENOA_SP5-SOCKET6096_13568-001,SMLF,IO,DGA^6000030',
 PART_NUMBER='DGA^6000030',
 VALUE='SOCKET6096_13568-001',
 PRIM_FILE='./archive_libs/logical/genoa_sp5/chips/chips.prt';

SECTION_NUMBER 31
 '@T6G_MB_LIB.T6G(SCH_1):PAGE31_I22@PURE_QUANTA.GENOA_SP5(CHIPS)':
 C_PATH='@t6g_mb_lib.t6g(sch_1):page31_i22@pure_quanta.genoa_sp5(chips)',
 P_PATH='@t6g_mb_lib.t6g(sch_1):page31_i22@pure_quanta.genoa_sp5(chips)',
 PATH='I22',
 DRAWING='@T6G_MB_LIB.T6G(SCH_1):PAGE31',
 PART_TYPE='SMLF',
 MATERIAL='IO',
 PHYS_PAGE='31',
 XY='(-4100,3475)',
 ROT='0',
 VER='31',
 LOCATION='U25',
 CDS_LIB='pure_quanta',
 CDS_PART_NAME='GENOA_SP5-SOCKET6096_13568-001,SMLF,IO,DGA^6000030',
 PART_NUMBER='DGA^6000030',
 VALUE='SOCKET6096_13568-001',
 PRIM_FILE='./archive_libs/logical/genoa_sp5/chips/chips.prt';

SECTION_NUMBER 32
 '@T6G_MB_LIB.T6G(SCH_1):PAGE31_I23@PURE_QUANTA.GENOA_SP5(CHIPS)':
 C_PATH='@t6g_mb_lib.t6g(sch_1):page31_i23@pure_quanta.genoa_sp5(chips)',
 P_PATH='@t6g_mb_lib.t6g(sch_1):page31_i23@pure_quanta.genoa_sp5(chips)',
 PATH='I23',
 DRAWING='@T6G_MB_LIB.T6G(SCH_1):PAGE31',
 PART_TYPE='SMLF',
 MATERIAL='IO',
 PHYS_PAGE='31',
 XY='(-2625,3475)',
 ROT='0',
 VER='32',
 LOCATION='U25',
 CDS_LIB='pure_quanta',
 CDS_PART_NAME='GENOA_SP5-SOCKET6096_13568-001,SMLF,IO,DGA^6000030',
 PART_NUMBER='DGA^6000030',
 VALUE='SOCKET6096_13568-001',
 PRIM_FILE='./archive_libs/logical/genoa_sp5/chips/chips.prt';

SECTION_NUMBER 33
 '@T6G_MB_LIB.T6G(SCH_1):PAGE31_I24@PURE_QUANTA.GENOA_SP5(CHIPS)':
 C_PATH='@t6g_mb_lib.t6g(sch_1):page31_i24@pure_quanta.genoa_sp5(chips)',
 P_PATH='@t6g_mb_lib.t6g(sch_1):page31_i24@pure_quanta.genoa_sp5(chips)',
 PATH='I24',
 DRAWING='@T6G_MB_LIB.T6G(SCH_1):PAGE31',
 PART_TYPE='SMLF',
 MATERIAL='IO',
 PHYS_PAGE='31',
 XY='(-1000,3475)',
 ROT='0',
 VER='33',
 LOCATION='U25',
 CDS_LIB='pure_quanta',
 CDS_PART_NAME='GENOA_SP5-SOCKET6096_13568-001,SMLF,IO,DGA^6000030',
 PART_NUMBER='DGA^6000030',
 VALUE='SOCKET6096_13568-001',
 PRIM_FILE='./archive_libs/logical/genoa_sp5/chips/chips.prt';

SECTION_NUMBER 34
 '@T6G_MB_LIB.T6G(SCH_1):PAGE32_I13@PURE_QUANTA.GENOA_SP5(CHIPS)':
 C_PATH='@t6g_mb_lib.t6g(sch_1):page32_i13@pure_quanta.genoa_sp5(chips)',
 P_PATH='@t6g_mb_lib.t6g(sch_1):page32_i13@pure_quanta.genoa_sp5(chips)',
 PATH='I13',
 DRAWING='@T6G_MB_LIB.T6G(SCH_1):PAGE32',
 PART_TYPE='SMLF',
 MATERIAL='IO',
 PHYS_PAGE='32',
 XY='(-7775,3450)',
 ROT='0',
 VER='34',
 LOCATION='U25',
 CDS_LIB='pure_quanta',
 CDS_PART_NAME='GENOA_SP5-SOCKET6096_13568-001,SMLF,IO,DGA^6000030',
 PART_NUMBER='DGA^6000030',
 VALUE='SOCKET6096_13568-001',
 PRIM_FILE='./archive_libs/logical/genoa_sp5/chips/chips.prt';

SECTION_NUMBER 35
 '@T6G_MB_LIB.T6G(SCH_1):PAGE21_I159@PURE_QUANTA.GENOA_SP5(CHIPS)':
 C_PATH='@t6g_mb_lib.t6g(sch_1):page21_i159@pure_quanta.genoa_sp5(chips)',
 P_PATH='@t6g_mb_lib.t6g(sch_1):page21_i159@pure_quanta.genoa_sp5(chips)',
 PATH='I159',
 DRAWING='@T6G_MB_LIB.T6G(SCH_1):PAGE21',
 PART_TYPE='SMLF',
 MATERIAL='IO',
 PHYS_PAGE='21',
 XY='(-4500,3625)',
 ROT='0',
 VER='35',
 LOCATION='U25',
 CDS_LIB='pure_quanta',
 CDS_PART_NAME='GENOA_SP5-SOCKET6096_13568-001,SMLF,IO,DGA^6000030',
 PART_NUMBER='DGA^6000030',
 VALUE='SOCKET6096_13568-001',
 PRIM_FILE='./archive_libs/logical/genoa_sp5/chips/chips.prt';

SECTION_NUMBER 36
 '@T6G_MB_LIB.T6G(SCH_1):PAGE20_I159@PURE_QUANTA.GENOA_SP5(CHIPS)':
 C_PATH='@t6g_mb_lib.t6g(sch_1):page20_i159@pure_quanta.genoa_sp5(chips)',
 P_PATH='@t6g_mb_lib.t6g(sch_1):page20_i159@pure_quanta.genoa_sp5(chips)',
 PATH='I159',
 DRAWING='@T6G_MB_LIB.T6G(SCH_1):PAGE20',
 PART_TYPE='SMLF',
 MATERIAL='IO',
 PHYS_PAGE='20',
 XY='(-4425,3575)',
 ROT='0',
 VER='36',
 LOCATION='U25',
 CDS_LIB='pure_quanta',
 CDS_PART_NAME='GENOA_SP5-SOCKET6096_13568-001,SMLF,IO,DGA^6000030',
 PART_NUMBER='DGA^6000030',
 VALUE='SOCKET6096_13568-001',
 PRIM_FILE='./archive_libs/logical/genoa_sp5/chips/chips.prt';

SECTION_NUMBER 37
 '@T6G_MB_LIB.T6G(SCH_1):PAGE32_I14@PURE_QUANTA.GENOA_SP5(CHIPS)':
 C_PATH='@t6g_mb_lib.t6g(sch_1):page32_i14@pure_quanta.genoa_sp5(chips)',
 P_PATH='@t6g_mb_lib.t6g(sch_1):page32_i14@pure_quanta.genoa_sp5(chips)',
 PATH='I14',
 DRAWING='@T6G_MB_LIB.T6G(SCH_1):PAGE32',
 PART_TYPE='SMLF',
 MATERIAL='IO',
 PHYS_PAGE='32',
 XY='(-5750,3450)',
 ROT='0',
 VER='37',
 LOCATION='U25',
 CDS_LIB='pure_quanta',
 CDS_PART_NAME='GENOA_SP5-SOCKET6096_13568-001,SMLF,IO,DGA^6000030',
 PART_NUMBER='DGA^6000030',
 VALUE='SOCKET6096_13568-001',
 PRIM_FILE='./archive_libs/logical/genoa_sp5/chips/chips.prt';

SECTION_NUMBER 38
 '@T6G_MB_LIB.T6G(SCH_1):PAGE32_I15@PURE_QUANTA.GENOA_SP5(CHIPS)':
 C_PATH='@t6g_mb_lib.t6g(sch_1):page32_i15@pure_quanta.genoa_sp5(chips)',
 P_PATH='@t6g_mb_lib.t6g(sch_1):page32_i15@pure_quanta.genoa_sp5(chips)',
 PATH='I15',
 DRAWING='@T6G_MB_LIB.T6G(SCH_1):PAGE32',
 PART_TYPE='SMLF',
 MATERIAL='IO',
 PHYS_PAGE='32',
 XY='(-3675,3425)',
 ROT='0',
 VER='38',
 LOCATION='U25',
 CDS_LIB='pure_quanta',
 CDS_PART_NAME='GENOA_SP5-SOCKET6096_13568-001,SMLF,IO,DGA^6000030',
 PART_NUMBER='DGA^6000030',
 VALUE='SOCKET6096_13568-001',
 PRIM_FILE='./archive_libs/logical/genoa_sp5/chips/chips.prt';

SECTION_NUMBER 39
 '@T6G_MB_LIB.T6G(SCH_1):PAGE32_I16@PURE_QUANTA.GENOA_SP5(CHIPS)':
 C_PATH='@t6g_mb_lib.t6g(sch_1):page32_i16@pure_quanta.genoa_sp5(chips)',
 P_PATH='@t6g_mb_lib.t6g(sch_1):page32_i16@pure_quanta.genoa_sp5(chips)',
 PATH='I16',
 DRAWING='@T6G_MB_LIB.T6G(SCH_1):PAGE32',
 PART_TYPE='SMLF',
 MATERIAL='IO',
 PHYS_PAGE='32',
 XY='(-1600,3450)',
 ROT='0',
 VER='39',
 LOCATION='U25',
 CDS_LIB='pure_quanta',
 CDS_PART_NAME='GENOA_SP5-SOCKET6096_13568-001,SMLF,IO,DGA^6000030',
 PART_NUMBER='DGA^6000030',
 VALUE='SOCKET6096_13568-001',
 PRIM_FILE='./archive_libs/logical/genoa_sp5/chips/chips.prt';

SECTION_NUMBER 40
 '@T6G_MB_LIB.T6G(SCH_1):PAGE33_I4@PURE_QUANTA.GENOA_SP5(CHIPS)':
 C_PATH='@t6g_mb_lib.t6g(sch_1):page33_i4@pure_quanta.genoa_sp5(chips)',
 P_PATH='@t6g_mb_lib.t6g(sch_1):page33_i4@pure_quanta.genoa_sp5(chips)',
 PATH='I4',
 DRAWING='@T6G_MB_LIB.T6G(SCH_1):PAGE33',
 PART_TYPE='SMLF',
 MATERIAL='IO',
 PHYS_PAGE='33',
 XY='(-4750,3750)',
 ROT='1',
 VER='40',
 LOCATION='U25',
 CDS_LIB='pure_quanta',
 CDS_PART_NAME='GENOA_SP5-SOCKET6096_13568-001,SMLF,IO,DGA^6000030',
 PART_NUMBER='DGA^6000030',
 VALUE='SOCKET6096_13568-001',
 PRIM_FILE='./archive_libs/logical/genoa_sp5/chips/chips.prt';

PART_NAME
 U26 'GENOA_SP5-SOCKET6096_13568-001,SMLF,IO,DGA^6000030':;

SECTION_NUMBER 1
 '@T6G_MB_LIB.T6G(SCH_1):PAGE37_I167@PURE_QUANTA.GENOA_SP5(CHIPS)':
 C_PATH='@t6g_mb_lib.t6g(sch_1):page37_i167@pure_quanta.genoa_sp5(chips)',
 P_PATH='@t6g_mb_lib.t6g(sch_1):page37_i167@pure_quanta.genoa_sp5(chips)',
 PATH='I167',
 DRAWING='@T6G_MB_LIB.T6G(SCH_1):PAGE37',
 PART_TYPE='SMLF',
 MATERIAL='IO',
 PHYS_PAGE='37',
 XY='(-4575,3675)',
 ROT='0',
 VER='1',
 LOCATION='U26',
 CDS_LIB='pure_quanta',
 CDS_PART_NAME='GENOA_SP5-SOCKET6096_13568-001,SMLF,IO,DGA^6000030',
 PART_NUMBER='DGA^6000030',
 VALUE='SOCKET6096_13568-001',
 PRIM_FILE='./archive_libs/logical/genoa_sp5/chips/chips.prt';

SECTION_NUMBER 2
 '@T6G_MB_LIB.T6G(SCH_1):PAGE38_I159@PURE_QUANTA.GENOA_SP5(CHIPS)':
 C_PATH='@t6g_mb_lib.t6g(sch_1):page38_i159@pure_quanta.genoa_sp5(chips)',
 P_PATH='@t6g_mb_lib.t6g(sch_1):page38_i159@pure_quanta.genoa_sp5(chips)',
 PATH='I159',
 DRAWING='@T6G_MB_LIB.T6G(SCH_1):PAGE38',
 PART_TYPE='SMLF',
 MATERIAL='IO',
 PHYS_PAGE='38',
 XY='(-4725,3625)',
 ROT='0',
 VER='2',
 LOCATION='U26',
 CDS_LIB='pure_quanta',
 CDS_PART_NAME='GENOA_SP5-SOCKET6096_13568-001,SMLF,IO,DGA^6000030',
 PART_NUMBER='DGA^6000030',
 VALUE='SOCKET6096_13568-001',
 PRIM_FILE='./archive_libs/logical/genoa_sp5/chips/chips.prt';

SECTION_NUMBER 3
 '@T6G_MB_LIB.T6G(SCH_1):PAGE39_I159@PURE_QUANTA.GENOA_SP5(CHIPS)':
 C_PATH='@t6g_mb_lib.t6g(sch_1):page39_i159@pure_quanta.genoa_sp5(chips)',
 P_PATH='@t6g_mb_lib.t6g(sch_1):page39_i159@pure_quanta.genoa_sp5(chips)',
 PATH='I159',
 DRAWING='@T6G_MB_LIB.T6G(SCH_1):PAGE39',
 PART_TYPE='SMLF',
 MATERIAL='IO',
 PHYS_PAGE='39',
 XY='(-4750,3675)',
 ROT='0',
 VER='3',
 LOCATION='U26',
 CDS_LIB='pure_quanta',
 CDS_PART_NAME='GENOA_SP5-SOCKET6096_13568-001,SMLF,IO,DGA^6000030',
 PART_NUMBER='DGA^6000030',
 VALUE='SOCKET6096_13568-001',
 PRIM_FILE='./archive_libs/logical/genoa_sp5/chips/chips.prt';

SECTION_NUMBER 4
 '@T6G_MB_LIB.T6G(SCH_1):PAGE40_I159@PURE_QUANTA.GENOA_SP5(CHIPS)':
 C_PATH='@t6g_mb_lib.t6g(sch_1):page40_i159@pure_quanta.genoa_sp5(chips)',
 P_PATH='@t6g_mb_lib.t6g(sch_1):page40_i159@pure_quanta.genoa_sp5(chips)',
 PATH='I159',
 DRAWING='@T6G_MB_LIB.T6G(SCH_1):PAGE40',
 PART_TYPE='SMLF',
 MATERIAL='IO',
 PHYS_PAGE='40',
 XY='(-4600,3650)',
 ROT='0',
 VER='4',
 LOCATION='U26',
 CDS_LIB='pure_quanta',
 CDS_PART_NAME='GENOA_SP5-SOCKET6096_13568-001,SMLF,IO,DGA^6000030',
 PART_NUMBER='DGA^6000030',
 VALUE='SOCKET6096_13568-001',
 PRIM_FILE='./archive_libs/logical/genoa_sp5/chips/chips.prt';

SECTION_NUMBER 5
 '@T6G_MB_LIB.T6G(SCH_1):PAGE41_I159@PURE_QUANTA.GENOA_SP5(CHIPS)':
 C_PATH='@t6g_mb_lib.t6g(sch_1):page41_i159@pure_quanta.genoa_sp5(chips)',
 P_PATH='@t6g_mb_lib.t6g(sch_1):page41_i159@pure_quanta.genoa_sp5(chips)',
 PATH='I159',
 DRAWING='@T6G_MB_LIB.T6G(SCH_1):PAGE41',
 PART_TYPE='SMLF',
 MATERIAL='IO',
 PHYS_PAGE='41',
 XY='(-4700,3600)',
 ROT='0',
 VER='5',
 LOCATION='U26',
 CDS_LIB='pure_quanta',
 CDS_PART_NAME='GENOA_SP5-SOCKET6096_13568-001,SMLF,IO,DGA^6000030',
 PART_NUMBER='DGA^6000030',
 VALUE='SOCKET6096_13568-001',
 PRIM_FILE='./archive_libs/logical/genoa_sp5/chips/chips.prt';

SECTION_NUMBER 6
 '@T6G_MB_LIB.T6G(SCH_1):PAGE42_I159@PURE_QUANTA.GENOA_SP5(CHIPS)':
 C_PATH='@t6g_mb_lib.t6g(sch_1):page42_i159@pure_quanta.genoa_sp5(chips)',
 P_PATH='@t6g_mb_lib.t6g(sch_1):page42_i159@pure_quanta.genoa_sp5(chips)',
 PATH='I159',
 DRAWING='@T6G_MB_LIB.T6G(SCH_1):PAGE42',
 PART_TYPE='SMLF',
 MATERIAL='IO',
 PHYS_PAGE='42',
 XY='(-4600,3775)',
 ROT='0',
 VER='6',
 LOCATION='U26',
 CDS_LIB='pure_quanta',
 CDS_PART_NAME='GENOA_SP5-SOCKET6096_13568-001,SMLF,IO,DGA^6000030',
 PART_NUMBER='DGA^6000030',
 VALUE='SOCKET6096_13568-001',
 PRIM_FILE='./archive_libs/logical/genoa_sp5/chips/chips.prt';

SECTION_NUMBER 7
 '@T6G_MB_LIB.T6G(SCH_1):PAGE43_I167@PURE_QUANTA.GENOA_SP5(CHIPS)':
 C_PATH='@t6g_mb_lib.t6g(sch_1):page43_i167@pure_quanta.genoa_sp5(chips)',
 P_PATH='@t6g_mb_lib.t6g(sch_1):page43_i167@pure_quanta.genoa_sp5(chips)',
 PATH='I167',
 DRAWING='@T6G_MB_LIB.T6G(SCH_1):PAGE43',
 PART_TYPE='SMLF',
 MATERIAL='IO',
 PHYS_PAGE='43',
 XY='(-4700,3675)',
 ROT='0',
 VER='7',
 LOCATION='U26',
 CDS_LIB='pure_quanta',
 CDS_PART_NAME='GENOA_SP5-SOCKET6096_13568-001,SMLF,IO,DGA^6000030',
 PART_NUMBER='DGA^6000030',
 VALUE='SOCKET6096_13568-001',
 PRIM_FILE='./archive_libs/logical/genoa_sp5/chips/chips.prt';

SECTION_NUMBER 8
 '@T6G_MB_LIB.T6G(SCH_1):PAGE44_I159@PURE_QUANTA.GENOA_SP5(CHIPS)':
 C_PATH='@t6g_mb_lib.t6g(sch_1):page44_i159@pure_quanta.genoa_sp5(chips)',
 P_PATH='@t6g_mb_lib.t6g(sch_1):page44_i159@pure_quanta.genoa_sp5(chips)',
 PATH='I159',
 DRAWING='@T6G_MB_LIB.T6G(SCH_1):PAGE44',
 PART_TYPE='SMLF',
 MATERIAL='IO',
 PHYS_PAGE='44',
 XY='(-4625,3525)',
 ROT='0',
 VER='8',
 LOCATION='U26',
 CDS_LIB='pure_quanta',
 CDS_PART_NAME='GENOA_SP5-SOCKET6096_13568-001,SMLF,IO,DGA^6000030',
 PART_NUMBER='DGA^6000030',
 VALUE='SOCKET6096_13568-001',
 PRIM_FILE='./archive_libs/logical/genoa_sp5/chips/chips.prt';

SECTION_NUMBER 9
 '@T6G_MB_LIB.T6G(SCH_1):PAGE45_I159@PURE_QUANTA.GENOA_SP5(CHIPS)':
 C_PATH='@t6g_mb_lib.t6g(sch_1):page45_i159@pure_quanta.genoa_sp5(chips)',
 P_PATH='@t6g_mb_lib.t6g(sch_1):page45_i159@pure_quanta.genoa_sp5(chips)',
 PATH='I159',
 DRAWING='@T6G_MB_LIB.T6G(SCH_1):PAGE45',
 PART_TYPE='SMLF',
 MATERIAL='IO',
 PHYS_PAGE='45',
 XY='(-4500,3575)',
 ROT='0',
 VER='9',
 LOCATION='U26',
 CDS_LIB='pure_quanta',
 CDS_PART_NAME='GENOA_SP5-SOCKET6096_13568-001,SMLF,IO,DGA^6000030',
 PART_NUMBER='DGA^6000030',
 VALUE='SOCKET6096_13568-001',
 PRIM_FILE='./archive_libs/logical/genoa_sp5/chips/chips.prt';

SECTION_NUMBER 10
 '@T6G_MB_LIB.T6G(SCH_1):PAGE46_I159@PURE_QUANTA.GENOA_SP5(CHIPS)':
 C_PATH='@t6g_mb_lib.t6g(sch_1):page46_i159@pure_quanta.genoa_sp5(chips)',
 P_PATH='@t6g_mb_lib.t6g(sch_1):page46_i159@pure_quanta.genoa_sp5(chips)',
 PATH='I159',
 DRAWING='@T6G_MB_LIB.T6G(SCH_1):PAGE46',
 PART_TYPE='SMLF',
 MATERIAL='IO',
 PHYS_PAGE='46',
 XY='(-4525,3525)',
 ROT='0',
 VER='10',
 LOCATION='U26',
 CDS_LIB='pure_quanta',
 CDS_PART_NAME='GENOA_SP5-SOCKET6096_13568-001,SMLF,IO,DGA^6000030',
 PART_NUMBER='DGA^6000030',
 VALUE='SOCKET6096_13568-001',
 PRIM_FILE='./archive_libs/logical/genoa_sp5/chips/chips.prt';

SECTION_NUMBER 11
 '@T6G_MB_LIB.T6G(SCH_1):PAGE49_I213@PURE_QUANTA.GENOA_SP5(CHIPS)':
 C_PATH='@t6g_mb_lib.t6g(sch_1):page49_i213@pure_quanta.genoa_sp5(chips)',
 P_PATH='@t6g_mb_lib.t6g(sch_1):page49_i213@pure_quanta.genoa_sp5(chips)',
 PATH='I213',
 DRAWING='@T6G_MB_LIB.T6G(SCH_1):PAGE49',
 PART_TYPE='SMLF',
 MATERIAL='IO',
 PHYS_PAGE='49',
 XY='(-4775,5000)',
 ROT='0',
 VER='11',
 LOCATION='U26',
 CDS_LIB='pure_quanta',
 CDS_PART_NAME='GENOA_SP5-SOCKET6096_13568-001,SMLF,IO,DGA^6000030',
 PART_NUMBER='DGA^6000030',
 VALUE='SOCKET6096_13568-001',
 PRIM_FILE='./archive_libs/logical/genoa_sp5/chips/chips.prt';

SECTION_NUMBER 12
 '@T6G_MB_LIB.T6G(SCH_1):PAGE49_I214@PURE_QUANTA.GENOA_SP5(CHIPS)':
 C_PATH='@t6g_mb_lib.t6g(sch_1):page49_i214@pure_quanta.genoa_sp5(chips)',
 P_PATH='@t6g_mb_lib.t6g(sch_1):page49_i214@pure_quanta.genoa_sp5(chips)',
 PATH='I214',
 DRAWING='@T6G_MB_LIB.T6G(SCH_1):PAGE49',
 PART_TYPE='SMLF',
 MATERIAL='IO',
 PHYS_PAGE='49',
 XY='(-4750,2275)',
 ROT='0',
 VER='12',
 LOCATION='U26',
 CDS_LIB='pure_quanta',
 CDS_PART_NAME='GENOA_SP5-SOCKET6096_13568-001,SMLF,IO,DGA^6000030',
 PART_NUMBER='DGA^6000030',
 VALUE='SOCKET6096_13568-001',
 PRIM_FILE='./archive_libs/logical/genoa_sp5/chips/chips.prt';

SECTION_NUMBER 13
 '@T6G_MB_LIB.T6G(SCH_1):PAGE50_I143@PURE_QUANTA.GENOA_SP5(CHIPS)':
 C_PATH='@t6g_mb_lib.t6g(sch_1):page50_i143@pure_quanta.genoa_sp5(chips)',
 P_PATH='@t6g_mb_lib.t6g(sch_1):page50_i143@pure_quanta.genoa_sp5(chips)',
 PATH='I143',
 DRAWING='@T6G_MB_LIB.T6G(SCH_1):PAGE50',
 PART_TYPE='SMLF',
 MATERIAL='IO',
 PHYS_PAGE='50',
 XY='(-4750,5050)',
 ROT='0',
 VER='13',
 LOCATION='U26',
 CDS_LIB='pure_quanta',
 CDS_PART_NAME='GENOA_SP5-SOCKET6096_13568-001,SMLF,IO,DGA^6000030',
 PART_NUMBER='DGA^6000030',
 VALUE='SOCKET6096_13568-001',
 PRIM_FILE='./archive_libs/logical/genoa_sp5/chips/chips.prt';

SECTION_NUMBER 14
 '@T6G_MB_LIB.T6G(SCH_1):PAGE50_I144@PURE_QUANTA.GENOA_SP5(CHIPS)':
 C_PATH='@t6g_mb_lib.t6g(sch_1):page50_i144@pure_quanta.genoa_sp5(chips)',
 P_PATH='@t6g_mb_lib.t6g(sch_1):page50_i144@pure_quanta.genoa_sp5(chips)',
 PATH='I144',
 DRAWING='@T6G_MB_LIB.T6G(SCH_1):PAGE50',
 PART_TYPE='SMLF',
 MATERIAL='IO',
 PHYS_PAGE='50',
 XY='(-4725,2375)',
 ROT='0',
 VER='14',
 LOCATION='U26',
 CDS_LIB='pure_quanta',
 CDS_PART_NAME='GENOA_SP5-SOCKET6096_13568-001,SMLF,IO,DGA^6000030',
 PART_NUMBER='DGA^6000030',
 VALUE='SOCKET6096_13568-001',
 PRIM_FILE='./archive_libs/logical/genoa_sp5/chips/chips.prt';

SECTION_NUMBER 15
 '@T6G_MB_LIB.T6G(SCH_1):PAGE51_I147@PURE_QUANTA.GENOA_SP5(CHIPS)':
 C_PATH='@t6g_mb_lib.t6g(sch_1):page51_i147@pure_quanta.genoa_sp5(chips)',
 P_PATH='@t6g_mb_lib.t6g(sch_1):page51_i147@pure_quanta.genoa_sp5(chips)',
 PATH='I147',
 DRAWING='@T6G_MB_LIB.T6G(SCH_1):PAGE51',
 PART_TYPE='SMLF',
 MATERIAL='IO',
 PHYS_PAGE='51',
 XY='(-4700,4750)',
 ROT='0',
 VER='15',
 LOCATION='U26',
 CDS_LIB='pure_quanta',
 CDS_PART_NAME='GENOA_SP5-SOCKET6096_13568-001,SMLF,IO,DGA^6000030',
 PART_NUMBER='DGA^6000030',
 VALUE='SOCKET6096_13568-001',
 PRIM_FILE='./archive_libs/logical/genoa_sp5/chips/chips.prt';

SECTION_NUMBER 16
 '@T6G_MB_LIB.T6G(SCH_1):PAGE51_I148@PURE_QUANTA.GENOA_SP5(CHIPS)':
 C_PATH='@t6g_mb_lib.t6g(sch_1):page51_i148@pure_quanta.genoa_sp5(chips)',
 P_PATH='@t6g_mb_lib.t6g(sch_1):page51_i148@pure_quanta.genoa_sp5(chips)',
 PATH='I148',
 DRAWING='@T6G_MB_LIB.T6G(SCH_1):PAGE51',
 PART_TYPE='SMLF',
 MATERIAL='IO',
 PHYS_PAGE='51',
 XY='(-4700,2100)',
 ROT='0',
 VER='16',
 LOCATION='U26',
 CDS_LIB='pure_quanta',
 CDS_PART_NAME='GENOA_SP5-SOCKET6096_13568-001,SMLF,IO,DGA^6000030',
 PART_NUMBER='DGA^6000030',
 VALUE='SOCKET6096_13568-001',
 PRIM_FILE='./archive_libs/logical/genoa_sp5/chips/chips.prt';

SECTION_NUMBER 17
 '@T6G_MB_LIB.T6G(SCH_1):PAGE52_I148@PURE_QUANTA.GENOA_SP5(CHIPS)':
 C_PATH='@t6g_mb_lib.t6g(sch_1):page52_i148@pure_quanta.genoa_sp5(chips)',
 P_PATH='@t6g_mb_lib.t6g(sch_1):page52_i148@pure_quanta.genoa_sp5(chips)',
 PATH='I148',
 DRAWING='@T6G_MB_LIB.T6G(SCH_1):PAGE52',
 PART_TYPE='SMLF',
 MATERIAL='IO',
 PHYS_PAGE='52',
 XY='(-4625,4850)',
 ROT='0',
 VER='17',
 LOCATION='U26',
 CDS_LIB='pure_quanta',
 CDS_PART_NAME='GENOA_SP5-SOCKET6096_13568-001,SMLF,IO,DGA^6000030',
 PART_NUMBER='DGA^6000030',
 VALUE='SOCKET6096_13568-001',
 PRIM_FILE='./archive_libs/logical/genoa_sp5/chips/chips.prt';

SECTION_NUMBER 18
 '@T6G_MB_LIB.T6G(SCH_1):PAGE52_I147@PURE_QUANTA.GENOA_SP5(CHIPS)':
 C_PATH='@t6g_mb_lib.t6g(sch_1):page52_i147@pure_quanta.genoa_sp5(chips)',
 P_PATH='@t6g_mb_lib.t6g(sch_1):page52_i147@pure_quanta.genoa_sp5(chips)',
 PATH='I147',
 DRAWING='@T6G_MB_LIB.T6G(SCH_1):PAGE52',
 PART_TYPE='SMLF',
 MATERIAL='IO',
 PHYS_PAGE='52',
 XY='(-4625,2350)',
 ROT='0',
 VER='18',
 LOCATION='U26',
 CDS_LIB='pure_quanta',
 CDS_PART_NAME='GENOA_SP5-SOCKET6096_13568-001,SMLF,IO,DGA^6000030',
 PART_NUMBER='DGA^6000030',
 VALUE='SOCKET6096_13568-001',
 PRIM_FILE='./archive_libs/logical/genoa_sp5/chips/chips.prt';

SECTION_NUMBER 19
 '@T6G_MB_LIB.T6G(SCH_1):PAGE53_I145@PURE_QUANTA.GENOA_SP5(CHIPS)':
 C_PATH='@t6g_mb_lib.t6g(sch_1):page53_i145@pure_quanta.genoa_sp5(chips)',
 P_PATH='@t6g_mb_lib.t6g(sch_1):page53_i145@pure_quanta.genoa_sp5(chips)',
 PATH='I145',
 DRAWING='@T6G_MB_LIB.T6G(SCH_1):PAGE53',
 PART_TYPE='SMLF',
 MATERIAL='IO',
 PHYS_PAGE='53',
 XY='(-5175,5225)',
 ROT='0',
 VER='19',
 LOCATION='U26',
 CDS_LIB='pure_quanta',
 CDS_PART_NAME='GENOA_SP5-SOCKET6096_13568-001,SMLF,IO,DGA^6000030',
 PART_NUMBER='DGA^6000030',
 VALUE='SOCKET6096_13568-001',
 PRIM_FILE='./archive_libs/logical/genoa_sp5/chips/chips.prt';

SECTION_NUMBER 20
 '@T6G_MB_LIB.T6G(SCH_1):PAGE54_I190@PURE_QUANTA.GENOA_SP5(CHIPS)':
 C_PATH='@t6g_mb_lib.t6g(sch_1):page54_i190@pure_quanta.genoa_sp5(chips)',
 P_PATH='@t6g_mb_lib.t6g(sch_1):page54_i190@pure_quanta.genoa_sp5(chips)',
 PATH='I190',
 DRAWING='@T6G_MB_LIB.T6G(SCH_1):PAGE54',
 PART_TYPE='SMLF',
 MATERIAL='IO',
 PHYS_PAGE='54',
 XY='(-4650,3750)',
 ROT='0',
 VER='20',
 LOCATION='U26',
 CDS_LIB='pure_quanta',
 CDS_PART_NAME='GENOA_SP5-SOCKET6096_13568-001,SMLF,IO,DGA^6000030',
 PART_NUMBER='DGA^6000030',
 VALUE='SOCKET6096_13568-001',
 PRIM_FILE='./archive_libs/logical/genoa_sp5/chips/chips.prt';

SECTION_NUMBER 21
 '@T6G_MB_LIB.T6G(SCH_1):PAGE55_I182@PURE_QUANTA.GENOA_SP5(CHIPS)':
 C_PATH='@t6g_mb_lib.t6g(sch_1):page55_i182@pure_quanta.genoa_sp5(chips)',
 P_PATH='@t6g_mb_lib.t6g(sch_1):page55_i182@pure_quanta.genoa_sp5(chips)',
 PATH='I182',
 DRAWING='@T6G_MB_LIB.T6G(SCH_1):PAGE55',
 PART_TYPE='SMLF',
 MATERIAL='IO',
 PHYS_PAGE='55',
 XY='(-4375,4475)',
 ROT='0',
 VER='21',
 LOCATION='U26',
 CDS_LIB='pure_quanta',
 CDS_PART_NAME='GENOA_SP5-SOCKET6096_13568-001,SMLF,IO,DGA^6000030',
 PART_NUMBER='DGA^6000030',
 VALUE='SOCKET6096_13568-001',
 PRIM_FILE='./archive_libs/logical/genoa_sp5/chips/chips.prt';

SECTION_NUMBER 22
 '@T6G_MB_LIB.T6G(SCH_1):PAGE56_I8@PURE_QUANTA.GENOA_SP5(CHIPS)':
 C_PATH='@t6g_mb_lib.t6g(sch_1):page56_i8@pure_quanta.genoa_sp5(chips)',
 P_PATH='@t6g_mb_lib.t6g(sch_1):page56_i8@pure_quanta.genoa_sp5(chips)',
 PATH='I8',
 DRAWING='@T6G_MB_LIB.T6G(SCH_1):PAGE56',
 PART_TYPE='SMLF',
 MATERIAL='IO',
 PHYS_PAGE='56',
 XY='(-4525,4675)',
 ROT='0',
 VER='22',
 LOCATION='U26',
 CDS_LIB='pure_quanta',
 CDS_PART_NAME='GENOA_SP5-SOCKET6096_13568-001,SMLF,IO,DGA^6000030',
 PART_NUMBER='DGA^6000030',
 VALUE='SOCKET6096_13568-001',
 PRIM_FILE='./archive_libs/logical/genoa_sp5/chips/chips.prt';

SECTION_NUMBER 23
 '@T6G_MB_LIB.T6G(SCH_1):PAGE57_I46@PURE_QUANTA.GENOA_SP5(CHIPS)':
 C_PATH='@t6g_mb_lib.t6g(sch_1):page57_i46@pure_quanta.genoa_sp5(chips)',
 P_PATH='@t6g_mb_lib.t6g(sch_1):page57_i46@pure_quanta.genoa_sp5(chips)',
 PATH='I46',
 DRAWING='@T6G_MB_LIB.T6G(SCH_1):PAGE57',
 PART_TYPE='SMLF',
 MATERIAL='IO',
 PHYS_PAGE='57',
 XY='(-875,4325)',
 ROT='0',
 VER='23',
 LOCATION='U26',
 CDS_LIB='pure_quanta',
 CDS_PART_NAME='GENOA_SP5-SOCKET6096_13568-001,SMLF,IO,DGA^6000030',
 PART_NUMBER='DGA^6000030',
 VALUE='SOCKET6096_13568-001',
 PRIM_FILE='./archive_libs/logical/genoa_sp5/chips/chips.prt';

SECTION_NUMBER 24
 '@T6G_MB_LIB.T6G(SCH_1):PAGE57_I29@PURE_QUANTA.GENOA_SP5(CHIPS)':
 C_PATH='@t6g_mb_lib.t6g(sch_1):page57_i29@pure_quanta.genoa_sp5(chips)',
 P_PATH='@t6g_mb_lib.t6g(sch_1):page57_i29@pure_quanta.genoa_sp5(chips)',
 PATH='I29',
 DRAWING='@T6G_MB_LIB.T6G(SCH_1):PAGE57',
 PART_TYPE='SMLF',
 MATERIAL='IO',
 PHYS_PAGE='57',
 XY='(-8150,3350)',
 ROT='0',
 VER='24',
 LOCATION='U26',
 CDS_LIB='pure_quanta',
 CDS_PART_NAME='GENOA_SP5-SOCKET6096_13568-001,SMLF,IO,DGA^6000030',
 PART_NUMBER='DGA^6000030',
 VALUE='SOCKET6096_13568-001',
 PRIM_FILE='./archive_libs/logical/genoa_sp5/chips/chips.prt';

SECTION_NUMBER 25
 '@T6G_MB_LIB.T6G(SCH_1):PAGE57_I32@PURE_QUANTA.GENOA_SP5(CHIPS)':
 C_PATH='@t6g_mb_lib.t6g(sch_1):page57_i32@pure_quanta.genoa_sp5(chips)',
 P_PATH='@t6g_mb_lib.t6g(sch_1):page57_i32@pure_quanta.genoa_sp5(chips)',
 PATH='I32',
 DRAWING='@T6G_MB_LIB.T6G(SCH_1):PAGE57',
 PART_TYPE='SMLF',
 MATERIAL='IO',
 PHYS_PAGE='57',
 XY='(-6225,3375)',
 ROT='0',
 VER='25',
 LOCATION='U26',
 CDS_LIB='pure_quanta',
 CDS_PART_NAME='GENOA_SP5-SOCKET6096_13568-001,SMLF,IO,DGA^6000030',
 PART_NUMBER='DGA^6000030',
 VALUE='SOCKET6096_13568-001',
 PRIM_FILE='./archive_libs/logical/genoa_sp5/chips/chips.prt';

SECTION_NUMBER 26
 '@T6G_MB_LIB.T6G(SCH_1):PAGE57_I49@PURE_QUANTA.GENOA_SP5(CHIPS)':
 C_PATH='@t6g_mb_lib.t6g(sch_1):page57_i49@pure_quanta.genoa_sp5(chips)',
 P_PATH='@t6g_mb_lib.t6g(sch_1):page57_i49@pure_quanta.genoa_sp5(chips)',
 PATH='I49',
 DRAWING='@T6G_MB_LIB.T6G(SCH_1):PAGE57',
 PART_TYPE='SMLF',
 MATERIAL='IO',
 PHYS_PAGE='57',
 XY='(-4475,4675)',
 ROT='0',
 VER='26',
 LOCATION='U26',
 CDS_LIB='pure_quanta',
 CDS_PART_NAME='GENOA_SP5-SOCKET6096_13568-001,SMLF,IO,DGA^6000030',
 PART_NUMBER='DGA^6000030',
 VALUE='SOCKET6096_13568-001',
 PRIM_FILE='./archive_libs/logical/genoa_sp5/chips/chips.prt';

SECTION_NUMBER 27
 '@T6G_MB_LIB.T6G(SCH_1):PAGE57_I45@PURE_QUANTA.GENOA_SP5(CHIPS)':
 C_PATH='@t6g_mb_lib.t6g(sch_1):page57_i45@pure_quanta.genoa_sp5(chips)',
 P_PATH='@t6g_mb_lib.t6g(sch_1):page57_i45@pure_quanta.genoa_sp5(chips)',
 PATH='I45',
 DRAWING='@T6G_MB_LIB.T6G(SCH_1):PAGE57',
 PART_TYPE='SMLF',
 MATERIAL='IO',
 PHYS_PAGE='57',
 XY='(-2800,3500)',
 ROT='0',
 VER='27',
 LOCATION='U26',
 CDS_LIB='pure_quanta',
 CDS_PART_NAME='GENOA_SP5-SOCKET6096_13568-001,SMLF,IO,DGA^6000030',
 PART_NUMBER='DGA^6000030',
 VALUE='SOCKET6096_13568-001',
 PRIM_FILE='./archive_libs/logical/genoa_sp5/chips/chips.prt';

SECTION_NUMBER 28
 '@T6G_MB_LIB.T6G(SCH_1):PAGE58_I1@PURE_QUANTA.GENOA_SP5(CHIPS)':
 C_PATH='@t6g_mb_lib.t6g(sch_1):page58_i1@pure_quanta.genoa_sp5(chips)',
 P_PATH='@t6g_mb_lib.t6g(sch_1):page58_i1@pure_quanta.genoa_sp5(chips)',
 PATH='I1',
 DRAWING='@T6G_MB_LIB.T6G(SCH_1):PAGE58',
 PART_TYPE='SMLF',
 MATERIAL='IO',
 PHYS_PAGE='58',
 XY='(-8575,3425)',
 ROT='0',
 VER='28',
 LOCATION='U26',
 CDS_LIB='pure_quanta',
 CDS_PART_NAME='GENOA_SP5-SOCKET6096_13568-001,SMLF,IO,DGA^6000030',
 PART_NUMBER='DGA^6000030',
 VALUE='SOCKET6096_13568-001',
 PRIM_FILE='./archive_libs/logical/genoa_sp5/chips/chips.prt';

SECTION_NUMBER 29
 '@T6G_MB_LIB.T6G(SCH_1):PAGE58_I15@PURE_QUANTA.GENOA_SP5(CHIPS)':
 C_PATH='@t6g_mb_lib.t6g(sch_1):page58_i15@pure_quanta.genoa_sp5(chips)',
 P_PATH='@t6g_mb_lib.t6g(sch_1):page58_i15@pure_quanta.genoa_sp5(chips)',
 PATH='I15',
 DRAWING='@T6G_MB_LIB.T6G(SCH_1):PAGE58',
 PART_TYPE='SMLF',
 MATERIAL='IO',
 PHYS_PAGE='58',
 XY='(-7050,3450)',
 ROT='0',
 VER='29',
 LOCATION='U26',
 CDS_LIB='pure_quanta',
 CDS_PART_NAME='GENOA_SP5-SOCKET6096_13568-001,SMLF,IO,DGA^6000030',
 PART_NUMBER='DGA^6000030',
 VALUE='SOCKET6096_13568-001',
 PRIM_FILE='./archive_libs/logical/genoa_sp5/chips/chips.prt';

SECTION_NUMBER 30
 '@T6G_MB_LIB.T6G(SCH_1):PAGE58_I12@PURE_QUANTA.GENOA_SP5(CHIPS)':
 C_PATH='@t6g_mb_lib.t6g(sch_1):page58_i12@pure_quanta.genoa_sp5(chips)',
 P_PATH='@t6g_mb_lib.t6g(sch_1):page58_i12@pure_quanta.genoa_sp5(chips)',
 PATH='I12',
 DRAWING='@T6G_MB_LIB.T6G(SCH_1):PAGE58',
 PART_TYPE='SMLF',
 MATERIAL='IO',
 PHYS_PAGE='58',
 XY='(-5575,3475)',
 ROT='0',
 VER='30',
 LOCATION='U26',
 CDS_LIB='pure_quanta',
 CDS_PART_NAME='GENOA_SP5-SOCKET6096_13568-001,SMLF,IO,DGA^6000030',
 PART_NUMBER='DGA^6000030',
 VALUE='SOCKET6096_13568-001',
 PRIM_FILE='./archive_libs/logical/genoa_sp5/chips/chips.prt';

SECTION_NUMBER 31
 '@T6G_MB_LIB.T6G(SCH_1):PAGE58_I9@PURE_QUANTA.GENOA_SP5(CHIPS)':
 C_PATH='@t6g_mb_lib.t6g(sch_1):page58_i9@pure_quanta.genoa_sp5(chips)',
 P_PATH='@t6g_mb_lib.t6g(sch_1):page58_i9@pure_quanta.genoa_sp5(chips)',
 PATH='I9',
 DRAWING='@T6G_MB_LIB.T6G(SCH_1):PAGE58',
 PART_TYPE='SMLF',
 MATERIAL='IO',
 PHYS_PAGE='58',
 XY='(-4075,3500)',
 ROT='0',
 VER='31',
 LOCATION='U26',
 CDS_LIB='pure_quanta',
 CDS_PART_NAME='GENOA_SP5-SOCKET6096_13568-001,SMLF,IO,DGA^6000030',
 PART_NUMBER='DGA^6000030',
 VALUE='SOCKET6096_13568-001',
 PRIM_FILE='./archive_libs/logical/genoa_sp5/chips/chips.prt';

SECTION_NUMBER 32
 '@T6G_MB_LIB.T6G(SCH_1):PAGE58_I6@PURE_QUANTA.GENOA_SP5(CHIPS)':
 C_PATH='@t6g_mb_lib.t6g(sch_1):page58_i6@pure_quanta.genoa_sp5(chips)',
 P_PATH='@t6g_mb_lib.t6g(sch_1):page58_i6@pure_quanta.genoa_sp5(chips)',
 PATH='I6',
 DRAWING='@T6G_MB_LIB.T6G(SCH_1):PAGE58',
 PART_TYPE='SMLF',
 MATERIAL='IO',
 PHYS_PAGE='58',
 XY='(-2600,3500)',
 ROT='0',
 VER='32',
 LOCATION='U26',
 CDS_LIB='pure_quanta',
 CDS_PART_NAME='GENOA_SP5-SOCKET6096_13568-001,SMLF,IO,DGA^6000030',
 PART_NUMBER='DGA^6000030',
 VALUE='SOCKET6096_13568-001',
 PRIM_FILE='./archive_libs/logical/genoa_sp5/chips/chips.prt';

SECTION_NUMBER 33
 '@T6G_MB_LIB.T6G(SCH_1):PAGE58_I3@PURE_QUANTA.GENOA_SP5(CHIPS)':
 C_PATH='@t6g_mb_lib.t6g(sch_1):page58_i3@pure_quanta.genoa_sp5(chips)',
 P_PATH='@t6g_mb_lib.t6g(sch_1):page58_i3@pure_quanta.genoa_sp5(chips)',
 PATH='I3',
 DRAWING='@T6G_MB_LIB.T6G(SCH_1):PAGE58',
 PART_TYPE='SMLF',
 MATERIAL='IO',
 PHYS_PAGE='58',
 XY='(-975,3500)',
 ROT='0',
 VER='33',
 LOCATION='U26',
 CDS_LIB='pure_quanta',
 CDS_PART_NAME='GENOA_SP5-SOCKET6096_13568-001,SMLF,IO,DGA^6000030',
 PART_NUMBER='DGA^6000030',
 VALUE='SOCKET6096_13568-001',
 PRIM_FILE='./archive_libs/logical/genoa_sp5/chips/chips.prt';

SECTION_NUMBER 34
 '@T6G_MB_LIB.T6G(SCH_1):PAGE59_I1@PURE_QUANTA.GENOA_SP5(CHIPS)':
 C_PATH='@t6g_mb_lib.t6g(sch_1):page59_i1@pure_quanta.genoa_sp5(chips)',
 P_PATH='@t6g_mb_lib.t6g(sch_1):page59_i1@pure_quanta.genoa_sp5(chips)',
 PATH='I1',
 DRAWING='@T6G_MB_LIB.T6G(SCH_1):PAGE59',
 PART_TYPE='SMLF',
 MATERIAL='IO',
 PHYS_PAGE='59',
 XY='(-7975,3500)',
 ROT='0',
 VER='34',
 LOCATION='U26',
 CDS_LIB='pure_quanta',
 CDS_PART_NAME='GENOA_SP5-SOCKET6096_13568-001,SMLF,IO,DGA^6000030',
 PART_NUMBER='DGA^6000030',
 VALUE='SOCKET6096_13568-001',
 PRIM_FILE='./archive_libs/logical/genoa_sp5/chips/chips.prt';

SECTION_NUMBER 35
 '@T6G_MB_LIB.T6G(SCH_1):PAGE48_I159@PURE_QUANTA.GENOA_SP5(CHIPS)':
 C_PATH='@t6g_mb_lib.t6g(sch_1):page48_i159@pure_quanta.genoa_sp5(chips)',
 P_PATH='@t6g_mb_lib.t6g(sch_1):page48_i159@pure_quanta.genoa_sp5(chips)',
 PATH='I159',
 DRAWING='@T6G_MB_LIB.T6G(SCH_1):PAGE48',
 PART_TYPE='SMLF',
 MATERIAL='IO',
 PHYS_PAGE='48',
 XY='(-4550,3550)',
 ROT='0',
 VER='35',
 LOCATION='U26',
 CDS_LIB='pure_quanta',
 CDS_PART_NAME='GENOA_SP5-SOCKET6096_13568-001,SMLF,IO,DGA^6000030',
 PART_NUMBER='DGA^6000030',
 VALUE='SOCKET6096_13568-001',
 PRIM_FILE='./archive_libs/logical/genoa_sp5/chips/chips.prt';

SECTION_NUMBER 36
 '@T6G_MB_LIB.T6G(SCH_1):PAGE47_I159@PURE_QUANTA.GENOA_SP5(CHIPS)':
 C_PATH='@t6g_mb_lib.t6g(sch_1):page47_i159@pure_quanta.genoa_sp5(chips)',
 P_PATH='@t6g_mb_lib.t6g(sch_1):page47_i159@pure_quanta.genoa_sp5(chips)',
 PATH='I159',
 DRAWING='@T6G_MB_LIB.T6G(SCH_1):PAGE47',
 PART_TYPE='SMLF',
 MATERIAL='IO',
 PHYS_PAGE='47',
 XY='(-4500,3525)',
 ROT='0',
 VER='36',
 LOCATION='U26',
 CDS_LIB='pure_quanta',
 CDS_PART_NAME='GENOA_SP5-SOCKET6096_13568-001,SMLF,IO,DGA^6000030',
 PART_NUMBER='DGA^6000030',
 VALUE='SOCKET6096_13568-001',
 PRIM_FILE='./archive_libs/logical/genoa_sp5/chips/chips.prt';

SECTION_NUMBER 37
 '@T6G_MB_LIB.T6G(SCH_1):PAGE59_I2@PURE_QUANTA.GENOA_SP5(CHIPS)':
 C_PATH='@t6g_mb_lib.t6g(sch_1):page59_i2@pure_quanta.genoa_sp5(chips)',
 P_PATH='@t6g_mb_lib.t6g(sch_1):page59_i2@pure_quanta.genoa_sp5(chips)',
 PATH='I2',
 DRAWING='@T6G_MB_LIB.T6G(SCH_1):PAGE59',
 PART_TYPE='SMLF',
 MATERIAL='IO',
 PHYS_PAGE='59',
 XY='(-5950,3500)',
 ROT='0',
 VER='37',
 LOCATION='U26',
 CDS_LIB='pure_quanta',
 CDS_PART_NAME='GENOA_SP5-SOCKET6096_13568-001,SMLF,IO,DGA^6000030',
 PART_NUMBER='DGA^6000030',
 VALUE='SOCKET6096_13568-001',
 PRIM_FILE='./archive_libs/logical/genoa_sp5/chips/chips.prt';

SECTION_NUMBER 38
 '@T6G_MB_LIB.T6G(SCH_1):PAGE59_I3@PURE_QUANTA.GENOA_SP5(CHIPS)':
 C_PATH='@t6g_mb_lib.t6g(sch_1):page59_i3@pure_quanta.genoa_sp5(chips)',
 P_PATH='@t6g_mb_lib.t6g(sch_1):page59_i3@pure_quanta.genoa_sp5(chips)',
 PATH='I3',
 DRAWING='@T6G_MB_LIB.T6G(SCH_1):PAGE59',
 PART_TYPE='SMLF',
 MATERIAL='IO',
 PHYS_PAGE='59',
 XY='(-3875,3475)',
 ROT='0',
 VER='38',
 LOCATION='U26',
 CDS_LIB='pure_quanta',
 CDS_PART_NAME='GENOA_SP5-SOCKET6096_13568-001,SMLF,IO,DGA^6000030',
 PART_NUMBER='DGA^6000030',
 VALUE='SOCKET6096_13568-001',
 PRIM_FILE='./archive_libs/logical/genoa_sp5/chips/chips.prt';

SECTION_NUMBER 39
 '@T6G_MB_LIB.T6G(SCH_1):PAGE59_I4@PURE_QUANTA.GENOA_SP5(CHIPS)':
 C_PATH='@t6g_mb_lib.t6g(sch_1):page59_i4@pure_quanta.genoa_sp5(chips)',
 P_PATH='@t6g_mb_lib.t6g(sch_1):page59_i4@pure_quanta.genoa_sp5(chips)',
 PATH='I4',
 DRAWING='@T6G_MB_LIB.T6G(SCH_1):PAGE59',
 PART_TYPE='SMLF',
 MATERIAL='IO',
 PHYS_PAGE='59',
 XY='(-1800,3500)',
 ROT='0',
 VER='39',
 LOCATION='U26',
 CDS_LIB='pure_quanta',
 CDS_PART_NAME='GENOA_SP5-SOCKET6096_13568-001,SMLF,IO,DGA^6000030',
 PART_NUMBER='DGA^6000030',
 VALUE='SOCKET6096_13568-001',
 PRIM_FILE='./archive_libs/logical/genoa_sp5/chips/chips.prt';

SECTION_NUMBER 40
 '@T6G_MB_LIB.T6G(SCH_1):PAGE60_I3@PURE_QUANTA.GENOA_SP5(CHIPS)':
 C_PATH='@t6g_mb_lib.t6g(sch_1):page60_i3@pure_quanta.genoa_sp5(chips)',
 P_PATH='@t6g_mb_lib.t6g(sch_1):page60_i3@pure_quanta.genoa_sp5(chips)',
 PATH='I3',
 DRAWING='@T6G_MB_LIB.T6G(SCH_1):PAGE60',
 PART_TYPE='SMLF',
 MATERIAL='IO',
 PHYS_PAGE='60',
 XY='(-4525,3950)',
 ROT='1',
 VER='40',
 LOCATION='U26',
 CDS_LIB='pure_quanta',
 CDS_PART_NAME='GENOA_SP5-SOCKET6096_13568-001,SMLF,IO,DGA^6000030',
 PART_NUMBER='DGA^6000030',
 VALUE='SOCKET6096_13568-001',
 PRIM_FILE='./archive_libs/logical/genoa_sp5/chips/chips.prt';

PART_NAME
 U27 'PCA9617ADP-PCA9617ADP,SMLF,IC,AL009617K02':;

SECTION_NUMBER 1
 '@T6G_MB_LIB.T6G(SCH_1):PAGE34_I18@PURE_QUANTA.PCA9617ADP(CHIPS)':
 C_PATH='@t6g_mb_lib.t6g(sch_1):page34_i18@pure_quanta.pca9617adp(chips)',
 P_PATH='@t6g_mb_lib.t6g(sch_1):page34_i18@pure_quanta.pca9617adp(chips)',
 PATH='I18',
 DRAWING='@T6G_MB_LIB.T6G(SCH_1):PAGE34',
 PART_TYPE='SMLF',
 MATERIAL='IC',
 PHYS_PAGE='34',
 XY='(-7200,5575)',
 ROT='0',
 VER='1',
 LOCATION='U27',
 CDS_LIB='pure_quanta',
 CDS_PART_NAME='PCA9617ADP-PCA9617ADP,SMLF,IC,AL009617K02',
 PART_NUMBER='AL009617K02',
 VALUE='PCA9617ADP',
 PRIM_FILE='./archive_libs/logical/pca9617adp/chips/chips.prt';

PART_NAME
 U28 'SN74LVC1G07DBVR_SMLF-SN74LVC1G07DBVR,IC,AL1G0007024':;

SECTION_NUMBER 1
 '@T6G_MB_LIB.T6G(SCH_1):PAGE340_I51@PURE_QUANTA.SN74LVC1G07DBVR(CHIPS)':
 C_PATH='@t6g_mb_lib.t6g(sch_1):page340_i51@pure_quanta.sn74lvc1g07dbvr(chips)',
 P_PATH='@t6g_mb_lib.t6g(sch_1):page136_i51@pure_quanta.sn74lvc1g07dbvr(chips)',
 PATH='I51',
 DRAWING='@T6G_MB_LIB.T6G(SCH_1):PAGE340',
 MATERIAL='IC',
 PHYS_PAGE='136',
 XY='(-2375,7450)',
 ROT='0',
 VER='1',
 PACK_TYPE='SMLF',
 LOCATION='U28',
 CDS_LIB='pure_quanta',
 CDS_PART_NAME='SN74LVC1G07DBVR_SMLF-SN74LVC1G07DBVR,IC,AL1G0007024',
 PART_NUMBER='AL1G0007024',
 VALUE='SN74LVC1G07DBVR',
 PRIM_FILE='./archive_libs/logical/sn74lvc1g07dbvr/chips/chips.prt';

PART_NAME
 U29 'SN74LVC2G07DCKR_SMLF-SN74LVC2G07DCKR,IC,AL002G07006':;

SECTION_NUMBER 1
 '@T6G_MB_LIB.T6G(SCH_1):PAGE77_I15@PURE_QUANTA.SN74LVC2G07DCKR(CHIPS)':
 C_PATH='@t6g_mb_lib.t6g(sch_1):page77_i15@pure_quanta.sn74lvc2g07dckr(chips)',
 P_PATH='@t6g_mb_lib.t6g(sch_1):page78_i15@pure_quanta.sn74lvc2g07dckr(chips)',
 PATH='I15',
 DRAWING='@T6G_MB_LIB.T6G(SCH_1):PAGE77',
 MATERIAL='IC',
 PHYS_PAGE='78',
 XY='(-4675,4275)',
 ROT='0',
 VER='1',
 PACK_TYPE='SMLF',
 LOCATION='U29',
 CDS_LIB='pure_quanta',
 CDS_PART_NAME='SN74LVC2G07DCKR_SMLF-SN74LVC2G07DCKR,IC,AL002G07006',
 PART_NUMBER='AL002G07006',
 VALUE='SN74LVC2G07DCKR',
 PRIM_FILE='./archive_libs/logical/sn74lvc2g07dckr/chips/chips.prt';

PART_NAME
 U30 'SN74LVC1G07DBVR_SMLF-SN74LVC1G07DBVR,IC,AL1G0007024':;

SECTION_NUMBER 1
 '@T6G_MB_LIB.T6G(SCH_1):PAGE340_I66@PURE_QUANTA.SN74LVC1G07DBVR(CHIPS)':
 C_PATH='@t6g_mb_lib.t6g(sch_1):page340_i66@pure_quanta.sn74lvc1g07dbvr(chips)',
 P_PATH='@t6g_mb_lib.t6g(sch_1):page136_i66@pure_quanta.sn74lvc1g07dbvr(chips)',
 PATH='I66',
 DRAWING='@T6G_MB_LIB.T6G(SCH_1):PAGE340',
 MATERIAL='IC',
 PHYS_PAGE='136',
 XY='(900,8225)',
 ROT='0',
 VER='1',
 PACK_TYPE='SMLF',
 LOCATION='U30',
 CDS_LIB='pure_quanta',
 CDS_PART_NAME='SN74LVC1G07DBVR_SMLF-SN74LVC1G07DBVR,IC,AL1G0007024',
 PART_NUMBER='AL1G0007024',
 VALUE='SN74LVC1G07DBVR',
 PRIM_FILE='./archive_libs/logical/sn74lvc1g07dbvr/chips/chips.prt';

PART_NAME
 U31 '74LVC1G08W57-74LVC1G08W5-7,SMLF,IC,AL1G0008020':;

SECTION_NUMBER 1
 '@T6G_MB_LIB.T6G(SCH_1):PAGE257_I31@PURE_QUANTA.74LVC1G08W57(CHIPS)':
 C_PATH='@t6g_mb_lib.t6g(sch_1):page257_i31@pure_quanta.\74lvc1g08w57\(chips)',
 P_PATH='@t6g_mb_lib.t6g(sch_1):page142_i31@pure_quanta.\74lvc1g08w57\(chips)',
 PATH='I31',
 DRAWING='@T6G_MB_LIB.T6G(SCH_1):PAGE257',
 SEC_TYPE='',
 PART_TYPE='SMLF',
 MATERIAL='IC',
 PHYS_PAGE='142',
 XY='(-950,3325)',
 ROT='0',
 VER='1',
 LOCATION='U31',
 SEC='1',
 CDS_LIB='pure_quanta',
 CDS_PART_NAME='74LVC1G08W57-74LVC1G08W5-7,SMLF,IC,AL1G0008020',
 PART_NUMBER='AL1G0008020',
 VALUE='74LVC1G08W5-7',
 PRIM_FILE='./archive_libs/logical/74lvc1g08w57/chips/chips.prt';

PART_NAME
 U32 'MOSFET_N_SMLF-BSS138K,BSS138K,IC,BAM138K0000':;

SECTION_NUMBER 1
 '@T6G_MB_LIB.T6G(SCH_1):PAGE257_I24@PURE_QUANTA.MOSFET_N(CHIPS)':
 C_PATH='@t6g_mb_lib.t6g(sch_1):page257_i24@pure_quanta.mosfet_n(chips)',
 P_PATH='@t6g_mb_lib.t6g(sch_1):page142_i24@pure_quanta.mosfet_n(chips)',
 PATH='I24',
 DRAWING='@T6G_MB_LIB.T6G(SCH_1):PAGE257',
 MANUF_PN='BSS138K',
 MATERIAL='IC',
 PHYS_PAGE='142',
 XY='(-4125,3075)',
 ROT='0',
 VER='1',
 PACK_TYPE='SMLF',
 LOCATION='U32',
 CDS_LIB='pure_quanta',
 CDS_PART_NAME='MOSFET_N_SMLF-BSS138K,BSS138K,IC,BAM138K0000',
 PART_NUMBER='BAM138K0000',
 VALUE='BSS138K',
 PRIM_FILE='./archive_libs/logical/mosfet_n/chips/chips.prt';

PART_NAME
 U33 'SN74LVC1G07DBVR_SMLF-SN74LVC1G07DBVR,IC,AL1G0007024':;

SECTION_NUMBER 1
 '@T6G_MB_LIB.T6G(SCH_1):PAGE257_I64@PURE_QUANTA.SN74LVC1G07DBVR(CHIPS)':
 C_PATH='@t6g_mb_lib.t6g(sch_1):page257_i64@pure_quanta.sn74lvc1g07dbvr(chips)',
 P_PATH='@t6g_mb_lib.t6g(sch_1):page142_i64@pure_quanta.sn74lvc1g07dbvr(chips)',
 PATH='I64',
 DRAWING='@T6G_MB_LIB.T6G(SCH_1):PAGE257',
 MATERIAL='IC',
 PHYS_PAGE='142',
 XY='(-2575,1575)',
 ROT='0',
 VER='1',
 PACK_TYPE='SMLF',
 LOCATION='U33',
 CDS_LIB='pure_quanta',
 CDS_PART_NAME='SN74LVC1G07DBVR_SMLF-SN74LVC1G07DBVR,IC,AL1G0007024',
 PART_NUMBER='AL1G0007024',
 VALUE='SN74LVC1G07DBVR',
 PRIM_FILE='./archive_libs/logical/sn74lvc1g07dbvr/chips/chips.prt';

PART_NAME
 U34 'SN74LVC1G07DBVR_SMLF-SN74LVC1G07DBVR,IC,AL1G0007024':;

SECTION_NUMBER 1
 '@T6G_MB_LIB.T6G(SCH_1):PAGE257_I45@PURE_QUANTA.SN74LVC1G07DBVR(CHIPS)':
 C_PATH='@t6g_mb_lib.t6g(sch_1):page257_i45@pure_quanta.sn74lvc1g07dbvr(chips)',
 P_PATH='@t6g_mb_lib.t6g(sch_1):page142_i45@pure_quanta.sn74lvc1g07dbvr(chips)',
 PATH='I45',
 DRAWING='@T6G_MB_LIB.T6G(SCH_1):PAGE257',
 MATERIAL='IC',
 PHYS_PAGE='142',
 XY='(700,2350)',
 ROT='0',
 VER='1',
 PACK_TYPE='SMLF',
 LOCATION='U34',
 CDS_LIB='pure_quanta',
 CDS_PART_NAME='SN74LVC1G07DBVR_SMLF-SN74LVC1G07DBVR,IC,AL1G0007024',
 PART_NUMBER='AL1G0007024',
 VALUE='SN74LVC1G07DBVR',
 PRIM_FILE='./archive_libs/logical/sn74lvc1g07dbvr/chips/chips.prt';

PART_NAME
 U35 '74LVC1G08W57-74LVC1G08W5-7,SMLF,IC,AL1G0008020':;

SECTION_NUMBER 1
 '@T6G_MB_LIB.T6G(SCH_1):PAGE257_I63@PURE_QUANTA.74LVC1G08W57(CHIPS)':
 C_PATH='@t6g_mb_lib.t6g(sch_1):page257_i63@pure_quanta.\74lvc1g08w57\(chips)',
 P_PATH='@t6g_mb_lib.t6g(sch_1):page142_i63@pure_quanta.\74lvc1g08w57\(chips)',
 PATH='I63',
 DRAWING='@T6G_MB_LIB.T6G(SCH_1):PAGE257',
 PART_TYPE='SMLF',
 MATERIAL='IC',
 PHYS_PAGE='142',
 XY='(300,725)',
 ROT='0',
 VER='1',
 LOCATION='U35',
 CDS_LIB='pure_quanta',
 CDS_PART_NAME='74LVC1G08W57-74LVC1G08W5-7,SMLF,IC,AL1G0008020',
 PART_NUMBER='AL1G0008020',
 VALUE='74LVC1G08W5-7',
 PRIM_FILE='./archive_libs/logical/74lvc1g08w57/chips/chips.prt';

PART_NAME
 U36 'TCA9548APWR-TCA9548APWR,SMLF,IC,AL009548K02':;

SECTION_NUMBER 1
 '@T6G_MB_LIB.T6G(SCH_1):PAGE252_I33@PURE_QUANTA.TCA9548APWR(CHIPS)':
 C_PATH='@t6g_mb_lib.t6g(sch_1):page252_i33@pure_quanta.tca9548apwr(chips)',
 P_PATH='@t6g_mb_lib.t6g(sch_1):page250_i33@pure_quanta.tca9548apwr(chips)',
 PATH='I33',
 DRAWING='@T6G_MB_LIB.T6G(SCH_1):PAGE252',
 SEC_TYPE='',
 PART_TYPE='SMLF',
 MATERIAL='IC',
 PHYS_PAGE='250',
 XY='(-3925,4550)',
 ROT='0',
 VER='1',
 LOCATION='U36',
 SEC='1',
 CDS_LIB='pure_quanta',
 CDS_PART_NAME='TCA9548APWR-TCA9548APWR,SMLF,IC,AL009548K02',
 PART_NUMBER='AL009548K02',
 VALUE='TCA9548APWR',
 PRIM_FILE='./archive_libs/logical/tca9548apwr/chips/chips.prt';

PART_NAME
 U37 '74LVC1G32GW_SMLF-74LVC1G32GW,IC,ALVC1G32007':;

SECTION_NUMBER 1
 '@T6G_MB_LIB.T6G(SCH_1):PAGE257_I40@PURE_QUANTA.74LVC1G32GW(CHIPS)':
 C_PATH='@t6g_mb_lib.t6g(sch_1):page257_i40@pure_quanta.\74lvc1g32gw\(chips)',
 P_PATH='@t6g_mb_lib.t6g(sch_1):page142_i40@pure_quanta.\74lvc1g32gw\(chips)',
 PATH='I40',
 DRAWING='@T6G_MB_LIB.T6G(SCH_1):PAGE257',
 MATERIAL='IC',
 PHYS_PAGE='142',
 XY='(225,-500)',
 ROT='0',
 VER='1',
 PACK_TYPE='SMLF',
 LOCATION='U37',
 CDS_LIB='pure_quanta',
 CDS_PART_NAME='74LVC1G32GW_SMLF-74LVC1G32GW,IC,ALVC1G32007',
 PART_NUMBER='ALVC1G32007',
 VALUE='74LVC1G32GW',
 PRIM_FILE='./archive_libs/logical/74lvc1g32gw/chips/chips.prt';

PART_NAME
 U38 'SN74LVC1G11DCKR-SN74LVC1G11DCKR,SMLF,IC,ALLVC1G1000':;

SECTION_NUMBER 1
 '@T6G_MB_LIB.T6G(SCH_1):PAGE264_I8@PURE_QUANTA.SN74LVC1G11DCKR(CHIPS)':
 C_PATH='@t6g_mb_lib.t6g(sch_1):page264_i8@pure_quanta.sn74lvc1g11dckr(chips)',
 P_PATH='@t6g_mb_lib.t6g(sch_1):page259_i8@pure_quanta.sn74lvc1g11dckr(chips)',
 PATH='I8',
 DRAWING='@T6G_MB_LIB.T6G(SCH_1):PAGE264',
 PART_TYPE='SMLF',
 MATERIAL='IC',
 PHYS_PAGE='259',
 XY='(-4500,2025)',
 ROT='0',
 VER='1',
 LOCATION='U38',
 CDS_LIB='pure_quanta',
 CDS_PART_NAME='SN74LVC1G11DCKR-SN74LVC1G11DCKR,SMLF,IC,ALLVC1G1000',
 PART_NUMBER='ALLVC1G1000',
 VALUE='SN74LVC1G11DCKR',
 PRIM_FILE='./archive_libs/logical/sn74lvc1g11dckr/chips/chips.prt';

PART_NAME
 U39 'TCA9548APWR-TCA9548APWR,SMLF,IC,AL009548K02':;

SECTION_NUMBER 1
 '@T6G_MB_LIB.T6G(SCH_1):PAGE251_I74@PURE_QUANTA.TCA9548APWR(CHIPS)':
 C_PATH='@t6g_mb_lib.t6g(sch_1):page251_i74@pure_quanta.tca9548apwr(chips)',
 P_PATH='@t6g_mb_lib.t6g(sch_1):page252_i74@pure_quanta.tca9548apwr(chips)',
 PATH='I74',
 DRAWING='@T6G_MB_LIB.T6G(SCH_1):PAGE251',
 SEC_TYPE='',
 PART_TYPE='SMLF',
 MATERIAL='IC',
 PHYS_PAGE='252',
 XY='(-4275,4275)',
 ROT='0',
 VER='1',
 LOCATION='U39',
 SEC='1',
 CDS_LIB='pure_quanta',
 CDS_PART_NAME='TCA9548APWR-TCA9548APWR,SMLF,IC,AL009548K02',
 PART_NUMBER='AL009548K02',
 VALUE='TCA9548APWR',
 PRIM_FILE='./archive_libs/logical/tca9548apwr/chips/chips.prt';

PART_NAME
 U40 'SN74LVC2G07DCKR_SMLF-SN74LVC2G07DCKR,IC,AL002G07006':;

SECTION_NUMBER 1
 '@T6G_MB_LIB.T6G(SCH_1):PAGE77_I21@PURE_QUANTA.SN74LVC2G07DCKR(CHIPS)':
 C_PATH='@t6g_mb_lib.t6g(sch_1):page77_i21@pure_quanta.sn74lvc2g07dckr(chips)',
 P_PATH='@t6g_mb_lib.t6g(sch_1):page78_i21@pure_quanta.sn74lvc2g07dckr(chips)',
 PATH='I21',
 DRAWING='@T6G_MB_LIB.T6G(SCH_1):PAGE77',
 MATERIAL='IC',
 PHYS_PAGE='78',
 XY='(-4625,2500)',
 ROT='0',
 VER='1',
 PACK_TYPE='SMLF',
 LOCATION='U40',
 CDS_LIB='pure_quanta',
 CDS_PART_NAME='SN74LVC2G07DCKR_SMLF-SN74LVC2G07DCKR,IC,AL002G07006',
 PART_NUMBER='AL002G07006',
 VALUE='SN74LVC2G07DCKR',
 PRIM_FILE='./archive_libs/logical/sn74lvc2g07dckr/chips/chips.prt';

PART_NAME
 U41 'PI3CSW12ZUAEX-PI3CSW12ZUAEX,SMLF,IC,AL3CSW12000':;

SECTION_NUMBER 1
 '@T6G_MB_LIB.T6G(SCH_1):PAGE376_I46@PURE_QUANTA.PI3CSW12ZUAEX(CHIPS)':
 C_PATH='@t6g_mb_lib.t6g(sch_1):page376_i46@pure_quanta.pi3csw12zuaex(chips)',
 P_PATH='@t6g_mb_lib.t6g(sch_1):page186_i46@pure_quanta.pi3csw12zuaex(chips)',
 PATH='I46',
 DRAWING='@T6G_MB_LIB.T6G(SCH_1):PAGE376',
 PART_TYPE='SMLF',
 MATERIAL='IC',
 PHYS_PAGE='186',
 XY='(-6275,2725)',
 ROT='0',
 VER='1',
 LOCATION='U41',
 CDS_LIB='pure_quanta',
 CDS_PART_NAME='PI3CSW12ZUAEX-PI3CSW12ZUAEX,SMLF,IC,AL3CSW12000',
 PART_NUMBER='AL3CSW12000',
 VALUE='PI3CSW12ZUAEX',
 PRIM_FILE='./archive_libs/logical/pi3csw12zuaex/chips/chips.prt';

PART_NAME
 U42 'PI3CSW12ZUAEX-PI3CSW12ZUAEX,SMLF,IC,AL3CSW12000':;

SECTION_NUMBER 1
 '@T6G_MB_LIB.T6G(SCH_1):PAGE376_I31@PURE_QUANTA.PI3CSW12ZUAEX(CHIPS)':
 C_PATH='@t6g_mb_lib.t6g(sch_1):page376_i31@pure_quanta.pi3csw12zuaex(chips)',
 P_PATH='@t6g_mb_lib.t6g(sch_1):page186_i31@pure_quanta.pi3csw12zuaex(chips)',
 PATH='I31',
 DRAWING='@T6G_MB_LIB.T6G(SCH_1):PAGE376',
 PART_TYPE='SMLF',
 MATERIAL='IC',
 PHYS_PAGE='186',
 XY='(-6225,4200)',
 ROT='0',
 VER='1',
 LOCATION='U42',
 CDS_LIB='pure_quanta',
 CDS_PART_NAME='PI3CSW12ZUAEX-PI3CSW12ZUAEX,SMLF,IC,AL3CSW12000',
 PART_NUMBER='AL3CSW12000',
 VALUE='PI3CSW12ZUAEX',
 PRIM_FILE='./archive_libs/logical/pi3csw12zuaex/chips/chips.prt';

PART_NAME
 U43 'PI3CSW12ZUAEX-PI3CSW12ZUAEX,SMLF,IC,AL3CSW12000':;

SECTION_NUMBER 1
 '@T6G_MB_LIB.T6G(SCH_1):PAGE376_I61@PURE_QUANTA.PI3CSW12ZUAEX(CHIPS)':
 C_PATH='@t6g_mb_lib.t6g(sch_1):page376_i61@pure_quanta.pi3csw12zuaex(chips)',
 P_PATH='@t6g_mb_lib.t6g(sch_1):page186_i61@pure_quanta.pi3csw12zuaex(chips)',
 PATH='I61',
 DRAWING='@T6G_MB_LIB.T6G(SCH_1):PAGE376',
 PART_TYPE='SMLF',
 MATERIAL='IC',
 PHYS_PAGE='186',
 XY='(-6225,1125)',
 ROT='0',
 VER='1',
 LOCATION='U43',
 CDS_LIB='pure_quanta',
 CDS_PART_NAME='PI3CSW12ZUAEX-PI3CSW12ZUAEX,SMLF,IC,AL3CSW12000',
 PART_NUMBER='AL3CSW12000',
 VALUE='PI3CSW12ZUAEX',
 PRIM_FILE='./archive_libs/logical/pi3csw12zuaex/chips/chips.prt';

PART_NAME
 U44 '74LVC1G17GW-74LVC1G17GW,SMLF,IC,AL1G0017K01':;

SECTION_NUMBER 1
 '@T6G_MB_LIB.T6G(SCH_1):PAGE297_I97@PURE_QUANTA.74LVC1G17GW(CHIPS)':
 C_PATH='@t6g_mb_lib.t6g(sch_1):page297_i97@pure_quanta.\74lvc1g17gw\(chips)',
 P_PATH='@t6g_mb_lib.t6g(sch_1):page145_i97@pure_quanta.\74lvc1g17gw\(chips)',
 PATH='I97',
 DRAWING='@T6G_MB_LIB.T6G(SCH_1):PAGE297',
 PIN_NAMES_ROTATE='True',
 PART_TYPE='SMLF',
 MATERIAL='IC',
 PHYS_PAGE='145',
 XY='(-1925,400)',
 ROT='0',
 VER='1',
 LOCATION='U44',
 CDS_LIB='pure_quanta',
 CDS_PART_NAME='74LVC1G17GW-74LVC1G17GW,SMLF,IC,AL1G0017K01',
 PART_NUMBER='AL1G0017K01',
 VALUE='74LVC1G17GW',
 PRIM_FILE='./archive_libs/logical/74lvc1g17gw/chips/chips.prt';

PART_NAME
 U45 'PI3CSW12ZUAEX-PI3CSW12ZUAEX,SMLF,IC,AL3CSW12000':;

SECTION_NUMBER 1
 '@T6G_MB_LIB.T6G(SCH_1):PAGE376_I22@PURE_QUANTA.PI3CSW12ZUAEX(CHIPS)':
 C_PATH='@t6g_mb_lib.t6g(sch_1):page376_i22@pure_quanta.pi3csw12zuaex(chips)',
 P_PATH='@t6g_mb_lib.t6g(sch_1):page186_i22@pure_quanta.pi3csw12zuaex(chips)',
 PATH='I22',
 DRAWING='@T6G_MB_LIB.T6G(SCH_1):PAGE376',
 PART_TYPE='SMLF',
 MATERIAL='IC',
 PHYS_PAGE='186',
 XY='(-6150,5625)',
 ROT='0',
 VER='1',
 LOCATION='U45',
 CDS_LIB='pure_quanta',
 CDS_PART_NAME='PI3CSW12ZUAEX-PI3CSW12ZUAEX,SMLF,IC,AL3CSW12000',
 PART_NUMBER='AL3CSW12000',
 VALUE='PI3CSW12ZUAEX',
 PRIM_FILE='./archive_libs/logical/pi3csw12zuaex/chips/chips.prt';

PART_NAME
 U46 'PI3CSW12ZUAEX-PI3CSW12ZUAEX,SMLF,IC,AL3CSW12000':;

SECTION_NUMBER 1
 '@T6G_MB_LIB.T6G(SCH_1):PAGE376_I108@PURE_QUANTA.PI3CSW12ZUAEX(CHIPS)':
 C_PATH='@t6g_mb_lib.t6g(sch_1):page376_i108@pure_quanta.pi3csw12zuaex(chips)',
 P_PATH='@t6g_mb_lib.t6g(sch_1):page186_i108@pure_quanta.pi3csw12zuaex(chips)',
 PATH='I108',
 DRAWING='@T6G_MB_LIB.T6G(SCH_1):PAGE376',
 PART_TYPE='SMLF',
 MATERIAL='IC',
 PHYS_PAGE='186',
 XY='(-1900,2100)',
 ROT='0',
 VER='1',
 LOCATION='U46',
 CDS_LIB='pure_quanta',
 CDS_PART_NAME='PI3CSW12ZUAEX-PI3CSW12ZUAEX,SMLF,IC,AL3CSW12000',
 PART_NUMBER='AL3CSW12000',
 VALUE='PI3CSW12ZUAEX',
 PRIM_FILE='./archive_libs/logical/pi3csw12zuaex/chips/chips.prt';

PART_NAME
 U47 'PI3CSW12ZUAEX-PI3CSW12ZUAEX,SMLF,IC,AL3CSW12000':;

SECTION_NUMBER 1
 '@T6G_MB_LIB.T6G(SCH_1):PAGE376_I121@PURE_QUANTA.PI3CSW12ZUAEX(CHIPS)':
 C_PATH='@t6g_mb_lib.t6g(sch_1):page376_i121@pure_quanta.pi3csw12zuaex(chips)',
 P_PATH='@t6g_mb_lib.t6g(sch_1):page186_i121@pure_quanta.pi3csw12zuaex(chips)',
 PATH='I121',
 DRAWING='@T6G_MB_LIB.T6G(SCH_1):PAGE376',
 PART_TYPE='SMLF',
 MATERIAL='IC',
 PHYS_PAGE='186',
 XY='(-1875,675)',
 ROT='0',
 VER='1',
 LOCATION='U47',
 CDS_LIB='pure_quanta',
 CDS_PART_NAME='PI3CSW12ZUAEX-PI3CSW12ZUAEX,SMLF,IC,AL3CSW12000',
 PART_NUMBER='AL3CSW12000',
 VALUE='PI3CSW12ZUAEX',
 PRIM_FILE='./archive_libs/logical/pi3csw12zuaex/chips/chips.prt';

PART_NAME
 U48 'PI3CSW12ZUAEX-PI3CSW12ZUAEX,SMLF,IC,AL3CSW12000':;

SECTION_NUMBER 1
 '@T6G_MB_LIB.T6G(SCH_1):PAGE376_I76@PURE_QUANTA.PI3CSW12ZUAEX(CHIPS)':
 C_PATH='@t6g_mb_lib.t6g(sch_1):page376_i76@pure_quanta.pi3csw12zuaex(chips)',
 P_PATH='@t6g_mb_lib.t6g(sch_1):page186_i76@pure_quanta.pi3csw12zuaex(chips)',
 PATH='I76',
 DRAWING='@T6G_MB_LIB.T6G(SCH_1):PAGE376',
 PART_TYPE='SMLF',
 MATERIAL='IC',
 PHYS_PAGE='186',
 XY='(-1850,3575)',
 ROT='0',
 VER='1',
 LOCATION='U48',
 CDS_LIB='pure_quanta',
 CDS_PART_NAME='PI3CSW12ZUAEX-PI3CSW12ZUAEX,SMLF,IC,AL3CSW12000',
 PART_NUMBER='AL3CSW12000',
 VALUE='PI3CSW12ZUAEX',
 PRIM_FILE='./archive_libs/logical/pi3csw12zuaex/chips/chips.prt';

PART_NAME
 U49 'PI3CSW12ZUAEX-PI3CSW12ZUAEX,SMLF,IC,AL3CSW12000':;

SECTION_NUMBER 1
 '@T6G_MB_LIB.T6G(SCH_1):PAGE376_I85@PURE_QUANTA.PI3CSW12ZUAEX(CHIPS)':
 C_PATH='@t6g_mb_lib.t6g(sch_1):page376_i85@pure_quanta.pi3csw12zuaex(chips)',
 P_PATH='@t6g_mb_lib.t6g(sch_1):page186_i85@pure_quanta.pi3csw12zuaex(chips)',
 PATH='I85',
 DRAWING='@T6G_MB_LIB.T6G(SCH_1):PAGE376',
 PART_TYPE='SMLF',
 MATERIAL='IC',
 PHYS_PAGE='186',
 XY='(-1775,5100)',
 ROT='0',
 VER='1',
 LOCATION='U49',
 CDS_LIB='pure_quanta',
 CDS_PART_NAME='PI3CSW12ZUAEX-PI3CSW12ZUAEX,SMLF,IC,AL3CSW12000',
 PART_NUMBER='AL3CSW12000',
 VALUE='PI3CSW12ZUAEX',
 PRIM_FILE='./archive_libs/logical/pi3csw12zuaex/chips/chips.prt';

PART_NAME
 U50 'MAX11617EEET-MAX11617EEE+T,SMLF,EMPTY,AL011617W00':
 ROOM='ADC_MAM_BOM2';

SECTION_NUMBER 1
 '@T6G_MB_LIB.T6G(SCH_1):PAGE263_I156@PURE_QUANTA.MAX11617EEET(CHIPS)':
 C_PATH='@t6g_mb_lib.t6g(sch_1):page263_i156@pure_quanta.max11617eeet(chips)',
 P_PATH='@t6g_mb_lib.t6g(sch_1):page258_i156@pure_quanta.max11617eeet(chips)',
 PATH='I156',
 DRAWING='@T6G_MB_LIB.T6G(SCH_1):PAGE263',
 SEC_TYPE='',
 PART_TYPE='SMLF',
 MATERIAL='EMPTY',
 PHYS_PAGE='258',
 XY='(-2375,4750)',
 ROT='0',
 VER='1',
 LOCATION='U50',
 SEC='1',
 CDS_LIB='pure_quanta',
 CDS_PART_NAME='MAX11617EEET-MAX11617EEE+T,SMLF,EMPTY,AL011617W00',
 ROOM='ADC_MAM_BOM2',
 PART_NUMBER='AL011617W00',
 VALUE='MAX11617EEE+T',
 PRIM_FILE='./archive_libs/logical/max11617eeet/chips/chips.prt';

PART_NAME
 U51 'ADC128D818CIMTXNOPB-ADC128D818CIMTX/NOPB,SMLF,IC,AA':
 ROOM='ADC_TI_BOM1';

SECTION_NUMBER 1
 '@T6G_MB_LIB.T6G(SCH_1):PAGE263_I142@PURE_QUANTA.ADC128D818CIMTXNOPB(CHIPS)':
 C_PATH='@t6g_mb_lib.t6g(sch_1):page263_i142@pure_quanta.adc128d818cimtxnopb(chi~
ps)',
 P_PATH='@t6g_mb_lib.t6g(sch_1):page258_i142@pure_quanta.adc128d818cimtxnopb(chi~
ps)',
 PATH='I142',
 DRAWING='@T6G_MB_LIB.T6G(SCH_1):PAGE263',
 PIN_NAMES_ROTATE='True',
 PART_TYPE='SMLF',
 MATERIAL='IC',
 PHYS_PAGE='258',
 XY='(-1575,1950)',
 ROT='0',
 VER='1',
 LOCATION='U51',
 CDS_LIB='pure_quanta',
 CDS_PART_NAME='ADC128D818CIMTXNOPB-ADC128D818CIMTX/NOPB,SMLF,IC,AA',
 ROOM='ADC_TI_BOM1',
 PART_NUMBER='AL000128K00',
 VALUE='ADC128D818CIMTX/NOPB',
 PRIM_FILE='./archive_libs/logical/adc128d818cimtxnopb/chips/chips.prt';

PART_NAME
 U52 'ISL28022FRZT-ISL28022FRZ-T,SMLF,IC,AL028022003':;

SECTION_NUMBER 1
 '@T6G_MB_LIB.T6G(SCH_1):PAGE466_I57@PURE_QUANTA.ISL28022FRZT(CHIPS)':
 C_PATH='@t6g_mb_lib.t6g(sch_1):page466_i57@pure_quanta.isl28022frzt(chips)',
 P_PATH='@t6g_mb_lib.t6g(sch_1):page357_i57@pure_quanta.isl28022frzt(chips)',
 PATH='I57',
 DRAWING='@T6G_MB_LIB.T6G(SCH_1):PAGE466',
 SEC_TYPE='',
 PART_TYPE='SMLF',
 MATERIAL='IC',
 PHYS_PAGE='357',
 XY='(-4750,1150)',
 ROT='0',
 VER='1',
 LOCATION='U52',
 SEC='1',
 CDS_LIB='pure_quanta',
 CDS_PART_NAME='ISL28022FRZT-ISL28022FRZ-T,SMLF,IC,AL028022003',
 PART_NUMBER='AL028022003',
 VALUE='ISL28022FRZ-T',
 PRIM_FILE='./archive_libs/logical/isl28022frzt/chips/chips.prt';

PART_NAME
 U53 'SN74AVC4T774PWR-SN74AVC4T774PWR,SMLF,IC,AL04T774K00':;

SECTION_NUMBER 1
 '@T6G_MB_LIB.T6G(SCH_1):PAGE76_I63@PURE_QUANTA.SN74AVC4T774PWR(CHIPS)':
 C_PATH='@t6g_mb_lib.t6g(sch_1):page76_i63@pure_quanta.sn74avc4t774pwr(chips)',
 P_PATH='@t6g_mb_lib.t6g(sch_1):page77_i63@pure_quanta.sn74avc4t774pwr(chips)',
 PATH='I63',
 DRAWING='@T6G_MB_LIB.T6G(SCH_1):PAGE76',
 PART_TYPE='SMLF',
 MATERIAL='IC',
 PHYS_PAGE='77',
 XY='(-5425,4175)',
 ROT='0',
 VER='1',
 LOCATION='U53',
 CDS_LIB='pure_quanta',
 CDS_PART_NAME='SN74AVC4T774PWR-SN74AVC4T774PWR,SMLF,IC,AL04T774K00',
 PART_NUMBER='AL04T774K00',
 VALUE='SN74AVC4T774PWR',
 PRIM_FILE='./archive_libs/logical/sn74avc4t774pwr/chips/chips.prt';

PART_NAME
 U54 'PI4ULS3V304AZMAEX-PI4ULS3V304AZMAEX,SMLF,IC,AL0003A':;

SECTION_NUMBER 1
 '@T6G_MB_LIB.T6G(SCH_1):PAGE76_I67@PURE_QUANTA.PI4ULS3V304AZMAEX(CHIPS)':
 C_PATH='@t6g_mb_lib.t6g(sch_1):page76_i67@pure_quanta.pi4uls3v304azmaex(chips)',
 P_PATH='@t6g_mb_lib.t6g(sch_1):page77_i67@pure_quanta.pi4uls3v304azmaex(chips)',
 PATH='I67',
 DRAWING='@T6G_MB_LIB.T6G(SCH_1):PAGE76',
 PART_TYPE='SMLF',
 MATERIAL='IC',
 PHYS_PAGE='77',
 XY='(-5550,2275)',
 ROT='0',
 VER='1',
 LOCATION='U54',
 CDS_LIB='pure_quanta',
 CDS_PART_NAME='PI4ULS3V304AZMAEX-PI4ULS3V304AZMAEX,SMLF,IC,AL0003A',
 PART_NUMBER='AL000304005',
 VALUE='PI4ULS3V304AZMAEX',
 PRIM_FILE='./archive_libs/logical/pi4uls3v304azmaex/chips/chips.prt';

PART_NAME
 U55 'ISL28022FRZT-ISL28022FRZ-T,SMLF,IC,AL028022003':;

SECTION_NUMBER 1
 '@T6G_MB_LIB.T6G(SCH_1):PAGE466_I28@PURE_QUANTA.ISL28022FRZT(CHIPS)':
 C_PATH='@t6g_mb_lib.t6g(sch_1):page466_i28@pure_quanta.isl28022frzt(chips)',
 P_PATH='@t6g_mb_lib.t6g(sch_1):page357_i28@pure_quanta.isl28022frzt(chips)',
 PATH='I28',
 DRAWING='@T6G_MB_LIB.T6G(SCH_1):PAGE466',
 SEC_TYPE='',
 PART_TYPE='SMLF',
 MATERIAL='IC',
 PHYS_PAGE='357',
 XY='(-4200,5475)',
 ROT='0',
 VER='1',
 LOCATION='U55',
 SEC='1',
 CDS_LIB='pure_quanta',
 CDS_PART_NAME='ISL28022FRZT-ISL28022FRZ-T,SMLF,IC,AL028022003',
 PART_NUMBER='AL028022003',
 VALUE='ISL28022FRZ-T',
 PRIM_FILE='./archive_libs/logical/isl28022frzt/chips/chips.prt';

PART_NAME
 U56 'ISL28022FRZT-ISL28022FRZ-T,SMLF,IC,AL028022003':;

SECTION_NUMBER 1
 '@T6G_MB_LIB.T6G(SCH_1):PAGE466_I29@PURE_QUANTA.ISL28022FRZT(CHIPS)':
 C_PATH='@t6g_mb_lib.t6g(sch_1):page466_i29@pure_quanta.isl28022frzt(chips)',
 P_PATH='@t6g_mb_lib.t6g(sch_1):page357_i29@pure_quanta.isl28022frzt(chips)',
 PATH='I29',
 DRAWING='@T6G_MB_LIB.T6G(SCH_1):PAGE466',
 SEC_TYPE='',
 PART_TYPE='SMLF',
 MATERIAL='IC',
 PHYS_PAGE='357',
 XY='(-3550,3425)',
 ROT='0',
 VER='1',
 LOCATION='U56',
 SEC='1',
 CDS_LIB='pure_quanta',
 CDS_PART_NAME='ISL28022FRZT-ISL28022FRZ-T,SMLF,IC,AL028022003',
 PART_NUMBER='AL028022003',
 VALUE='ISL28022FRZ-T',
 PRIM_FILE='./archive_libs/logical/isl28022frzt/chips/chips.prt';

PART_NAME
 U57 'SCHOTTKY_DUAL_12A_3C-BAT54CW,SMLF,EMPTY,BCBAT54CZ13':;

SECTION_NUMBER 1
 '@T6G_MB_LIB.T6G(SCH_1):PAGE146_I5@PURE_QUANTA.SCHOTTKY_DUAL_12A_3C(CHIPS)':
 C_PATH='@t6g_mb_lib.t6g(sch_1):page146_i5@pure_quanta.schottky_dual_12a_3c(chip~
s)',
 P_PATH='@t6g_mb_lib.t6g(sch_1):page169_i5@pure_quanta.schottky_dual_12a_3c(chip~
s)',
 PATH='I5',
 DRAWING='@T6G_MB_LIB.T6G(SCH_1):PAGE146',
 SEC_TYPE='',
 PART_TYPE='SMLF',
 MATERIAL='EMPTY',
 PHYS_PAGE='169',
 XY='(-7375,4325)',
 ROT='5',
 VER='1',
 LOCATION='U57',
 SEC='1',
 CDS_LIB='pure_quanta',
 CDS_PART_NAME='SCHOTTKY_DUAL_12A_3C-BAT54CW,SMLF,EMPTY,BCBAT54CZ13',
 PART_NUMBER='BCBAT54CZ13',
 VALUE='BAT54CW',
 PRIM_FILE='./archive_libs/logical/schottky_dual_12a_3c/chips/chips.prt';

PART_NAME
 U58 '74LVC2G07DW7-74LVC2G07DW-7,SMLF,IC,AL002G07003':;

SECTION_NUMBER 1
 '@T6G_MB_LIB.T6G(SCH_1):PAGE343_I28@PURE_QUANTA.74LVC2G07DW7(CHIPS)':
 C_PATH='@t6g_mb_lib.t6g(sch_1):page343_i28@pure_quanta.\74lvc2g07dw7\(chips)',
 P_PATH='@t6g_mb_lib.t6g(sch_1):page140_i28@pure_quanta.\74lvc2g07dw7\(chips)',
 PATH='I28',
 DRAWING='@T6G_MB_LIB.T6G(SCH_1):PAGE343',
 PART_TYPE='SMLF',
 MATERIAL='IC',
 PHYS_PAGE='140',
 XY='(-1150,5075)',
 ROT='0',
 VER='1',
 LOCATION='U58',
 CDS_LIB='pure_quanta',
 CDS_PART_NAME='74LVC2G07DW7-74LVC2G07DW-7,SMLF,IC,AL002G07003',
 PART_NUMBER='AL002G07003',
 VALUE='74LVC2G07DW-7',
 PRIM_FILE='./archive_libs/logical/74lvc2g07dw7/chips/chips.prt';

PART_NAME
 U59 '74LVC2G07DW7-74LVC2G07DW-7,SMLF,IC,AL002G07003':;

SECTION_NUMBER 1
 '@T6G_MB_LIB.T6G(SCH_1):PAGE343_I22@PURE_QUANTA.74LVC2G07DW7(CHIPS)':
 C_PATH='@t6g_mb_lib.t6g(sch_1):page343_i22@pure_quanta.\74lvc2g07dw7\(chips)',
 P_PATH='@t6g_mb_lib.t6g(sch_1):page140_i22@pure_quanta.\74lvc2g07dw7\(chips)',
 PATH='I22',
 DRAWING='@T6G_MB_LIB.T6G(SCH_1):PAGE343',
 PART_TYPE='SMLF',
 MATERIAL='IC',
 PHYS_PAGE='140',
 XY='(-1150,4175)',
 ROT='0',
 VER='1',
 LOCATION='U59',
 CDS_LIB='pure_quanta',
 CDS_PART_NAME='74LVC2G07DW7-74LVC2G07DW-7,SMLF,IC,AL002G07003',
 PART_NUMBER='AL002G07003',
 VALUE='74LVC2G07DW-7',
 PRIM_FILE='./archive_libs/logical/74lvc2g07dw7/chips/chips.prt';

PART_NAME
 U60 'SCHOTTKY_DUAL_12A_3C-BAT54CW,SMLF,EMPTY,BCBAT54CZ13':;

SECTION_NUMBER 1
 '@T6G_MB_LIB.T6G(SCH_1):PAGE146_I25@PURE_QUANTA.SCHOTTKY_DUAL_12A_3C(CHIPS)':
 C_PATH='@t6g_mb_lib.t6g(sch_1):page146_i25@pure_quanta.schottky_dual_12a_3c(chi~
ps)',
 P_PATH='@t6g_mb_lib.t6g(sch_1):page169_i25@pure_quanta.schottky_dual_12a_3c(chi~
ps)',
 PATH='I25',
 DRAWING='@T6G_MB_LIB.T6G(SCH_1):PAGE146',
 PART_TYPE='SMLF',
 MATERIAL='EMPTY',
 PHYS_PAGE='169',
 XY='(-7250,1450)',
 ROT='5',
 VER='1',
 LOCATION='U60',
 CDS_LIB='pure_quanta',
 CDS_PART_NAME='SCHOTTKY_DUAL_12A_3C-BAT54CW,SMLF,EMPTY,BCBAT54CZ13',
 PART_NUMBER='BCBAT54CZ13',
 VALUE='BAT54CW',
 PRIM_FILE='./archive_libs/logical/schottky_dual_12a_3c/chips/chips.prt';

PART_NAME
 U64 'M24128BWMN6TP-M24128-BWMN6TP,SMLF,IC,AKE30Z00613':;

SECTION_NUMBER 1
 '@T6G_MB_LIB.T6G(SCH_1):PAGE361_I35@PURE_QUANTA.M24128BWMN6TP(CHIPS)':
 C_PATH='@t6g_mb_lib.t6g(sch_1):page361_i35@pure_quanta.m24128bwmn6tp(chips)',
 P_PATH='@t6g_mb_lib.t6g(sch_1):page238_i35@pure_quanta.m24128bwmn6tp(chips)',
 PATH='I35',
 DRAWING='@T6G_MB_LIB.T6G(SCH_1):PAGE361',
 PART_TYPE='SMLF',
 MATERIAL='IC',
 PHYS_PAGE='238',
 XY='(-250,3375)',
 ROT='0',
 VER='1',
 LOCATION='U64',
 CDS_LIB='pure_quanta',
 CDS_PART_NAME='M24128BWMN6TP-M24128-BWMN6TP,SMLF,IC,AKE30Z00613',
 PART_NUMBER='AKE30Z00613',
 VALUE='M24128-BWMN6TP',
 PRIM_FILE='./archive_libs/logical/m24128bwmn6tp/chips/chips.prt';

PART_NAME
 U66 '74LVC1G126SE7-74LVC1G126SE-7,SMLF,IC,AL1G0126009':;

SECTION_NUMBER 1
 '@T6G_MB_LIB.T6G(SCH_1):PAGE336_I157@PURE_QUANTA.74LVC1G126SE7(CHIPS)':
 C_PATH='@t6g_mb_lib.t6g(sch_1):page336_i157@pure_quanta.\74lvc1g126se7\(chips)',
 P_PATH='@t6g_mb_lib.t6g(sch_1):page132_i157@pure_quanta.\74lvc1g126se7\(chips)',
 PATH='I157',
 DRAWING='@T6G_MB_LIB.T6G(SCH_1):PAGE336',
 SEC_TYPE='',
 PART_TYPE='SMLF',
 MATERIAL='IC',
 PHYS_PAGE='132',
 XY='(-1650,4000)',
 ROT='0',
 VER='1',
 LOCATION='U66',
 SEC='1',
 CDS_LIB='pure_quanta',
 CDS_PART_NAME='74LVC1G126SE7-74LVC1G126SE-7,SMLF,IC,AL1G0126009',
 PART_NUMBER='AL1G0126009',
 VALUE='74LVC1G126SE-7',
 PRIM_FILE='./archive_libs/logical/74lvc1g126se7/chips/chips.prt';

PART_NAME
 U67 '74CBTLV3126PW-74CBTLV3126PW,SMLF,IC,AL003126K08':;

SECTION_NUMBER 1
 '@T6G_MB_LIB.T6G(SCH_1):PAGE336_I1@PURE_QUANTA.74CBTLV3126PW(CHIPS)':
 C_PATH='@t6g_mb_lib.t6g(sch_1):page336_i1@pure_quanta.\74cbtlv3126pw\(chips)',
 P_PATH='@t6g_mb_lib.t6g(sch_1):page132_i1@pure_quanta.\74cbtlv3126pw\(chips)',
 PATH='I1',
 DRAWING='@T6G_MB_LIB.T6G(SCH_1):PAGE336',
 PART_TYPE='SMLF',
 MATERIAL='IC',
 PHYS_PAGE='132',
 XY='(-225,6700)',
 ROT='2',
 VER='1',
 LOCATION='U67',
 CDS_LIB='pure_quanta',
 CDS_PART_NAME='74CBTLV3126PW-74CBTLV3126PW,SMLF,IC,AL003126K08',
 PART_NUMBER='AL003126K08',
 VALUE='74CBTLV3126PW',
 PRIM_FILE='./archive_libs/logical/74cbtlv3126pw/chips/chips.prt';

PART_NAME
 U75 '74LVC1G17GW-74LVC1G17GW,SMLF,IC,AL1G0017K01':;

SECTION_NUMBER 1
 '@T6G_MB_LIB.T6G(SCH_1):PAGE337_I64@PURE_QUANTA.74LVC1G17GW(CHIPS)':
 C_PATH='@t6g_mb_lib.t6g(sch_1):page337_i64@pure_quanta.\74lvc1g17gw\(chips)',
 P_PATH='@t6g_mb_lib.t6g(sch_1):page133_i64@pure_quanta.\74lvc1g17gw\(chips)',
 PATH='I64',
 DRAWING='@T6G_MB_LIB.T6G(SCH_1):PAGE337',
 SEC_TYPE='',
 PIN_NAMES_ROTATE='True',
 PART_TYPE='SMLF',
 MATERIAL='IC',
 PHYS_PAGE='133',
 XY='(-7975,7025)',
 ROT='0',
 VER='1',
 LOCATION='U75',
 SEC='1',
 CDS_LIB='pure_quanta',
 CDS_PART_NAME='74LVC1G17GW-74LVC1G17GW,SMLF,IC,AL1G0017K01',
 PART_NUMBER='AL1G0017K01',
 VALUE='74LVC1G17GW',
 PRIM_FILE='./archive_libs/logical/74lvc1g17gw/chips/chips.prt';

PART_NAME
 U82 'SN74LVC1G07DBVR_SMLF-SN74LVC1G07DBVR,IC,AL1G0007024':;

SECTION_NUMBER 1
 '@T6G_MB_LIB.T6G(SCH_1):PAGE143_I26@PURE_QUANTA.SN74LVC1G07DBVR(CHIPS)':
 C_PATH='@t6g_mb_lib.t6g(sch_1):page143_i26@pure_quanta.sn74lvc1g07dbvr(chips)',
 P_PATH='@t6g_mb_lib.t6g(sch_1):page166_i26@pure_quanta.sn74lvc1g07dbvr(chips)',
 PATH='I26',
 DRAWING='@T6G_MB_LIB.T6G(SCH_1):PAGE143',
 MATERIAL='IC',
 PHYS_PAGE='166',
 XY='(-6600,5125)',
 ROT='0',
 VER='1',
 PACK_TYPE='SMLF',
 LOCATION='U82',
 CDS_LIB='pure_quanta',
 CDS_PART_NAME='SN74LVC1G07DBVR_SMLF-SN74LVC1G07DBVR,IC,AL1G0007024',
 PART_NUMBER='AL1G0007024',
 VALUE='SN74LVC1G07DBVR',
 PRIM_FILE='./archive_libs/logical/sn74lvc1g07dbvr/chips/chips.prt';

PART_NAME
 U86 'SN74LVC1G07DBVR_SMLF-SN74LVC1G07DBVR,IC,AL1G0007024':;

SECTION_NUMBER 1
 '@T6G_MB_LIB.T6G(SCH_1):PAGE143_I31@PURE_QUANTA.SN74LVC1G07DBVR(CHIPS)':
 C_PATH='@t6g_mb_lib.t6g(sch_1):page143_i31@pure_quanta.sn74lvc1g07dbvr(chips)',
 P_PATH='@t6g_mb_lib.t6g(sch_1):page166_i31@pure_quanta.sn74lvc1g07dbvr(chips)',
 PATH='I31',
 DRAWING='@T6G_MB_LIB.T6G(SCH_1):PAGE143',
 MATERIAL='IC',
 PHYS_PAGE='166',
 XY='(-6750,3500)',
 ROT='0',
 VER='1',
 PACK_TYPE='SMLF',
 LOCATION='U86',
 CDS_LIB='pure_quanta',
 CDS_PART_NAME='SN74LVC1G07DBVR_SMLF-SN74LVC1G07DBVR,IC,AL1G0007024',
 PART_NUMBER='AL1G0007024',
 VALUE='SN74LVC1G07DBVR',
 PRIM_FILE='./archive_libs/logical/sn74lvc1g07dbvr/chips/chips.prt';

PART_NAME
 U90 'PI6CV304LE-PI6CV304LE,SMLF,IC,AL000304K01':;

SECTION_NUMBER 1
 '@T6G_MB_LIB.T6G(SCH_1):PAGE337_I16@PURE_QUANTA.PI6CV304LE(CHIPS)':
 C_PATH='@t6g_mb_lib.t6g(sch_1):page337_i16@pure_quanta.pi6cv304le(chips)',
 P_PATH='@t6g_mb_lib.t6g(sch_1):page133_i16@pure_quanta.pi6cv304le(chips)',
 PATH='I16',
 DRAWING='@T6G_MB_LIB.T6G(SCH_1):PAGE337',
 PART_TYPE='SMLF',
 MATERIAL='IC',
 PHYS_PAGE='133',
 XY='(-6975,2450)',
 ROT='0',
 VER='1',
 LOCATION='U90',
 CDS_LIB='pure_quanta',
 CDS_PART_NAME='PI6CV304LE-PI6CV304LE,SMLF,IC,AL000304K01',
 PART_NUMBER='AL000304K01',
 VALUE='PI6CV304LE',
 PRIM_FILE='./archive_libs/logical/pi6cv304le/chips/chips.prt';

PART_NAME
 U92 'SN74LVC1G07DBVR_SMLF-SN74LVC1G07DBVR,IC,AL1G0007024':;

SECTION_NUMBER 1
 '@T6G_MB_LIB.T6G(SCH_1):PAGE83_I26@PURE_QUANTA.SN74LVC1G07DBVR(CHIPS)':
 C_PATH='@t6g_mb_lib.t6g(sch_1):page83_i26@pure_quanta.sn74lvc1g07dbvr(chips)',
 P_PATH='@t6g_mb_lib.t6g(sch_1):page84_i26@pure_quanta.sn74lvc1g07dbvr(chips)',
 PATH='I26',
 DRAWING='@T6G_MB_LIB.T6G(SCH_1):PAGE83',
 MATERIAL='IC',
 PHYS_PAGE='84',
 XY='(-2250,5525)',
 ROT='0',
 VER='1',
 PACK_TYPE='SMLF',
 LOCATION='U92',
 CDS_LIB='pure_quanta',
 CDS_PART_NAME='SN74LVC1G07DBVR_SMLF-SN74LVC1G07DBVR,IC,AL1G0007024',
 PART_NUMBER='AL1G0007024',
 VALUE='SN74LVC1G07DBVR',
 PRIM_FILE='./archive_libs/logical/sn74lvc1g07dbvr/chips/chips.prt';

PART_NAME
 U96 'PCA9617ADP-PCA9617ADP,SMLF,IC,AL009617K02':;

SECTION_NUMBER 1
 '@T6G_MB_LIB.T6G(SCH_1):PAGE137_I51@PURE_QUANTA.PCA9617ADP(CHIPS)':
 C_PATH='@t6g_mb_lib.t6g(sch_1):page137_i51@pure_quanta.pca9617adp(chips)',
 P_PATH='@t6g_mb_lib.t6g(sch_1):page160_i51@pure_quanta.pca9617adp(chips)',
 PATH='I51',
 DRAWING='@T6G_MB_LIB.T6G(SCH_1):PAGE137',
 SEC_TYPE='',
 PART_TYPE='SMLF',
 MATERIAL='IC',
 PHYS_PAGE='160',
 XY='(-5775,-1625)',
 ROT='2',
 VER='1',
 LOCATION='U96',
 SEC='1',
 CDS_LIB='pure_quanta',
 CDS_PART_NAME='PCA9617ADP-PCA9617ADP,SMLF,IC,AL009617K02',
 PART_NUMBER='AL009617K02',
 VALUE='PCA9617ADP',
 PRIM_FILE='./archive_libs/logical/pca9617adp/chips/chips.prt';

PART_NAME
 U98 'PCA9306DP1-PCA9306DP1,SMLF,IC,AL009306K04':;

SECTION_NUMBER 1
 '@T6G_MB_LIB.T6G(SCH_1):PAGE346_I27@PURE_QUANTA.PCA9306DP1(CHIPS)':
 C_PATH='@t6g_mb_lib.t6g(sch_1):page346_i27@pure_quanta.pca9306dp1(chips)',
 P_PATH='@t6g_mb_lib.t6g(sch_1):page148_i27@pure_quanta.pca9306dp1(chips)',
 PATH='I27',
 DRAWING='@T6G_MB_LIB.T6G(SCH_1):PAGE346',
 PART_TYPE='SMLF',
 MATERIAL='IC',
 PHYS_PAGE='148',
 XY='(725,3400)',
 ROT='2',
 VER='1',
 LOCATION='U98',
 CDS_LIB='pure_quanta',
 CDS_PART_NAME='PCA9306DP1-PCA9306DP1,SMLF,IC,AL009306K04',
 PART_NUMBER='AL009306K04',
 VALUE='PCA9306DP1',
 PRIM_FILE='./archive_libs/logical/pca9306dp1/chips/chips.prt';

PART_NAME
 U99 'SN74LVC1G07DBVR_SMLF-SN74LVC1G07DBVR,EMPTY,AL1G000A':;

SECTION_NUMBER 1
 '@T6G_MB_LIB.T6G(SCH_1):PAGE148_I340@PURE_QUANTA.SN74LVC1G07DBVR(CHIPS)':
 C_PATH='@t6g_mb_lib.t6g(sch_1):page148_i340@pure_quanta.sn74lvc1g07dbvr(chips)',
 P_PATH='@t6g_mb_lib.t6g(sch_1):page171_i340@pure_quanta.sn74lvc1g07dbvr(chips)',
 PATH='I340',
 DRAWING='@T6G_MB_LIB.T6G(SCH_1):PAGE148',
 MATERIAL='EMPTY',
 PHYS_PAGE='171',
 XY='(-7400,5225)',
 ROT='0',
 VER='1',
 PACK_TYPE='SMLF',
 LOCATION='U99',
 CDS_LIB='pure_quanta',
 CDS_PART_NAME='SN74LVC1G07DBVR_SMLF-SN74LVC1G07DBVR,EMPTY,AL1G000A',
 PART_NUMBER='AL1G0007024',
 VALUE='SN74LVC1G07DBVR',
 PRIM_FILE='./archive_libs/logical/sn74lvc1g07dbvr/chips/chips.prt';

PART_NAME
 U100 'RT9818C44GV-RT9818C-44GV,SMLF,IC,AL009818001':;

SECTION_NUMBER 1
 '@T6G_MB_LIB.T6G(SCH_1):PAGE273_I77@PURE_QUANTA.RT9818C44GV(CHIPS)':
 C_PATH='@t6g_mb_lib.t6g(sch_1):page273_i77@pure_quanta.rt9818c44gv(chips)',
 P_PATH='@t6g_mb_lib.t6g(sch_1):page188_i77@pure_quanta.rt9818c44gv(chips)',
 PATH='I77',
 DRAWING='@T6G_MB_LIB.T6G(SCH_1):PAGE273',
 SEC_TYPE='',
 PIN_NAMES_ROTATE='True',
 PART_TYPE='SMLF',
 MATERIAL='IC',
 PHYS_PAGE='188',
 XY='(-3750,3875)',
 ROT='2',
 VER='1',
 LOCATION='U100',
 SEC='1',
 CDS_LIB='pure_quanta',
 CDS_PART_NAME='RT9818C44GV-RT9818C-44GV,SMLF,IC,AL009818001',
 PART_NUMBER='AL009818001',
 VALUE='RT9818C-44GV',
 PRIM_FILE='./archive_libs/logical/rt9818c44gv/chips/chips.prt';

PART_NAME
 U101 'SN74LVC1G07DBVR_SMLF-SN74LVC1G07DBVR,IC,AL1G0007024':;

SECTION_NUMBER 1
 '@T6G_MB_LIB.T6G(SCH_1):PAGE34_I55@PURE_QUANTA.SN74LVC1G07DBVR(CHIPS)':
 C_PATH='@t6g_mb_lib.t6g(sch_1):page34_i55@pure_quanta.sn74lvc1g07dbvr(chips)',
 P_PATH='@t6g_mb_lib.t6g(sch_1):page34_i55@pure_quanta.sn74lvc1g07dbvr(chips)',
 PATH='I55',
 DRAWING='@T6G_MB_LIB.T6G(SCH_1):PAGE34',
 MATERIAL='IC',
 PHYS_PAGE='34',
 XY='(-6350,2725)',
 ROT='0',
 VER='1',
 PACK_TYPE='SMLF',
 LOCATION='U101',
 CDS_LIB='pure_quanta',
 CDS_PART_NAME='SN74LVC1G07DBVR_SMLF-SN74LVC1G07DBVR,IC,AL1G0007024',
 PART_NUMBER='AL1G0007024',
 VALUE='SN74LVC1G07DBVR',
 PRIM_FILE='./archive_libs/logical/sn74lvc1g07dbvr/chips/chips.prt';

PART_NAME
 U104 '74LVC1G07GV-74LVC1G07GV,SMLF,IC,AL1G0007001':;

SECTION_NUMBER 1
 '@T6G_MB_LIB.T6G(SCH_1):PAGE337_I38@PURE_QUANTA.74LVC1G07GV(CHIPS)':
 C_PATH='@t6g_mb_lib.t6g(sch_1):page337_i38@pure_quanta.\74lvc1g07gv\(chips)',
 P_PATH='@t6g_mb_lib.t6g(sch_1):page133_i38@pure_quanta.\74lvc1g07gv\(chips)',
 PATH='I38',
 DRAWING='@T6G_MB_LIB.T6G(SCH_1):PAGE337',
 PART_TYPE='SMLF',
 MATERIAL='IC',
 PHYS_PAGE='133',
 XY='(-7250,5825)',
 ROT='0',
 VER='1',
 LOCATION='U104',
 CDS_LIB='pure_quanta',
 CDS_PART_NAME='74LVC1G07GV-74LVC1G07GV,SMLF,IC,AL1G0007001',
 PART_NUMBER='AL1G0007001',
 VALUE='74LVC1G07GV',
 PRIM_FILE='./archive_libs/logical/74lvc1g07gv/chips/chips.prt';

PART_NAME
 U105 'PI3CSW12ZUAEX-PI3CSW12ZUAEX,SMLF,IC,AL3CSW12000':;

SECTION_NUMBER 1
 '@T6G_MB_LIB.T6G(SCH_1):PAGE136_I47@PURE_QUANTA.PI3CSW12ZUAEX(CHIPS)':
 C_PATH='@t6g_mb_lib.t6g(sch_1):page136_i47@pure_quanta.pi3csw12zuaex(chips)',
 P_PATH='@t6g_mb_lib.t6g(sch_1):page159_i47@pure_quanta.pi3csw12zuaex(chips)',
 PATH='I47',
 DRAWING='@T6G_MB_LIB.T6G(SCH_1):PAGE136',
 PART_TYPE='SMLF',
 MATERIAL='IC',
 PHYS_PAGE='159',
 XY='(-4775,5775)',
 ROT='0',
 VER='1',
 LOCATION='U105',
 CDS_LIB='pure_quanta',
 CDS_PART_NAME='PI3CSW12ZUAEX-PI3CSW12ZUAEX,SMLF,IC,AL3CSW12000',
 PART_NUMBER='AL3CSW12000',
 VALUE='PI3CSW12ZUAEX',
 PRIM_FILE='./archive_libs/logical/pi3csw12zuaex/chips/chips.prt';

PART_NAME
 U106 'PI3CSW12ZUAEX-PI3CSW12ZUAEX,SMLF,IC,AL3CSW12000':;

SECTION_NUMBER 1
 '@T6G_MB_LIB.T6G(SCH_1):PAGE136_I54@PURE_QUANTA.PI3CSW12ZUAEX(CHIPS)':
 C_PATH='@t6g_mb_lib.t6g(sch_1):page136_i54@pure_quanta.pi3csw12zuaex(chips)',
 P_PATH='@t6g_mb_lib.t6g(sch_1):page159_i54@pure_quanta.pi3csw12zuaex(chips)',
 PATH='I54',
 DRAWING='@T6G_MB_LIB.T6G(SCH_1):PAGE136',
 PART_TYPE='SMLF',
 MATERIAL='IC',
 PHYS_PAGE='159',
 XY='(-4750,4375)',
 ROT='0',
 VER='1',
 LOCATION='U106',
 CDS_LIB='pure_quanta',
 CDS_PART_NAME='PI3CSW12ZUAEX-PI3CSW12ZUAEX,SMLF,IC,AL3CSW12000',
 PART_NUMBER='AL3CSW12000',
 VALUE='PI3CSW12ZUAEX',
 PRIM_FILE='./archive_libs/logical/pi3csw12zuaex/chips/chips.prt';

PART_NAME
 U107 'PI3CSW12ZUAEX-PI3CSW12ZUAEX,SMLF,IC,AL3CSW12000':;

SECTION_NUMBER 1
 '@T6G_MB_LIB.T6G(SCH_1):PAGE136_I63@PURE_QUANTA.PI3CSW12ZUAEX(CHIPS)':
 C_PATH='@t6g_mb_lib.t6g(sch_1):page136_i63@pure_quanta.pi3csw12zuaex(chips)',
 P_PATH='@t6g_mb_lib.t6g(sch_1):page159_i63@pure_quanta.pi3csw12zuaex(chips)',
 PATH='I63',
 DRAWING='@T6G_MB_LIB.T6G(SCH_1):PAGE136',
 PART_TYPE='SMLF',
 MATERIAL='IC',
 PHYS_PAGE='159',
 XY='(-4750,2850)',
 ROT='0',
 VER='1',
 LOCATION='U107',
 CDS_LIB='pure_quanta',
 CDS_PART_NAME='PI3CSW12ZUAEX-PI3CSW12ZUAEX,SMLF,IC,AL3CSW12000',
 PART_NUMBER='AL3CSW12000',
 VALUE='PI3CSW12ZUAEX',
 PRIM_FILE='./archive_libs/logical/pi3csw12zuaex/chips/chips.prt';

PART_NAME
 U108 'PI3CSW12ZUAEX-PI3CSW12ZUAEX,SMLF,IC,AL3CSW12000':;

SECTION_NUMBER 1
 '@T6G_MB_LIB.T6G(SCH_1):PAGE136_I68@PURE_QUANTA.PI3CSW12ZUAEX(CHIPS)':
 C_PATH='@t6g_mb_lib.t6g(sch_1):page136_i68@pure_quanta.pi3csw12zuaex(chips)',
 P_PATH='@t6g_mb_lib.t6g(sch_1):page159_i68@pure_quanta.pi3csw12zuaex(chips)',
 PATH='I68',
 DRAWING='@T6G_MB_LIB.T6G(SCH_1):PAGE136',
 PART_TYPE='SMLF',
 MATERIAL='IC',
 PHYS_PAGE='159',
 XY='(-4700,1400)',
 ROT='0',
 VER='1',
 LOCATION='U108',
 CDS_LIB='pure_quanta',
 CDS_PART_NAME='PI3CSW12ZUAEX-PI3CSW12ZUAEX,SMLF,IC,AL3CSW12000',
 PART_NUMBER='AL3CSW12000',
 VALUE='PI3CSW12ZUAEX',
 PRIM_FILE='./archive_libs/logical/pi3csw12zuaex/chips/chips.prt';

PART_NAME
 U116 'SN74AVC4T774PWR-SN74AVC4T774PWR,SMLF,IC,AL04T774K00':;

SECTION_NUMBER 1
 '@T6G_MB_LIB.T6G(SCH_1):PAGE141_I117@PURE_QUANTA.SN74AVC4T774PWR(CHIPS)':
 C_PATH='@t6g_mb_lib.t6g(sch_1):page141_i117@pure_quanta.sn74avc4t774pwr(chips)',
 P_PATH='@t6g_mb_lib.t6g(sch_1):page164_i117@pure_quanta.sn74avc4t774pwr(chips)',
 PATH='I117',
 DRAWING='@T6G_MB_LIB.T6G(SCH_1):PAGE141',
 PART_TYPE='SMLF',
 MATERIAL='IC',
 PHYS_PAGE='164',
 XY='(-4525,3300)',
 ROT='0',
 VER='1',
 LOCATION='U116',
 CDS_LIB='pure_quanta',
 CDS_PART_NAME='SN74AVC4T774PWR-SN74AVC4T774PWR,SMLF,IC,AL04T774K00',
 PART_NUMBER='AL04T774K00',
 VALUE='SN74AVC4T774PWR',
 PRIM_FILE='./archive_libs/logical/sn74avc4t774pwr/chips/chips.prt';

PART_NAME
 U124 'SN74LVC1G07DBVR_SMLF-SN74LVC1G07DBVR,IC,AL1G0007024':;

SECTION_NUMBER 1
 '@T6G_MB_LIB.T6G(SCH_1):PAGE144_I38@PURE_QUANTA.SN74LVC1G07DBVR(CHIPS)':
 C_PATH='@t6g_mb_lib.t6g(sch_1):page144_i38@pure_quanta.sn74lvc1g07dbvr(chips)',
 P_PATH='@t6g_mb_lib.t6g(sch_1):page167_i38@pure_quanta.sn74lvc1g07dbvr(chips)',
 PATH='I38',
 DRAWING='@T6G_MB_LIB.T6G(SCH_1):PAGE144',
 MATERIAL='IC',
 PHYS_PAGE='167',
 XY='(-4475,700)',
 ROT='0',
 VER='1',
 PACK_TYPE='SMLF',
 LOCATION='U124',
 CDS_LIB='pure_quanta',
 CDS_PART_NAME='SN74LVC1G07DBVR_SMLF-SN74LVC1G07DBVR,IC,AL1G0007024',
 PART_NUMBER='AL1G0007024',
 VALUE='SN74LVC1G07DBVR',
 PRIM_FILE='./archive_libs/logical/sn74lvc1g07dbvr/chips/chips.prt';

PART_NAME
 U134 '74LVC2G07DW7-74LVC2G07DW-7,SMLF,IC,AL002G07003':;

SECTION_NUMBER 1
 '@T6G_MB_LIB.T6G(SCH_1):PAGE297_I4@PURE_QUANTA.74LVC2G07DW7(CHIPS)':
 C_PATH='@t6g_mb_lib.t6g(sch_1):page297_i4@pure_quanta.\74lvc2g07dw7\(chips)',
 P_PATH='@t6g_mb_lib.t6g(sch_1):page145_i4@pure_quanta.\74lvc2g07dw7\(chips)',
 PATH='I4',
 DRAWING='@T6G_MB_LIB.T6G(SCH_1):PAGE297',
 PART_TYPE='SMLF',
 MATERIAL='IC',
 PHYS_PAGE='145',
 XY='(400,-750)',
 ROT='0',
 VER='1',
 LOCATION='U134',
 CDS_LIB='pure_quanta',
 CDS_PART_NAME='74LVC2G07DW7-74LVC2G07DW-7,SMLF,IC,AL002G07003',
 PART_NUMBER='AL002G07003',
 VALUE='74LVC2G07DW-7',
 PRIM_FILE='./archive_libs/logical/74lvc2g07dw7/chips/chips.prt';

PART_NAME
 U142 'LT6700CS61TRPBF-LT6700CS6-1#TRPBF,SMLF,EMPTY,AL006A':
 ROOM='HSC BOM2';

SECTION_NUMBER 1
 '@T6G_MB_LIB.T6G(SCH_1):PAGE371_I50@PURE_QUANTA.LT6700CS61TRPBF(CHIPS)':
 C_PATH='@t6g_mb_lib.t6g(sch_1):page371_i50@pure_quanta.lt6700cs61trpbf(chips)',
 P_PATH='@t6g_mb_lib.t6g(sch_1):page267_i50@pure_quanta.lt6700cs61trpbf(chips)',
 PATH='I50',
 DRAWING='@T6G_MB_LIB.T6G(SCH_1):PAGE371',
 SEC_TYPE='',
 PART_TYPE='SMLF',
 MATERIAL='EMPTY',
 PHYS_PAGE='267',
 XY='(-5500,5800)',
 ROT='0',
 VER='1',
 LOCATION='U142',
 SEC='1',
 CDS_LIB='pure_quanta',
 CDS_PART_NAME='LT6700CS61TRPBF-LT6700CS6-1#TRPBF,SMLF,EMPTY,AL006A',
 ROOM='HSC BOM2',
 PART_NUMBER='AL006700001',
 VALUE='LT6700CS6-1#TRPBF',
 PRIM_FILE='./archive_libs/logical/lt6700cs61trpbf/chips/chips.prt';

PART_NAME
 U143 'NCT7718W-NCT7718W,SMLF,IC,AL007718001':
 ROOM='HSC BOM2';

SECTION_NUMBER 1
 '@T6G_MB_LIB.T6G(SCH_1):PAGE371_I8@PURE_QUANTA.NCT7718W(CHIPS)':
 C_PATH='@t6g_mb_lib.t6g(sch_1):page371_i8@pure_quanta.nct7718w(chips)',
 P_PATH='@t6g_mb_lib.t6g(sch_1):page267_i8@pure_quanta.nct7718w(chips)',
 PATH='I8',
 DRAWING='@T6G_MB_LIB.T6G(SCH_1):PAGE371',
 PART_TYPE='SMLF',
 MATERIAL='IC',
 PHYS_PAGE='267',
 XY='(-3825,2075)',
 ROT='0',
 VER='1',
 LOCATION='U143',
 CDS_LIB='pure_quanta',
 CDS_PART_NAME='NCT7718W-NCT7718W,SMLF,IC,AL007718001',
 ROOM='HSC BOM2',
 PART_NUMBER='AL007718001',
 VALUE='NCT7718W',
 PRIM_FILE='./archive_libs/logical/nct7718w/chips/chips.prt';

PART_NAME
 U146 'SN74AVC2T245RSWR-SN74AVC2T245RSWR,SMLF,IC,AL02T245A':;

SECTION_NUMBER 1
 '@T6G_MB_LIB.T6G(SCH_1):PAGE149_I76@PURE_QUANTA.SN74AVC2T245RSWR(CHIPS)':
 C_PATH='@t6g_mb_lib.t6g(sch_1):page149_i76@pure_quanta.sn74avc2t245rswr(chips)',
 P_PATH='@t6g_mb_lib.t6g(sch_1):page172_i76@pure_quanta.sn74avc2t245rswr(chips)',
 PATH='I76',
 DRAWING='@T6G_MB_LIB.T6G(SCH_1):PAGE149',
 PART_TYPE='SMLF',
 MATERIAL='IC',
 PHYS_PAGE='172',
 XY='(-7025,4000)',
 ROT='2',
 VER='1',
 LOCATION='U146',
 CDS_LIB='pure_quanta',
 CDS_PART_NAME='SN74AVC2T245RSWR-SN74AVC2T245RSWR,SMLF,IC,AL02T245A',
 PART_NUMBER='AL02T245000',
 VALUE='SN74AVC2T245RSWR',
 PRIM_FILE='./archive_libs/logical/sn74avc2t245rswr/chips/chips.prt';

PART_NAME
 U147 'SN74AVC2T245RSWR-SN74AVC2T245RSWR,SMLF,IC,AL02T245A':;

SECTION_NUMBER 1
 '@T6G_MB_LIB.T6G(SCH_1):PAGE149_I1@PURE_QUANTA.SN74AVC2T245RSWR(CHIPS)':
 C_PATH='@t6g_mb_lib.t6g(sch_1):page149_i1@pure_quanta.sn74avc2t245rswr(chips)',
 P_PATH='@t6g_mb_lib.t6g(sch_1):page172_i1@pure_quanta.sn74avc2t245rswr(chips)',
 PATH='I1',
 DRAWING='@T6G_MB_LIB.T6G(SCH_1):PAGE149',
 PART_TYPE='SMLF',
 MATERIAL='IC',
 PHYS_PAGE='172',
 XY='(-7000,2100)',
 ROT='2',
 VER='1',
 LOCATION='U147',
 CDS_LIB='pure_quanta',
 CDS_PART_NAME='SN74AVC2T245RSWR-SN74AVC2T245RSWR,SMLF,IC,AL02T245A',
 PART_NUMBER='AL02T245000',
 VALUE='SN74AVC2T245RSWR',
 PRIM_FILE='./archive_libs/logical/sn74avc2t245rswr/chips/chips.prt';

PART_NAME
 U148 'SN74AVC4T774PWR-SN74AVC4T774PWR,SMLF,IC,AL04T774K00':;

SECTION_NUMBER 1
 '@T6G_MB_LIB.T6G(SCH_1):PAGE149_I34@PURE_QUANTA.SN74AVC4T774PWR(CHIPS)':
 C_PATH='@t6g_mb_lib.t6g(sch_1):page149_i34@pure_quanta.sn74avc4t774pwr(chips)',
 P_PATH='@t6g_mb_lib.t6g(sch_1):page172_i34@pure_quanta.sn74avc4t774pwr(chips)',
 PATH='I34',
 DRAWING='@T6G_MB_LIB.T6G(SCH_1):PAGE149',
 PART_TYPE='SMLF',
 MATERIAL='IC',
 PHYS_PAGE='172',
 XY='(-3250,1925)',
 ROT='0',
 VER='1',
 LOCATION='U148',
 CDS_LIB='pure_quanta',
 CDS_PART_NAME='SN74AVC4T774PWR-SN74AVC4T774PWR,SMLF,IC,AL04T774K00',
 PART_NUMBER='AL04T774K00',
 VALUE='SN74AVC4T774PWR',
 PRIM_FILE='./archive_libs/logical/sn74avc4t774pwr/chips/chips.prt';

PART_NAME
 U149 'SN74AVC4T774PWR-SN74AVC4T774PWR,SMLF,IC,AL04T774K00':;

SECTION_NUMBER 1
 '@T6G_MB_LIB.T6G(SCH_1):PAGE149_I31@PURE_QUANTA.SN74AVC4T774PWR(CHIPS)':
 C_PATH='@t6g_mb_lib.t6g(sch_1):page149_i31@pure_quanta.sn74avc4t774pwr(chips)',
 P_PATH='@t6g_mb_lib.t6g(sch_1):page172_i31@pure_quanta.sn74avc4t774pwr(chips)',
 PATH='I31',
 DRAWING='@T6G_MB_LIB.T6G(SCH_1):PAGE149',
 PART_TYPE='SMLF',
 MATERIAL='IC',
 PHYS_PAGE='172',
 XY='(-3225,4075)',
 ROT='0',
 VER='1',
 LOCATION='U149',
 CDS_LIB='pure_quanta',
 CDS_PART_NAME='SN74AVC4T774PWR-SN74AVC4T774PWR,SMLF,IC,AL04T774K00',
 PART_NUMBER='AL04T774K00',
 VALUE='SN74AVC4T774PWR',
 PRIM_FILE='./archive_libs/logical/sn74avc4t774pwr/chips/chips.prt';

PART_NAME
 U150 'SN74AVC4T774PWR-SN74AVC4T774PWR,SMLF,IC,AL04T774K00':;

SECTION_NUMBER 1
 '@T6G_MB_LIB.T6G(SCH_1):PAGE150_I8@PURE_QUANTA.SN74AVC4T774PWR(CHIPS)':
 C_PATH='@t6g_mb_lib.t6g(sch_1):page150_i8@pure_quanta.sn74avc4t774pwr(chips)',
 P_PATH='@t6g_mb_lib.t6g(sch_1):page173_i8@pure_quanta.sn74avc4t774pwr(chips)',
 PATH='I8',
 DRAWING='@T6G_MB_LIB.T6G(SCH_1):PAGE150',
 PART_TYPE='SMLF',
 MATERIAL='IC',
 PHYS_PAGE='173',
 XY='(-5325,5550)',
 ROT='0',
 VER='1',
 LOCATION='U150',
 CDS_LIB='pure_quanta',
 CDS_PART_NAME='SN74AVC4T774PWR-SN74AVC4T774PWR,SMLF,IC,AL04T774K00',
 PART_NUMBER='AL04T774K00',
 VALUE='SN74AVC4T774PWR',
 PRIM_FILE='./archive_libs/logical/sn74avc4t774pwr/chips/chips.prt';

PART_NAME
 U151 'SN74AVC4T774PWR-SN74AVC4T774PWR,SMLF,IC,AL04T774K00':;

SECTION_NUMBER 1
 '@T6G_MB_LIB.T6G(SCH_1):PAGE150_I28@PURE_QUANTA.SN74AVC4T774PWR(CHIPS)':
 C_PATH='@t6g_mb_lib.t6g(sch_1):page150_i28@pure_quanta.sn74avc4t774pwr(chips)',
 P_PATH='@t6g_mb_lib.t6g(sch_1):page173_i28@pure_quanta.sn74avc4t774pwr(chips)',
 PATH='I28',
 DRAWING='@T6G_MB_LIB.T6G(SCH_1):PAGE150',
 PART_TYPE='SMLF',
 MATERIAL='IC',
 PHYS_PAGE='173',
 XY='(-5325,3875)',
 ROT='0',
 VER='1',
 LOCATION='U151',
 CDS_LIB='pure_quanta',
 CDS_PART_NAME='SN74AVC4T774PWR-SN74AVC4T774PWR,SMLF,IC,AL04T774K00',
 PART_NUMBER='AL04T774K00',
 VALUE='SN74AVC4T774PWR',
 PRIM_FILE='./archive_libs/logical/sn74avc4t774pwr/chips/chips.prt';

PART_NAME
 U152 'SN74AVC2T245RSWR-SN74AVC2T245RSWR,SMLF,IC,AL02T245A':;

SECTION_NUMBER 1
 '@T6G_MB_LIB.T6G(SCH_1):PAGE150_I60@PURE_QUANTA.SN74AVC2T245RSWR(CHIPS)':
 C_PATH='@t6g_mb_lib.t6g(sch_1):page150_i60@pure_quanta.sn74avc2t245rswr(chips)',
 P_PATH='@t6g_mb_lib.t6g(sch_1):page173_i60@pure_quanta.sn74avc2t245rswr(chips)',
 PATH='I60',
 DRAWING='@T6G_MB_LIB.T6G(SCH_1):PAGE150',
 PART_TYPE='SMLF',
 MATERIAL='IC',
 PHYS_PAGE='173',
 XY='(-5325,2175)',
 ROT='2',
 VER='1',
 LOCATION='U152',
 CDS_LIB='pure_quanta',
 CDS_PART_NAME='SN74AVC2T245RSWR-SN74AVC2T245RSWR,SMLF,IC,AL02T245A',
 PART_NUMBER='AL02T245000',
 VALUE='SN74AVC2T245RSWR',
 PRIM_FILE='./archive_libs/logical/sn74avc2t245rswr/chips/chips.prt';

PART_NAME
 U153 'SN74AUC2G66DCTR-SN74AUC2G66DCTR,SMLF,IC,AL2G0066C00':;

SECTION_NUMBER 1
 '@T6G_MB_LIB.T6G(SCH_1):PAGE151_I1@PURE_QUANTA.SN74AUC2G66DCTR(CHIPS)':
 C_PATH='@t6g_mb_lib.t6g(sch_1):page151_i1@pure_quanta.sn74auc2g66dctr(chips)',
 P_PATH='@t6g_mb_lib.t6g(sch_1):page174_i1@pure_quanta.sn74auc2g66dctr(chips)',
 PATH='I1',
 DRAWING='@T6G_MB_LIB.T6G(SCH_1):PAGE151',
 PART_TYPE='SMLF',
 MATERIAL='IC',
 PHYS_PAGE='174',
 XY='(-6375,5800)',
 ROT='0',
 VER='1',
 LOCATION='U153',
 CDS_LIB='pure_quanta',
 CDS_PART_NAME='SN74AUC2G66DCTR-SN74AUC2G66DCTR,SMLF,IC,AL2G0066C00',
 PART_NUMBER='AL2G0066C00',
 VALUE='SN74AUC2G66DCTR',
 PRIM_FILE='./archive_libs/logical/sn74auc2g66dctr/chips/chips.prt';

PART_NAME
 U154 'SN74AUC2G66DCTR-SN74AUC2G66DCTR,SMLF,IC,AL2G0066C00':;

SECTION_NUMBER 1
 '@T6G_MB_LIB.T6G(SCH_1):PAGE151_I31@PURE_QUANTA.SN74AUC2G66DCTR(CHIPS)':
 C_PATH='@t6g_mb_lib.t6g(sch_1):page151_i31@pure_quanta.sn74auc2g66dctr(chips)',
 P_PATH='@t6g_mb_lib.t6g(sch_1):page174_i31@pure_quanta.sn74auc2g66dctr(chips)',
 PATH='I31',
 DRAWING='@T6G_MB_LIB.T6G(SCH_1):PAGE151',
 PART_TYPE='SMLF',
 MATERIAL='IC',
 PHYS_PAGE='174',
 XY='(-1850,3400)',
 ROT='0',
 VER='1',
 LOCATION='U154',
 CDS_LIB='pure_quanta',
 CDS_PART_NAME='SN74AUC2G66DCTR-SN74AUC2G66DCTR,SMLF,IC,AL2G0066C00',
 PART_NUMBER='AL2G0066C00',
 VALUE='SN74AUC2G66DCTR',
 PRIM_FILE='./archive_libs/logical/sn74auc2g66dctr/chips/chips.prt';

PART_NAME
 U157 '74LVC1G07GV-74LVC1G07GV,SMLF,IC,AL1G0007001':;

SECTION_NUMBER 1
 '@T6G_MB_LIB.T6G(SCH_1):PAGE337_I25@PURE_QUANTA.74LVC1G07GV(CHIPS)':
 C_PATH='@t6g_mb_lib.t6g(sch_1):page337_i25@pure_quanta.\74lvc1g07gv\(chips)',
 P_PATH='@t6g_mb_lib.t6g(sch_1):page133_i25@pure_quanta.\74lvc1g07gv\(chips)',
 PATH='I25',
 DRAWING='@T6G_MB_LIB.T6G(SCH_1):PAGE337',
 PART_TYPE='SMLF',
 MATERIAL='IC',
 PHYS_PAGE='133',
 XY='(-4950,4250)',
 ROT='0',
 VER='1',
 LOCATION='U157',
 CDS_LIB='pure_quanta',
 CDS_PART_NAME='74LVC1G07GV-74LVC1G07GV,SMLF,IC,AL1G0007001',
 PART_NUMBER='AL1G0007001',
 VALUE='74LVC1G07GV',
 PRIM_FILE='./archive_libs/logical/74lvc1g07gv/chips/chips.prt';

PART_NAME
 U158 'MOSFET_NCH_GDS_ESD_PROTECTED-2N7002K,SMLF,IC,BAM70A':;

SECTION_NUMBER 1
 '@T6G_MB_LIB.T6G(SCH_1):PAGE365_I6@PURE_QUANTA.MOSFET_NCH_GDS_ESD_PROTECTED(CHIPS)':
 C_PATH='@t6g_mb_lib.t6g(sch_1):page365_i6@pure_quanta.mosfet_nch_gds_esd_protec~
ted(chips)',
 P_PATH='@t6g_mb_lib.t6g(sch_1):page242_i6@pure_quanta.mosfet_nch_gds_esd_protec~
ted(chips)',
 PATH='I6',
 DRAWING='@T6G_MB_LIB.T6G(SCH_1):PAGE365',
 PART_TYPE='SMLF',
 MATERIAL='IC',
 PHYS_PAGE='242',
 XY='(11625,3125)',
 ROT='0',
 VER='1',
 LOCATION='U158',
 CDS_LIB='pure_quanta',
 CDS_PART_NAME='MOSFET_NCH_GDS_ESD_PROTECTED-2N7002K,SMLF,IC,BAM70A',
 PART_NUMBER='BAM70020002',
 VALUE='2N7002K',
 PRIM_FILE='./archive_libs/logical/mosfet_nch_gds_esd_protected/chips/chips.prt';

PART_NAME
 U160 '74LV4052PW-74LV4052PW,SMLF,IC,ALLV4052K19':;

SECTION_NUMBER 1
 '@T6G_MB_LIB.T6G(SCH_1):PAGE148_I266@PURE_QUANTA.74LV4052PW(CHIPS)':
 C_PATH='@t6g_mb_lib.t6g(sch_1):page148_i266@pure_quanta.\74lv4052pw\(chips)',
 P_PATH='@t6g_mb_lib.t6g(sch_1):page171_i266@pure_quanta.\74lv4052pw\(chips)',
 PATH='I266',
 DRAWING='@T6G_MB_LIB.T6G(SCH_1):PAGE148',
 SEC_TYPE='',
 PART_TYPE='SMLF',
 MATERIAL='IC',
 PHYS_PAGE='171',
 XY='(-4875,4050)',
 ROT='0',
 VER='1',
 LOCATION='U160',
 SEC='1',
 CDS_LIB='pure_quanta',
 CDS_PART_NAME='74LV4052PW-74LV4052PW,SMLF,IC,ALLV4052K19',
 PART_NUMBER='ALLV4052K19',
 VALUE='74LV4052PW',
 PRIM_FILE='./archive_libs/logical/74lv4052pw/chips/chips.prt';

PART_NAME
 U166 'SCHOTTKY_DUAL_12A_3C-BAT54CW,SMLF,IC,BCBAT54CZ13':;

SECTION_NUMBER 1
 '@T6G_MB_LIB.T6G(SCH_1):PAGE156_I99@PURE_QUANTA.SCHOTTKY_DUAL_12A_3C(CHIPS)':
 C_PATH='@t6g_mb_lib.t6g(sch_1):page156_i99@pure_quanta.schottky_dual_12a_3c(chi~
ps)',
 P_PATH='@t6g_mb_lib.t6g(sch_1):page187_i99@pure_quanta.schottky_dual_12a_3c(chi~
ps)',
 PATH='I99',
 DRAWING='@T6G_MB_LIB.T6G(SCH_1):PAGE156',
 PART_TYPE='SMLF',
 MATERIAL='IC',
 PHYS_PAGE='187',
 XY='(-7200,7000)',
 ROT='5',
 VER='1',
 LOCATION='U166',
 CDS_LIB='pure_quanta',
 CDS_PART_NAME='SCHOTTKY_DUAL_12A_3C-BAT54CW,SMLF,IC,BCBAT54CZ13',
 PART_NUMBER='BCBAT54CZ13',
 VALUE='BAT54CW',
 PRIM_FILE='./archive_libs/logical/schottky_dual_12a_3c/chips/chips.prt';

PART_NAME
 U167 'NCP698SQ15T1G-NCP698SQ15T1G,SMLF,EMPTY,AL000698000':;

SECTION_NUMBER 1
 '@T6G_MB_LIB.T6G(SCH_1):PAGE156_I130@PURE_QUANTA.NCP698SQ15T1G(CHIPS)':
 C_PATH='@t6g_mb_lib.t6g(sch_1):page156_i130@pure_quanta.ncp698sq15t1g(chips)',
 P_PATH='@t6g_mb_lib.t6g(sch_1):page187_i130@pure_quanta.ncp698sq15t1g(chips)',
 PATH='I130',
 DRAWING='@T6G_MB_LIB.T6G(SCH_1):PAGE156',
 PART_TYPE='SMLF',
 MATERIAL='EMPTY',
 PHYS_PAGE='187',
 XY='(-4300,6925)',
 ROT='0',
 VER='1',
 LOCATION='U167',
 CDS_LIB='pure_quanta',
 CDS_PART_NAME='NCP698SQ15T1G-NCP698SQ15T1G,SMLF,EMPTY,AL000698000',
 PART_NUMBER='AL000698000',
 VALUE='NCP698SQ15T1G',
 PRIM_FILE='./archive_libs/logical/ncp698sq15t1g/chips/chips.prt';

PART_NAME
 U175 'LTC4307CMS8-LTC4307CMS8,SMLF,IC,AL004307000':;

SECTION_NUMBER 1
 '@T6G_MB_LIB.T6G(SCH_1):PAGE249_I49@PURE_QUANTA.LTC4307CMS8(CHIPS)':
 C_PATH='@t6g_mb_lib.t6g(sch_1):page249_i49@pure_quanta.ltc4307cms8(chips)',
 P_PATH='@t6g_mb_lib.t6g(sch_1):page248_i49@pure_quanta.ltc4307cms8(chips)',
 PATH='I49',
 DRAWING='@T6G_MB_LIB.T6G(SCH_1):PAGE249',
 PART_TYPE='SMLF',
 MATERIAL='IC',
 PHYS_PAGE='248',
 XY='(-6275,5325)',
 ROT='0',
 VER='1',
 LOCATION='U175',
 CDS_LIB='pure_quanta',
 CDS_PART_NAME='LTC4307CMS8-LTC4307CMS8,SMLF,IC,AL004307000',
 PART_NUMBER='AL004307000',
 VALUE='LTC4307CMS8',
 PRIM_FILE='./archive_libs/logical/ltc4307cms8/chips/chips.prt';

PART_NAME
 U176 'LTC4307CMS8-LTC4307CMS8,SMLF,EMPTY,AL004307000':;

SECTION_NUMBER 1
 '@T6G_MB_LIB.T6G(SCH_1):PAGE249_I30@PURE_QUANTA.LTC4307CMS8(CHIPS)':
 C_PATH='@t6g_mb_lib.t6g(sch_1):page249_i30@pure_quanta.ltc4307cms8(chips)',
 P_PATH='@t6g_mb_lib.t6g(sch_1):page248_i30@pure_quanta.ltc4307cms8(chips)',
 PATH='I30',
 DRAWING='@T6G_MB_LIB.T6G(SCH_1):PAGE249',
 PART_TYPE='SMLF',
 MATERIAL='EMPTY',
 PHYS_PAGE='248',
 XY='(-3925,1175)',
 ROT='0',
 VER='1',
 LOCATION='U176',
 CDS_LIB='pure_quanta',
 CDS_PART_NAME='LTC4307CMS8-LTC4307CMS8,SMLF,EMPTY,AL004307000',
 PART_NUMBER='AL004307000',
 VALUE='LTC4307CMS8',
 PRIM_FILE='./archive_libs/logical/ltc4307cms8/chips/chips.prt';

PART_NAME
 U181 'PCA9539RPW-PCA9539RPW,SMLF,IC,AL009539K07':;

SECTION_NUMBER 1
 '@T6G_MB_LIB.T6G(SCH_1):PAGE246_I83@PURE_QUANTA.PCA9539RPW(CHIPS)':
 C_PATH='@t6g_mb_lib.t6g(sch_1):page246_i83@pure_quanta.pca9539rpw(chips)',
 P_PATH='@t6g_mb_lib.t6g(sch_1):page245_i83@pure_quanta.pca9539rpw(chips)',
 PATH='I83',
 DRAWING='@T6G_MB_LIB.T6G(SCH_1):PAGE246',
 SEC_TYPE='',
 PART_TYPE='SMLF',
 MATERIAL='IC',
 PHYS_PAGE='245',
 XY='(-4400,4950)',
 ROT='0',
 VER='1',
 LOCATION='U181',
 SEC='1',
 CDS_LIB='pure_quanta',
 CDS_PART_NAME='PCA9539RPW-PCA9539RPW,SMLF,IC,AL009539K07',
 PART_NUMBER='AL009539K07',
 VALUE='PCA9539RPW',
 PRIM_FILE='./archive_libs/logical/pca9539rpw/chips/chips.prt';

PART_NAME
 U190 'MOSFET_NCH_GDS_ESD_PROTECTED-2N7002K,SMLF,IC,BAM70A':;

SECTION_NUMBER 1
 '@T6G_MB_LIB.T6G(SCH_1):PAGE363_I392@PURE_QUANTA.MOSFET_NCH_GDS_ESD_PROTECTED(CHIPS)':
 C_PATH='@t6g_mb_lib.t6g(sch_1):page363_i392@pure_quanta.mosfet_nch_gds_esd_prot~
ected(chips)',
 P_PATH='@t6g_mb_lib.t6g(sch_1):page240_i392@pure_quanta.mosfet_nch_gds_esd_prot~
ected(chips)',
 PATH='I392',
 DRAWING='@T6G_MB_LIB.T6G(SCH_1):PAGE363',
 PART_TYPE='SMLF',
 MATERIAL='IC',
 PHYS_PAGE='240',
 XY='(-6000,-2650)',
 ROT='0',
 VER='1',
 LOCATION='U190',
 CDS_LIB='pure_quanta',
 CDS_PART_NAME='MOSFET_NCH_GDS_ESD_PROTECTED-2N7002K,SMLF,IC,BAM70A',
 PART_NUMBER='BAM70020002',
 VALUE='2N7002K',
 PRIM_FILE='./archive_libs/logical/mosfet_nch_gds_esd_protected/chips/chips.prt';

PART_NAME
 U192 'LTC4307CMS8-LTC4307CMS8,SMLF,IC,AL004307000':;

SECTION_NUMBER 1
 '@T6G_MB_LIB.T6G(SCH_1):PAGE363_I398@PURE_QUANTA.LTC4307CMS8(CHIPS)':
 C_PATH='@t6g_mb_lib.t6g(sch_1):page363_i398@pure_quanta.ltc4307cms8(chips)',
 P_PATH='@t6g_mb_lib.t6g(sch_1):page240_i398@pure_quanta.ltc4307cms8(chips)',
 PATH='I398',
 DRAWING='@T6G_MB_LIB.T6G(SCH_1):PAGE363',
 PART_TYPE='SMLF',
 MATERIAL='IC',
 PHYS_PAGE='240',
 XY='(-3100,-3400)',
 ROT='0',
 VER='1',
 LOCATION='U192',
 CDS_LIB='pure_quanta',
 CDS_PART_NAME='LTC4307CMS8-LTC4307CMS8,SMLF,IC,AL004307000',
 PART_NUMBER='AL004307000',
 VALUE='LTC4307CMS8',
 PRIM_FILE='./archive_libs/logical/ltc4307cms8/chips/chips.prt';

PART_NAME
 U193 'MAX11617EEET-MAX11617EEE+T,SMLF,EMPTY,AL011617W00':
 ROOM='ADC_MAM_BOM2';

SECTION_NUMBER 1
 '@T6G_MB_LIB.T6G(SCH_1):PAGE369_I169@PURE_QUANTA.MAX11617EEET(CHIPS)':
 C_PATH='@t6g_mb_lib.t6g(sch_1):page369_i169@pure_quanta.max11617eeet(chips)',
 P_PATH='@t6g_mb_lib.t6g(sch_1):page257_i169@pure_quanta.max11617eeet(chips)',
 PATH='I169',
 DRAWING='@T6G_MB_LIB.T6G(SCH_1):PAGE369',
 SEC_TYPE='',
 PART_TYPE='SMLF',
 MATERIAL='EMPTY',
 PHYS_PAGE='257',
 XY='(-2425,4900)',
 ROT='0',
 VER='1',
 LOCATION='U193',
 SEC='1',
 CDS_LIB='pure_quanta',
 CDS_PART_NAME='MAX11617EEET-MAX11617EEE+T,SMLF,EMPTY,AL011617W00',
 ROOM='ADC_MAM_BOM2',
 PART_NUMBER='AL011617W00',
 VALUE='MAX11617EEE+T',
 PRIM_FILE='./archive_libs/logical/max11617eeet/chips/chips.prt';

PART_NAME
 U194 'LTC4307CMS8-LTC4307CMS8,SMLF,IC,AL004307000':;

SECTION_NUMBER 1
 '@T6G_MB_LIB.T6G(SCH_1):PAGE249_I42@PURE_QUANTA.LTC4307CMS8(CHIPS)':
 C_PATH='@t6g_mb_lib.t6g(sch_1):page249_i42@pure_quanta.ltc4307cms8(chips)',
 P_PATH='@t6g_mb_lib.t6g(sch_1):page248_i42@pure_quanta.ltc4307cms8(chips)',
 PATH='I42',
 DRAWING='@T6G_MB_LIB.T6G(SCH_1):PAGE249',
 PART_TYPE='SMLF',
 MATERIAL='IC',
 PHYS_PAGE='248',
 XY='(-3900,3950)',
 ROT='0',
 VER='1',
 LOCATION='U194',
 CDS_LIB='pure_quanta',
 CDS_PART_NAME='LTC4307CMS8-LTC4307CMS8,SMLF,IC,AL004307000',
 PART_NUMBER='AL004307000',
 VALUE='LTC4307CMS8',
 PRIM_FILE='./archive_libs/logical/ltc4307cms8/chips/chips.prt';

PART_NAME
 U195 '74LVC2G17GW-74LVC2G17GW,SMLF,IC,AL2G0017005':;

SECTION_NUMBER 1
 '@T6G_MB_LIB.T6G(SCH_1):PAGE256_I65@PURE_QUANTA.74LVC2G17GW(CHIPS)':
 C_PATH='@t6g_mb_lib.t6g(sch_1):page256_i65@pure_quanta.\74lvc2g17gw\(chips)',
 P_PATH='@t6g_mb_lib.t6g(sch_1):page130_i65@pure_quanta.\74lvc2g17gw\(chips)',
 PATH='I65',
 DRAWING='@T6G_MB_LIB.T6G(SCH_1):PAGE256',
 PART_TYPE='SMLF',
 MATERIAL='IC',
 PHYS_PAGE='130',
 XY='(1475,2450)',
 ROT='0',
 VER='1',
 LOCATION='U195',
 CDS_LIB='pure_quanta',
 CDS_PART_NAME='74LVC2G17GW-74LVC2G17GW,SMLF,IC,AL2G0017005',
 PART_NUMBER='AL2G0017005',
 VALUE='74LVC2G17GW',
 PRIM_FILE='./archive_libs/logical/74lvc2g17gw/chips/chips.prt';

PART_NAME
 U196 '74LVC2G17GW-74LVC2G17GW,SMLF,IC,AL2G0017005':;

SECTION_NUMBER 1
 '@T6G_MB_LIB.T6G(SCH_1):PAGE256_I127@PURE_QUANTA.74LVC2G17GW(CHIPS)':
 C_PATH='@t6g_mb_lib.t6g(sch_1):page256_i127@pure_quanta.\74lvc2g17gw\(chips)',
 P_PATH='@t6g_mb_lib.t6g(sch_1):page130_i127@pure_quanta.\74lvc2g17gw\(chips)',
 PATH='I127',
 DRAWING='@T6G_MB_LIB.T6G(SCH_1):PAGE256',
 PART_TYPE='SMLF',
 MATERIAL='IC',
 PHYS_PAGE='130',
 XY='(1475,50)',
 ROT='0',
 VER='1',
 LOCATION='U196',
 CDS_LIB='pure_quanta',
 CDS_PART_NAME='74LVC2G17GW-74LVC2G17GW,SMLF,IC,AL2G0017005',
 PART_NUMBER='AL2G0017005',
 VALUE='74LVC2G17GW',
 PRIM_FILE='./archive_libs/logical/74lvc2g17gw/chips/chips.prt';

PART_NAME
 U200 'LTC4307CMS8-LTC4307CMS8,SMLF,IC,AL004307000':;

SECTION_NUMBER 1
 '@T6G_MB_LIB.T6G(SCH_1):PAGE249_I15@PURE_QUANTA.LTC4307CMS8(CHIPS)':
 C_PATH='@t6g_mb_lib.t6g(sch_1):page249_i15@pure_quanta.ltc4307cms8(chips)',
 P_PATH='@t6g_mb_lib.t6g(sch_1):page248_i15@pure_quanta.ltc4307cms8(chips)',
 PATH='I15',
 DRAWING='@T6G_MB_LIB.T6G(SCH_1):PAGE249',
 PART_TYPE='SMLF',
 MATERIAL='IC',
 PHYS_PAGE='248',
 XY='(-6500,2600)',
 ROT='0',
 VER='1',
 LOCATION='U200',
 CDS_LIB='pure_quanta',
 CDS_PART_NAME='LTC4307CMS8-LTC4307CMS8,SMLF,IC,AL004307000',
 PART_NUMBER='AL004307000',
 VALUE='LTC4307CMS8',
 PRIM_FILE='./archive_libs/logical/ltc4307cms8/chips/chips.prt';

PART_NAME
 U204 '74LVC1G126SE7-74LVC1G126SE-7,SMLF,IC,AL1G0126009':;

SECTION_NUMBER 1
 '@T6G_MB_LIB.T6G(SCH_1):PAGE256_I195@PURE_QUANTA.74LVC1G126SE7(CHIPS)':
 C_PATH='@t6g_mb_lib.t6g(sch_1):page256_i195@pure_quanta.\74lvc1g126se7\(chips)',
 P_PATH='@t6g_mb_lib.t6g(sch_1):page130_i195@pure_quanta.\74lvc1g126se7\(chips)',
 PATH='I195',
 DRAWING='@T6G_MB_LIB.T6G(SCH_1):PAGE256',
 PART_TYPE='SMLF',
 MATERIAL='IC',
 PHYS_PAGE='130',
 XY='(2000,-1950)',
 ROT='0',
 VER='1',
 LOCATION='U204',
 CDS_LIB='pure_quanta',
 CDS_PART_NAME='74LVC1G126SE7-74LVC1G126SE-7,SMLF,IC,AL1G0126009',
 PART_NUMBER='AL1G0126009',
 VALUE='74LVC1G126SE-7',
 PRIM_FILE='./archive_libs/logical/74lvc1g126se7/chips/chips.prt';

PART_NAME
 U206 'LT6700CS61TRPBF-LT6700CS6-1#TRPBF,SMLF,EMPTY,AL006A':;

SECTION_NUMBER 1
 '@T6G_MB_LIB.T6G(SCH_1):PAGE372_I49@PURE_QUANTA.LT6700CS61TRPBF(CHIPS)':
 C_PATH='@t6g_mb_lib.t6g(sch_1):page372_i49@pure_quanta.lt6700cs61trpbf(chips)',
 P_PATH='@t6g_mb_lib.t6g(sch_1):page268_i49@pure_quanta.lt6700cs61trpbf(chips)',
 PATH='I49',
 DRAWING='@T6G_MB_LIB.T6G(SCH_1):PAGE372',
 PART_TYPE='SMLF',
 MATERIAL='EMPTY',
 PHYS_PAGE='268',
 XY='(-3825,5100)',
 ROT='0',
 VER='1',
 LOCATION='U206',
 CDS_LIB='pure_quanta',
 CDS_PART_NAME='LT6700CS61TRPBF-LT6700CS6-1#TRPBF,SMLF,EMPTY,AL006A',
 PART_NUMBER='AL006700001',
 VALUE='LT6700CS6-1#TRPBF',
 PRIM_FILE='./archive_libs/logical/lt6700cs61trpbf/chips/chips.prt';

PART_NAME
 U207 '74LVC1G17GW-74LVC1G17GW,SMLF,IC,AL1G0017K01':;

SECTION_NUMBER 1
 '@T6G_MB_LIB.T6G(SCH_1):PAGE342_I58@PURE_QUANTA.74LVC1G17GW(CHIPS)':
 C_PATH='@t6g_mb_lib.t6g(sch_1):page342_i58@pure_quanta.\74lvc1g17gw\(chips)',
 P_PATH='@t6g_mb_lib.t6g(sch_1):page139_i58@pure_quanta.\74lvc1g17gw\(chips)',
 PATH='I58',
 DRAWING='@T6G_MB_LIB.T6G(SCH_1):PAGE342',
 SEC_TYPE='',
 PIN_NAMES_ROTATE='True',
 PART_TYPE='SMLF',
 MATERIAL='IC',
 PHYS_PAGE='139',
 XY='(5000,925)',
 ROT='0',
 VER='1',
 LOCATION='U207',
 SEC='1',
 CDS_LIB='pure_quanta',
 CDS_PART_NAME='74LVC1G17GW-74LVC1G17GW,SMLF,IC,AL1G0017K01',
 PART_NUMBER='AL1G0017K01',
 VALUE='74LVC1G17GW',
 PRIM_FILE='./archive_libs/logical/74lvc1g17gw/chips/chips.prt';

PART_NAME
 U211 '74LVC2G07DW7-74LVC2G07DW-7,SMLF,IC,AL002G07003':;

SECTION_NUMBER 1
 '@T6G_MB_LIB.T6G(SCH_1):PAGE338_I29@PURE_QUANTA.74LVC2G07DW7(CHIPS)':
 C_PATH='@t6g_mb_lib.t6g(sch_1):page338_i29@pure_quanta.\74lvc2g07dw7\(chips)',
 P_PATH='@t6g_mb_lib.t6g(sch_1):page134_i29@pure_quanta.\74lvc2g07dw7\(chips)',
 PATH='I29',
 DRAWING='@T6G_MB_LIB.T6G(SCH_1):PAGE338',
 PART_TYPE='SMLF',
 MATERIAL='IC',
 PHYS_PAGE='134',
 XY='(5275,9450)',
 ROT='0',
 VER='1',
 LOCATION='U211',
 CDS_LIB='pure_quanta',
 CDS_PART_NAME='74LVC2G07DW7-74LVC2G07DW-7,SMLF,IC,AL002G07003',
 PART_NUMBER='AL002G07003',
 VALUE='74LVC2G07DW-7',
 PRIM_FILE='./archive_libs/logical/74lvc2g07dw7/chips/chips.prt';

PART_NAME
 U212 '74LV4052PW-74LV4052PW,SMLF,IC,ALLV4052K19':;

SECTION_NUMBER 1
 '@T6G_MB_LIB.T6G(SCH_1):PAGE148_I302@PURE_QUANTA.74LV4052PW(CHIPS)':
 C_PATH='@t6g_mb_lib.t6g(sch_1):page148_i302@pure_quanta.\74lv4052pw\(chips)',
 P_PATH='@t6g_mb_lib.t6g(sch_1):page171_i302@pure_quanta.\74lv4052pw\(chips)',
 PATH='I302',
 DRAWING='@T6G_MB_LIB.T6G(SCH_1):PAGE148',
 SEC_TYPE='',
 PART_TYPE='SMLF',
 MATERIAL='IC',
 PHYS_PAGE='171',
 XY='(-4825,2100)',
 ROT='0',
 VER='1',
 LOCATION='U212',
 SEC='1',
 CDS_LIB='pure_quanta',
 CDS_PART_NAME='74LV4052PW-74LV4052PW,SMLF,IC,ALLV4052K19',
 PART_NUMBER='ALLV4052K19',
 VALUE='74LV4052PW',
 PRIM_FILE='./archive_libs/logical/74lv4052pw/chips/chips.prt';

PART_NAME
 U213 'IML3112Y2B000NCG8-IML3112-Y2B000NCG8,SMLF,EMPTY,ALA':;

SECTION_NUMBER 1
 '@T6G_MB_LIB.T6G(SCH_1):PAGE138_I111@PURE_QUANTA.IML3112Y2B000NCG8(CHIPS)':
 C_PATH='@t6g_mb_lib.t6g(sch_1):page138_i111@pure_quanta.iml3112y2b000ncg8(chips~
)',
 P_PATH='@t6g_mb_lib.t6g(sch_1):page161_i111@pure_quanta.iml3112y2b000ncg8(chips~
)',
 PATH='I111',
 DRAWING='@T6G_MB_LIB.T6G(SCH_1):PAGE138',
 SEC_TYPE='',
 PART_TYPE='SMLF',
 MATERIAL='EMPTY',
 PHYS_PAGE='161',
 XY='(1675,3925)',
 ROT='0',
 VER='1',
 LOCATION='U213',
 SEC='1',
 CDS_LIB='pure_quanta',
 CDS_PART_NAME='IML3112Y2B000NCG8-IML3112-Y2B000NCG8,SMLF,EMPTY,ALA',
 PART_NUMBER='AL003112004',
 VALUE='IML3112-Y2B000NCG8',
 PRIM_FILE='./archive_libs/logical/iml3112y2b000ncg8/chips/chips.prt';

PART_NAME
 U217 '74LVC1G126SE7-74LVC1G126SE-7,SMLF,IC,AL1G0126009':;

SECTION_NUMBER 1
 '@T6G_MB_LIB.T6G(SCH_1):PAGE342_I14@PURE_QUANTA.74LVC1G126SE7(CHIPS)':
 C_PATH='@t6g_mb_lib.t6g(sch_1):page342_i14@pure_quanta.\74lvc1g126se7\(chips)',
 P_PATH='@t6g_mb_lib.t6g(sch_1):page139_i14@pure_quanta.\74lvc1g126se7\(chips)',
 PATH='I14',
 DRAWING='@T6G_MB_LIB.T6G(SCH_1):PAGE342',
 PART_TYPE='SMLF',
 MATERIAL='IC',
 PHYS_PAGE='139',
 XY='(4850,-1725)',
 ROT='0',
 VER='1',
 LOCATION='U217',
 CDS_LIB='pure_quanta',
 CDS_PART_NAME='74LVC1G126SE7-74LVC1G126SE-7,SMLF,IC,AL1G0126009',
 PART_NUMBER='AL1G0126009',
 VALUE='74LVC1G126SE-7',
 PRIM_FILE='./archive_libs/logical/74lvc1g126se7/chips/chips.prt';

PART_NAME
 U218 '74LVC1G07GV-74LVC1G07GV,SMLF,IC,AL1G0007001':;

SECTION_NUMBER 1
 '@T6G_MB_LIB.T6G(SCH_1):PAGE342_I22@PURE_QUANTA.74LVC1G07GV(CHIPS)':
 C_PATH='@t6g_mb_lib.t6g(sch_1):page342_i22@pure_quanta.\74lvc1g07gv\(chips)',
 P_PATH='@t6g_mb_lib.t6g(sch_1):page139_i22@pure_quanta.\74lvc1g07gv\(chips)',
 PATH='I22',
 DRAWING='@T6G_MB_LIB.T6G(SCH_1):PAGE342',
 PART_TYPE='SMLF',
 MATERIAL='IC',
 PHYS_PAGE='139',
 XY='(5775,-400)',
 ROT='0',
 VER='1',
 LOCATION='U218',
 CDS_LIB='pure_quanta',
 CDS_PART_NAME='74LVC1G07GV-74LVC1G07GV,SMLF,IC,AL1G0007001',
 PART_NUMBER='AL1G0007001',
 VALUE='74LVC1G07GV',
 PRIM_FILE='./archive_libs/logical/74lvc1g07gv/chips/chips.prt';

PART_NAME
 U219 '74LVC1G07GV-74LVC1G07GV,SMLF,IC,AL1G0007001':;

SECTION_NUMBER 1
 '@T6G_MB_LIB.T6G(SCH_1):PAGE342_I32@PURE_QUANTA.74LVC1G07GV(CHIPS)':
 C_PATH='@t6g_mb_lib.t6g(sch_1):page342_i32@pure_quanta.\74lvc1g07gv\(chips)',
 P_PATH='@t6g_mb_lib.t6g(sch_1):page139_i32@pure_quanta.\74lvc1g07gv\(chips)',
 PATH='I32',
 DRAWING='@T6G_MB_LIB.T6G(SCH_1):PAGE342',
 PART_TYPE='SMLF',
 MATERIAL='IC',
 PHYS_PAGE='139',
 XY='(8075,-1725)',
 ROT='0',
 VER='1',
 LOCATION='U219',
 CDS_LIB='pure_quanta',
 CDS_PART_NAME='74LVC1G07GV-74LVC1G07GV,SMLF,IC,AL1G0007001',
 PART_NUMBER='AL1G0007001',
 VALUE='74LVC1G07GV',
 PRIM_FILE='./archive_libs/logical/74lvc1g07gv/chips/chips.prt';

PART_NAME
 U222 '74CBTLV3126PW-74CBTLV3126PW,SMLF,IC,AL003126K08':;

SECTION_NUMBER 1
 '@T6G_MB_LIB.T6G(SCH_1):PAGE307_I32@PURE_QUANTA.74CBTLV3126PW(CHIPS)':
 C_PATH='@t6g_mb_lib.t6g(sch_1):page307_i32@pure_quanta.\74cbtlv3126pw\(chips)',
 P_PATH='@t6g_mb_lib.t6g(sch_1):page138_i32@pure_quanta.\74cbtlv3126pw\(chips)',
 PATH='I32',
 DRAWING='@T6G_MB_LIB.T6G(SCH_1):PAGE307',
 PART_TYPE='SMLF',
 MATERIAL='IC',
 PHYS_PAGE='138',
 XY='(225,2275)',
 ROT='2',
 VER='1',
 LOCATION='U222',
 CDS_LIB='pure_quanta',
 CDS_PART_NAME='74CBTLV3126PW-74CBTLV3126PW,SMLF,IC,AL003126K08',
 PART_NUMBER='AL003126K08',
 VALUE='74CBTLV3126PW',
 PRIM_FILE='./archive_libs/logical/74cbtlv3126pw/chips/chips.prt';

PART_NAME
 U223 '74CBTLV3126PW-74CBTLV3126PW,SMLF,IC,AL003126K08':;

SECTION_NUMBER 1
 '@T6G_MB_LIB.T6G(SCH_1):PAGE307_I78@PURE_QUANTA.74CBTLV3126PW(CHIPS)':
 C_PATH='@t6g_mb_lib.t6g(sch_1):page307_i78@pure_quanta.\74cbtlv3126pw\(chips)',
 P_PATH='@t6g_mb_lib.t6g(sch_1):page138_i78@pure_quanta.\74cbtlv3126pw\(chips)',
 PATH='I78',
 DRAWING='@T6G_MB_LIB.T6G(SCH_1):PAGE307',
 PART_TYPE='SMLF',
 MATERIAL='IC',
 PHYS_PAGE='138',
 XY='(225,850)',
 ROT='2',
 VER='1',
 LOCATION='U223',
 CDS_LIB='pure_quanta',
 CDS_PART_NAME='74CBTLV3126PW-74CBTLV3126PW,SMLF,IC,AL003126K08',
 PART_NUMBER='AL003126K08',
 VALUE='74CBTLV3126PW',
 PRIM_FILE='./archive_libs/logical/74cbtlv3126pw/chips/chips.prt';

PART_NAME
 U224 '74LVC1G126SE7-74LVC1G126SE-7,SMLF,IC,AL1G0126009':;

SECTION_NUMBER 1
 '@T6G_MB_LIB.T6G(SCH_1):PAGE336_I159@PURE_QUANTA.74LVC1G126SE7(CHIPS)':
 C_PATH='@t6g_mb_lib.t6g(sch_1):page336_i159@pure_quanta.\74lvc1g126se7\(chips)',
 P_PATH='@t6g_mb_lib.t6g(sch_1):page132_i159@pure_quanta.\74lvc1g126se7\(chips)',
 PATH='I159',
 DRAWING='@T6G_MB_LIB.T6G(SCH_1):PAGE336',
 PART_TYPE='SMLF',
 MATERIAL='IC',
 PHYS_PAGE='132',
 XY='(-1975,2275)',
 ROT='0',
 VER='1',
 LOCATION='U224',
 CDS_LIB='pure_quanta',
 CDS_PART_NAME='74LVC1G126SE7-74LVC1G126SE-7,SMLF,IC,AL1G0126009',
 PART_NUMBER='AL1G0126009',
 VALUE='74LVC1G126SE-7',
 PRIM_FILE='./archive_libs/logical/74lvc1g126se7/chips/chips.prt';

PART_NAME
 U225 '74LVC1G126SE7-74LVC1G126SE-7,SMLF,IC,AL1G0126009':;

SECTION_NUMBER 1
 '@T6G_MB_LIB.T6G(SCH_1):PAGE342_I9@PURE_QUANTA.74LVC1G126SE7(CHIPS)':
 C_PATH='@t6g_mb_lib.t6g(sch_1):page342_i9@pure_quanta.\74lvc1g126se7\(chips)',
 P_PATH='@t6g_mb_lib.t6g(sch_1):page139_i9@pure_quanta.\74lvc1g126se7\(chips)',
 PATH='I9',
 DRAWING='@T6G_MB_LIB.T6G(SCH_1):PAGE342',
 PART_TYPE='SMLF',
 MATERIAL='IC',
 PHYS_PAGE='139',
 XY='(5875,-3125)',
 ROT='0',
 VER='1',
 LOCATION='U225',
 CDS_LIB='pure_quanta',
 CDS_PART_NAME='74LVC1G126SE7-74LVC1G126SE-7,SMLF,IC,AL1G0126009',
 PART_NUMBER='AL1G0126009',
 VALUE='74LVC1G126SE-7',
 PRIM_FILE='./archive_libs/logical/74lvc1g126se7/chips/chips.prt';

PART_NAME
 U235 'PCA9617ADP-PCA9617ADP,SMLF,IC,AL009617K02':;

SECTION_NUMBER 1
 '@T6G_MB_LIB.T6G(SCH_1):PAGE248_I6@PURE_QUANTA.PCA9617ADP(CHIPS)':
 C_PATH='@t6g_mb_lib.t6g(sch_1):page248_i6@pure_quanta.pca9617adp(chips)',
 P_PATH='@t6g_mb_lib.t6g(sch_1):page247_i6@pure_quanta.pca9617adp(chips)',
 PATH='I6',
 DRAWING='@T6G_MB_LIB.T6G(SCH_1):PAGE248',
 PART_TYPE='SMLF',
 MATERIAL='IC',
 PHYS_PAGE='247',
 XY='(-4775,3225)',
 ROT='0',
 VER='1',
 LOCATION='U235',
 CDS_LIB='pure_quanta',
 CDS_PART_NAME='PCA9617ADP-PCA9617ADP,SMLF,IC,AL009617K02',
 PART_NUMBER='AL009617K02',
 VALUE='PCA9617ADP',
 PRIM_FILE='./archive_libs/logical/pca9617adp/chips/chips.prt';

PART_NAME
 U236 'PCA9617ADP-PCA9617ADP,SMLF,IC,AL009617K02':;

SECTION_NUMBER 1
 '@T6G_MB_LIB.T6G(SCH_1):PAGE248_I14@PURE_QUANTA.PCA9617ADP(CHIPS)':
 C_PATH='@t6g_mb_lib.t6g(sch_1):page248_i14@pure_quanta.pca9617adp(chips)',
 P_PATH='@t6g_mb_lib.t6g(sch_1):page247_i14@pure_quanta.pca9617adp(chips)',
 PATH='I14',
 DRAWING='@T6G_MB_LIB.T6G(SCH_1):PAGE248',
 PART_TYPE='SMLF',
 MATERIAL='IC',
 PHYS_PAGE='247',
 XY='(-4750,5050)',
 ROT='0',
 VER='1',
 LOCATION='U236',
 CDS_LIB='pure_quanta',
 CDS_PART_NAME='PCA9617ADP-PCA9617ADP,SMLF,IC,AL009617K02',
 PART_NUMBER='AL009617K02',
 VALUE='PCA9617ADP',
 PRIM_FILE='./archive_libs/logical/pca9617adp/chips/chips.prt';

PART_NAME
 U237 'PI3EQX12902AZLEX-PI3EQX12902AZLEX,SMLF,IC,AL012902A':
 ROOM='PCIE REDRIVER BOM1';

SECTION_NUMBER 1
 '@T6G_MB_LIB.T6G(SCH_1):PAGE110_I63@PURE_QUANTA.PI3EQX12902AZLEX(CHIPS)':
 C_PATH='@t6g_mb_lib.t6g(sch_1):page110_i63@pure_quanta.pi3eqx12902azlex(chips)',
 P_PATH='@t6g_mb_lib.t6g(sch_1):page111_i63@pure_quanta.pi3eqx12902azlex(chips)',
 PATH='I63',
 DRAWING='@T6G_MB_LIB.T6G(SCH_1):PAGE110',
 PART_TYPE='SMLF',
 MATERIAL='IC',
 PHYS_PAGE='111',
 XY='(5200,5050)',
 ROT='0',
 VER='1',
 LOCATION='U237',
 CDS_LIB='pure_quanta',
 CDS_PART_NAME='PI3EQX12902AZLEX-PI3EQX12902AZLEX,SMLF,IC,AL012902A',
 ROOM='PCIE REDRIVER BOM1',
 PART_NUMBER='AL012902001',
 VALUE='PI3EQX12902AZLEX',
 PRIM_FILE='./archive_libs/logical/pi3eqx12902azlex/chips/chips.prt';

PART_NAME
 U239 '74LVC1G126SE7-74LVC1G126SE-7,SMLF,IC,AL1G0126009':;

SECTION_NUMBER 1
 '@T6G_MB_LIB.T6G(SCH_1):PAGE345_I53@PURE_QUANTA.74LVC1G126SE7(CHIPS)':
 C_PATH='@t6g_mb_lib.t6g(sch_1):page345_i53@pure_quanta.\74lvc1g126se7\(chips)',
 P_PATH='@t6g_mb_lib.t6g(sch_1):page144_i53@pure_quanta.\74lvc1g126se7\(chips)',
 PATH='I53',
 DRAWING='@T6G_MB_LIB.T6G(SCH_1):PAGE345',
 PART_TYPE='SMLF',
 MATERIAL='IC',
 PHYS_PAGE='144',
 XY='(9300,1100)',
 ROT='0',
 VER='1',
 LOCATION='U239',
 CDS_LIB='pure_quanta',
 CDS_PART_NAME='74LVC1G126SE7-74LVC1G126SE-7,SMLF,IC,AL1G0126009',
 PART_NUMBER='AL1G0126009',
 VALUE='74LVC1G126SE-7',
 PRIM_FILE='./archive_libs/logical/74lvc1g126se7/chips/chips.prt';

PART_NAME
 U240 '74LVC2G08DP-74LVC2G08DP,SMLF,EMPTY,ALVC2G08K01':;

SECTION_NUMBER 1
 '@T6G_MB_LIB.T6G(SCH_1):PAGE258_I11@PURE_QUANTA.74LVC2G08DP(CHIPS)':
 C_PATH='@t6g_mb_lib.t6g(sch_1):page258_i11@pure_quanta.\74lvc2g08dp\(chips)',
 P_PATH='@t6g_mb_lib.t6g(sch_1):page143_i11@pure_quanta.\74lvc2g08dp\(chips)',
 PATH='I11',
 DRAWING='@T6G_MB_LIB.T6G(SCH_1):PAGE258',
 PART_TYPE='SMLF',
 MATERIAL='EMPTY',
 PHYS_PAGE='143',
 XY='(-2600,2850)',
 ROT='0',
 VER='1',
 LOCATION='U240',
 CDS_LIB='pure_quanta',
 CDS_PART_NAME='74LVC2G08DP-74LVC2G08DP,SMLF,EMPTY,ALVC2G08K01',
 PART_NUMBER='ALVC2G08K01',
 VALUE='74LVC2G08DP',
 PRIM_FILE='./archive_libs/logical/74lvc2g08dp/chips/chips.prt';

SECTION_NUMBER 2
 '@T6G_MB_LIB.T6G(SCH_1):PAGE258_I12@PURE_QUANTA.74LVC2G08DP(CHIPS)':
 C_PATH='@t6g_mb_lib.t6g(sch_1):page258_i12@pure_quanta.\74lvc2g08dp\(chips)',
 P_PATH='@t6g_mb_lib.t6g(sch_1):page143_i12@pure_quanta.\74lvc2g08dp\(chips)',
 PATH='I12',
 DRAWING='@T6G_MB_LIB.T6G(SCH_1):PAGE258',
 PART_TYPE='SMLF',
 MATERIAL='EMPTY',
 PHYS_PAGE='143',
 XY='(-2600,1950)',
 ROT='0',
 VER='2',
 LOCATION='U240',
 CDS_LIB='pure_quanta',
 CDS_PART_NAME='74LVC2G08DP-74LVC2G08DP,SMLF,EMPTY,ALVC2G08K01',
 PART_NUMBER='ALVC2G08K01',
 VALUE='74LVC2G08DP',
 PRIM_FILE='./archive_libs/logical/74lvc2g08dp/chips/chips.prt';

PART_NAME
 U241 '74LVC2G08DP-74LVC2G08DP,SMLF,EMPTY,ALVC2G08K01':;

SECTION_NUMBER 1
 '@T6G_MB_LIB.T6G(SCH_1):PAGE258_I1@PURE_QUANTA.74LVC2G08DP(CHIPS)':
 C_PATH='@t6g_mb_lib.t6g(sch_1):page258_i1@pure_quanta.\74lvc2g08dp\(chips)',
 P_PATH='@t6g_mb_lib.t6g(sch_1):page143_i1@pure_quanta.\74lvc2g08dp\(chips)',
 PATH='I1',
 DRAWING='@T6G_MB_LIB.T6G(SCH_1):PAGE258',
 PART_TYPE='SMLF',
 MATERIAL='EMPTY',
 PHYS_PAGE='143',
 XY='(-2600,750)',
 ROT='0',
 VER='1',
 LOCATION='U241',
 CDS_LIB='pure_quanta',
 CDS_PART_NAME='74LVC2G08DP-74LVC2G08DP,SMLF,EMPTY,ALVC2G08K01',
 PART_NUMBER='ALVC2G08K01',
 VALUE='74LVC2G08DP',
 PRIM_FILE='./archive_libs/logical/74lvc2g08dp/chips/chips.prt';

SECTION_NUMBER 2
 '@T6G_MB_LIB.T6G(SCH_1):PAGE258_I2@PURE_QUANTA.74LVC2G08DP(CHIPS)':
 C_PATH='@t6g_mb_lib.t6g(sch_1):page258_i2@pure_quanta.\74lvc2g08dp\(chips)',
 P_PATH='@t6g_mb_lib.t6g(sch_1):page143_i2@pure_quanta.\74lvc2g08dp\(chips)',
 PATH='I2',
 DRAWING='@T6G_MB_LIB.T6G(SCH_1):PAGE258',
 PART_TYPE='SMLF',
 MATERIAL='EMPTY',
 PHYS_PAGE='143',
 XY='(-2600,-150)',
 ROT='0',
 VER='2',
 LOCATION='U241',
 CDS_LIB='pure_quanta',
 CDS_PART_NAME='74LVC2G08DP-74LVC2G08DP,SMLF,EMPTY,ALVC2G08K01',
 PART_NUMBER='ALVC2G08K01',
 VALUE='74LVC2G08DP',
 PRIM_FILE='./archive_libs/logical/74lvc2g08dp/chips/chips.prt';

PART_NAME
 U242 '74LVC2G08DP-74LVC2G08DP,SMLF,EMPTY,ALVC2G08K01':;

SECTION_NUMBER 1
 '@T6G_MB_LIB.T6G(SCH_1):PAGE258_I13@PURE_QUANTA.74LVC2G08DP(CHIPS)':
 C_PATH='@t6g_mb_lib.t6g(sch_1):page258_i13@pure_quanta.\74lvc2g08dp\(chips)',
 P_PATH='@t6g_mb_lib.t6g(sch_1):page143_i13@pure_quanta.\74lvc2g08dp\(chips)',
 PATH='I13',
 DRAWING='@T6G_MB_LIB.T6G(SCH_1):PAGE258',
 PART_TYPE='SMLF',
 MATERIAL='EMPTY',
 PHYS_PAGE='143',
 XY='(-400,2400)',
 ROT='0',
 VER='1',
 LOCATION='U242',
 CDS_LIB='pure_quanta',
 CDS_PART_NAME='74LVC2G08DP-74LVC2G08DP,SMLF,EMPTY,ALVC2G08K01',
 PART_NUMBER='ALVC2G08K01',
 VALUE='74LVC2G08DP',
 PRIM_FILE='./archive_libs/logical/74lvc2g08dp/chips/chips.prt';

SECTION_NUMBER 2
 '@T6G_MB_LIB.T6G(SCH_1):PAGE258_I14@PURE_QUANTA.74LVC2G08DP(CHIPS)':
 C_PATH='@t6g_mb_lib.t6g(sch_1):page258_i14@pure_quanta.\74lvc2g08dp\(chips)',
 P_PATH='@t6g_mb_lib.t6g(sch_1):page143_i14@pure_quanta.\74lvc2g08dp\(chips)',
 PATH='I14',
 DRAWING='@T6G_MB_LIB.T6G(SCH_1):PAGE258',
 PART_TYPE='SMLF',
 MATERIAL='EMPTY',
 PHYS_PAGE='143',
 XY='(-400,275)',
 ROT='0',
 VER='2',
 LOCATION='U242',
 CDS_LIB='pure_quanta',
 CDS_PART_NAME='74LVC2G08DP-74LVC2G08DP,SMLF,EMPTY,ALVC2G08K01',
 PART_NUMBER='ALVC2G08K01',
 VALUE='74LVC2G08DP',
 PRIM_FILE='./archive_libs/logical/74lvc2g08dp/chips/chips.prt';

PART_NAME
 U243 'NC7SB3157_SMLF-NC7SB3157P6X,NC7SB3157P6X,EMPTY,ALSA':;

SECTION_NUMBER 1
 '@T6G_MB_LIB.T6G(SCH_1):PAGE258_I15@PURE_QUANTA.NC7SB3157(CHIPS)':
 C_PATH='@t6g_mb_lib.t6g(sch_1):page258_i15@pure_quanta.nc7sb3157(chips)',
 P_PATH='@t6g_mb_lib.t6g(sch_1):page143_i15@pure_quanta.nc7sb3157(chips)',
 PATH='I15',
 DRAWING='@T6G_MB_LIB.T6G(SCH_1):PAGE258',
 MANUF_PN='NC7SB3157P6X',
 MATERIAL='EMPTY',
 PHYS_PAGE='143',
 XY='(2025,2400)',
 ROT='2',
 VER='1',
 PACK_TYPE='SMLF',
 LOCATION='U243',
 CDS_LIB='pure_quanta',
 CDS_PART_NAME='NC7SB3157_SMLF-NC7SB3157P6X,NC7SB3157P6X,EMPTY,ALSA',
 PART_NUMBER='ALSB3157000',
 VALUE='NC7SB3157P6X',
 PRIM_FILE='./archive_libs/logical/nc7sb3157/chips/chips.prt';

PART_NAME
 U244 'NC7SB3157_SMLF-NC7SB3157P6X,NC7SB3157P6X,EMPTY,ALSA':;

SECTION_NUMBER 1
 '@T6G_MB_LIB.T6G(SCH_1):PAGE258_I16@PURE_QUANTA.NC7SB3157(CHIPS)':
 C_PATH='@t6g_mb_lib.t6g(sch_1):page258_i16@pure_quanta.nc7sb3157(chips)',
 P_PATH='@t6g_mb_lib.t6g(sch_1):page143_i16@pure_quanta.nc7sb3157(chips)',
 PATH='I16',
 DRAWING='@T6G_MB_LIB.T6G(SCH_1):PAGE258',
 MANUF_PN='NC7SB3157P6X',
 MATERIAL='EMPTY',
 PHYS_PAGE='143',
 XY='(2025,1550)',
 ROT='2',
 VER='1',
 PACK_TYPE='SMLF',
 LOCATION='U244',
 CDS_LIB='pure_quanta',
 CDS_PART_NAME='NC7SB3157_SMLF-NC7SB3157P6X,NC7SB3157P6X,EMPTY,ALSA',
 PART_NUMBER='ALSB3157000',
 VALUE='NC7SB3157P6X',
 PRIM_FILE='./archive_libs/logical/nc7sb3157/chips/chips.prt';

PART_NAME
 U245 'NC7SB3157_SMLF-NC7SB3157P6X,NC7SB3157P6X,EMPTY,ALSA':;

SECTION_NUMBER 1
 '@T6G_MB_LIB.T6G(SCH_1):PAGE258_I18@PURE_QUANTA.NC7SB3157(CHIPS)':
 C_PATH='@t6g_mb_lib.t6g(sch_1):page258_i18@pure_quanta.nc7sb3157(chips)',
 P_PATH='@t6g_mb_lib.t6g(sch_1):page143_i18@pure_quanta.nc7sb3157(chips)',
 PATH='I18',
 DRAWING='@T6G_MB_LIB.T6G(SCH_1):PAGE258',
 MANUF_PN='NC7SB3157P6X',
 MATERIAL='EMPTY',
 PHYS_PAGE='143',
 XY='(2175,-575)',
 ROT='2',
 VER='1',
 PACK_TYPE='SMLF',
 LOCATION='U245',
 CDS_LIB='pure_quanta',
 CDS_PART_NAME='NC7SB3157_SMLF-NC7SB3157P6X,NC7SB3157P6X,EMPTY,ALSA',
 PART_NUMBER='ALSB3157000',
 VALUE='NC7SB3157P6X',
 PRIM_FILE='./archive_libs/logical/nc7sb3157/chips/chips.prt';

PART_NAME
 U246 'NC7SB3157_SMLF-NC7SB3157P6X,NC7SB3157P6X,EMPTY,ALSA':;

SECTION_NUMBER 1
 '@T6G_MB_LIB.T6G(SCH_1):PAGE258_I17@PURE_QUANTA.NC7SB3157(CHIPS)':
 C_PATH='@t6g_mb_lib.t6g(sch_1):page258_i17@pure_quanta.nc7sb3157(chips)',
 P_PATH='@t6g_mb_lib.t6g(sch_1):page143_i17@pure_quanta.nc7sb3157(chips)',
 PATH='I17',
 DRAWING='@T6G_MB_LIB.T6G(SCH_1):PAGE258',
 MANUF_PN='NC7SB3157P6X',
 MATERIAL='EMPTY',
 PHYS_PAGE='143',
 XY='(2200,275)',
 ROT='2',
 VER='1',
 PACK_TYPE='SMLF',
 LOCATION='U246',
 CDS_LIB='pure_quanta',
 CDS_PART_NAME='NC7SB3157_SMLF-NC7SB3157P6X,NC7SB3157P6X,EMPTY,ALSA',
 PART_NUMBER='ALSB3157000',
 VALUE='NC7SB3157P6X',
 PRIM_FILE='./archive_libs/logical/nc7sb3157/chips/chips.prt';

PART_NAME
 U247 '9FGL0251DKILFT-9FGL0251DKILFT,SMLF,IC,AL000251002':;

SECTION_NUMBER 1
 '@T6G_MB_LIB.T6G(SCH_1):PAGE232_I77@PURE_QUANTA.9FGL0251DKILFT(CHIPS)':
 C_PATH='@t6g_mb_lib.t6g(sch_1):page232_i77@pure_quanta.\9fgl0251dkilft\(chips)',
 P_PATH='@t6g_mb_lib.t6g(sch_1):page233_i77@pure_quanta.\9fgl0251dkilft\(chips)',
 PATH='I77',
 DRAWING='@T6G_MB_LIB.T6G(SCH_1):PAGE232',
 SEC_TYPE='',
 PART_TYPE='SMLF',
 MATERIAL='IC',
 PHYS_PAGE='233',
 XY='(-4300,3700)',
 ROT='0',
 VER='1',
 LOCATION='U247',
 SEC='1',
 CDS_LIB='pure_quanta',
 CDS_PART_NAME='9FGL0251DKILFT-9FGL0251DKILFT,SMLF,IC,AL000251002',
 PART_NUMBER='AL000251002',
 VALUE='9FGL0251DKILFT',
 PRIM_FILE='./archive_libs/logical/9fgl0251dkilft/chips/chips.prt';

PART_NAME
 U248 '74LVC1G32GW_SMLF-74LVC1G32GW,IC,ALVC1G32007':;

SECTION_NUMBER 1
 '@T6G_MB_LIB.T6G(SCH_1):PAGE232_I26@PURE_QUANTA.74LVC1G32GW(CHIPS)':
 C_PATH='@t6g_mb_lib.t6g(sch_1):page232_i26@pure_quanta.\74lvc1g32gw\(chips)',
 P_PATH='@t6g_mb_lib.t6g(sch_1):page233_i26@pure_quanta.\74lvc1g32gw\(chips)',
 PATH='I26',
 DRAWING='@T6G_MB_LIB.T6G(SCH_1):PAGE232',
 MATERIAL='IC',
 PHYS_PAGE='233',
 XY='(-5125,1450)',
 ROT='0',
 VER='1',
 PACK_TYPE='SMLF',
 LOCATION='U248',
 CDS_LIB='pure_quanta',
 CDS_PART_NAME='74LVC1G32GW_SMLF-74LVC1G32GW,IC,ALVC1G32007',
 PART_NUMBER='ALVC1G32007',
 VALUE='74LVC1G32GW',
 PRIM_FILE='./archive_libs/logical/74lvc1g32gw/chips/chips.prt';

PART_NAME
 U252 '74LVC2G17GW-74LVC2G17GW,SMLF,IC,AL2G0017005':;

SECTION_NUMBER 1
 '@T6G_MB_LIB.T6G(SCH_1):PAGE334_I153@PURE_QUANTA.74LVC2G17GW(CHIPS)':
 C_PATH='@t6g_mb_lib.t6g(sch_1):page334_i153@pure_quanta.\74lvc2g17gw\(chips)',
 P_PATH='@t6g_mb_lib.t6g(sch_1):page128_i153@pure_quanta.\74lvc2g17gw\(chips)',
 PATH='I153',
 DRAWING='@T6G_MB_LIB.T6G(SCH_1):PAGE334',
 PART_TYPE='SMLF',
 MATERIAL='IC',
 PHYS_PAGE='128',
 XY='(-6250,1575)',
 ROT='0',
 VER='1',
 LOCATION='U252',
 CDS_LIB='pure_quanta',
 CDS_PART_NAME='74LVC2G17GW-74LVC2G17GW,SMLF,IC,AL2G0017005',
 PART_NUMBER='AL2G0017005',
 VALUE='74LVC2G17GW',
 PRIM_FILE='./archive_libs/logical/74lvc2g17gw/chips/chips.prt';

PART_NAME
 U253 '74LVC2G17GW-74LVC2G17GW,SMLF,IC,AL2G0017005':;

SECTION_NUMBER 1
 '@T6G_MB_LIB.T6G(SCH_1):PAGE334_I26@PURE_QUANTA.74LVC2G17GW(CHIPS)':
 C_PATH='@t6g_mb_lib.t6g(sch_1):page334_i26@pure_quanta.\74lvc2g17gw\(chips)',
 P_PATH='@t6g_mb_lib.t6g(sch_1):page128_i26@pure_quanta.\74lvc2g17gw\(chips)',
 PATH='I26',
 DRAWING='@T6G_MB_LIB.T6G(SCH_1):PAGE334',
 PART_TYPE='SMLF',
 MATERIAL='IC',
 PHYS_PAGE='128',
 XY='(-6125,3575)',
 ROT='0',
 VER='1',
 LOCATION='U253',
 CDS_LIB='pure_quanta',
 CDS_PART_NAME='74LVC2G17GW-74LVC2G17GW,SMLF,IC,AL2G0017005',
 PART_NUMBER='AL2G0017005',
 VALUE='74LVC2G17GW',
 PRIM_FILE='./archive_libs/logical/74lvc2g17gw/chips/chips.prt';

PART_NAME
 U255 '74LVC2G07DW7-74LVC2G07DW-7,SMLF,IC,AL002G07003':;

SECTION_NUMBER 1
 '@T6G_MB_LIB.T6G(SCH_1):PAGE255_I16@PURE_QUANTA.74LVC2G07DW7(CHIPS)':
 C_PATH='@t6g_mb_lib.t6g(sch_1):page255_i16@pure_quanta.\74lvc2g07dw7\(chips)',
 P_PATH='@t6g_mb_lib.t6g(sch_1):page129_i16@pure_quanta.\74lvc2g07dw7\(chips)',
 PATH='I16',
 DRAWING='@T6G_MB_LIB.T6G(SCH_1):PAGE255',
 PART_TYPE='SMLF',
 MATERIAL='IC',
 PHYS_PAGE='129',
 XY='(775,3750)',
 ROT='0',
 VER='1',
 LOCATION='U255',
 CDS_LIB='pure_quanta',
 CDS_PART_NAME='74LVC2G07DW7-74LVC2G07DW-7,SMLF,IC,AL002G07003',
 PART_NUMBER='AL002G07003',
 VALUE='74LVC2G07DW-7',
 PRIM_FILE='./archive_libs/logical/74lvc2g07dw7/chips/chips.prt';

PART_NAME
 U256 '74LVC2G17GW-74LVC2G17GW,SMLF,IC,AL2G0017005':;

SECTION_NUMBER 1
 '@T6G_MB_LIB.T6G(SCH_1):PAGE334_I173@PURE_QUANTA.74LVC2G17GW(CHIPS)':
 C_PATH='@t6g_mb_lib.t6g(sch_1):page334_i173@pure_quanta.\74lvc2g17gw\(chips)',
 P_PATH='@t6g_mb_lib.t6g(sch_1):page128_i173@pure_quanta.\74lvc2g17gw\(chips)',
 PATH='I173',
 DRAWING='@T6G_MB_LIB.T6G(SCH_1):PAGE334',
 PART_TYPE='SMLF',
 MATERIAL='IC',
 PHYS_PAGE='128',
 XY='(-6325,-275)',
 ROT='0',
 VER='1',
 LOCATION='U256',
 CDS_LIB='pure_quanta',
 CDS_PART_NAME='74LVC2G17GW-74LVC2G17GW,SMLF,IC,AL2G0017005',
 PART_NUMBER='AL2G0017005',
 VALUE='74LVC2G17GW',
 PRIM_FILE='./archive_libs/logical/74lvc2g17gw/chips/chips.prt';

PART_NAME
 U257 '74LVC2G07DW7-74LVC2G07DW-7,SMLF,IC,AL002G07003':;

SECTION_NUMBER 1
 '@T6G_MB_LIB.T6G(SCH_1):PAGE255_I50@PURE_QUANTA.74LVC2G07DW7(CHIPS)':
 C_PATH='@t6g_mb_lib.t6g(sch_1):page255_i50@pure_quanta.\74lvc2g07dw7\(chips)',
 P_PATH='@t6g_mb_lib.t6g(sch_1):page129_i50@pure_quanta.\74lvc2g07dw7\(chips)',
 PATH='I50',
 DRAWING='@T6G_MB_LIB.T6G(SCH_1):PAGE255',
 PART_TYPE='SMLF',
 MATERIAL='IC',
 PHYS_PAGE='129',
 XY='(775,1250)',
 ROT='0',
 VER='1',
 LOCATION='U257',
 CDS_LIB='pure_quanta',
 CDS_PART_NAME='74LVC2G07DW7-74LVC2G07DW-7,SMLF,IC,AL002G07003',
 PART_NUMBER='AL002G07003',
 VALUE='74LVC2G07DW-7',
 PRIM_FILE='./archive_libs/logical/74lvc2g07dw7/chips/chips.prt';

PART_NAME
 U259 'SN74LVC2G07DCKR_SMLF-SN74LVC2G07DCKR,IC,AL002G07006':;

SECTION_NUMBER 1
 '@T6G_MB_LIB.T6G(SCH_1):PAGE345_I5@PURE_QUANTA.SN74LVC2G07DCKR(CHIPS)':
 C_PATH='@t6g_mb_lib.t6g(sch_1):page345_i5@pure_quanta.sn74lvc2g07dckr(chips)',
 P_PATH='@t6g_mb_lib.t6g(sch_1):page144_i5@pure_quanta.sn74lvc2g07dckr(chips)',
 PATH='I5',
 DRAWING='@T6G_MB_LIB.T6G(SCH_1):PAGE345',
 MATERIAL='IC',
 PHYS_PAGE='144',
 XY='(7625,-475)',
 ROT='0',
 VER='1',
 PACK_TYPE='SMLF',
 LOCATION='U259',
 CDS_LIB='pure_quanta',
 CDS_PART_NAME='SN74LVC2G07DCKR_SMLF-SN74LVC2G07DCKR,IC,AL002G07006',
 PART_NUMBER='AL002G07006',
 VALUE='SN74LVC2G07DCKR',
 PRIM_FILE='./archive_libs/logical/sn74lvc2g07dckr/chips/chips.prt';

PART_NAME
 U263 'ISL28022FRZT-ISL28022FRZ-T,SMLF,IC,AL028022003':;

SECTION_NUMBER 1
 '@T6G_MB_LIB.T6G(SCH_1):PAGE360_I94@PURE_QUANTA.ISL28022FRZT(CHIPS)':
 C_PATH='@t6g_mb_lib.t6g(sch_1):page360_i94@pure_quanta.isl28022frzt(chips)',
 P_PATH='@t6g_mb_lib.t6g(sch_1):page237_i94@pure_quanta.isl28022frzt(chips)',
 PATH='I94',
 DRAWING='@T6G_MB_LIB.T6G(SCH_1):PAGE360',
 SEC_TYPE='',
 PART_TYPE='SMLF',
 MATERIAL='IC',
 PHYS_PAGE='237',
 XY='(1775,125)',
 ROT='0',
 VER='1',
 LOCATION='U263',
 SEC='1',
 CDS_LIB='pure_quanta',
 CDS_PART_NAME='ISL28022FRZT-ISL28022FRZ-T,SMLF,IC,AL028022003',
 PART_NUMBER='AL028022003',
 VALUE='ISL28022FRZ-T',
 PRIM_FILE='./archive_libs/logical/isl28022frzt/chips/chips.prt';

PART_NAME
 U264 'ISL28022FRZT-ISL28022FRZ-T,SMLF,IC,AL028022003':;

SECTION_NUMBER 1
 '@T6G_MB_LIB.T6G(SCH_1):PAGE360_I46@PURE_QUANTA.ISL28022FRZT(CHIPS)':
 C_PATH='@t6g_mb_lib.t6g(sch_1):page360_i46@pure_quanta.isl28022frzt(chips)',
 P_PATH='@t6g_mb_lib.t6g(sch_1):page237_i46@pure_quanta.isl28022frzt(chips)',
 PATH='I46',
 DRAWING='@T6G_MB_LIB.T6G(SCH_1):PAGE360',
 SEC_TYPE='',
 PART_TYPE='SMLF',
 MATERIAL='IC',
 PHYS_PAGE='237',
 XY='(1350,-1975)',
 ROT='0',
 VER='1',
 LOCATION='U264',
 SEC='1',
 CDS_LIB='pure_quanta',
 CDS_PART_NAME='ISL28022FRZT-ISL28022FRZ-T,SMLF,IC,AL028022003',
 PART_NUMBER='AL028022003',
 VALUE='ISL28022FRZ-T',
 PRIM_FILE='./archive_libs/logical/isl28022frzt/chips/chips.prt';

PART_NAME
 U265 'ISL28022FRZT-ISL28022FRZ-T,SMLF,IC,AL028022003':;

SECTION_NUMBER 1
 '@T6G_MB_LIB.T6G(SCH_1):PAGE360_I69@PURE_QUANTA.ISL28022FRZT(CHIPS)':
 C_PATH='@t6g_mb_lib.t6g(sch_1):page360_i69@pure_quanta.isl28022frzt(chips)',
 P_PATH='@t6g_mb_lib.t6g(sch_1):page237_i69@pure_quanta.isl28022frzt(chips)',
 PATH='I69',
 DRAWING='@T6G_MB_LIB.T6G(SCH_1):PAGE360',
 SEC_TYPE='',
 PART_TYPE='SMLF',
 MATERIAL='IC',
 PHYS_PAGE='237',
 XY='(1475,-4125)',
 ROT='0',
 VER='1',
 LOCATION='U265',
 SEC='1',
 CDS_LIB='pure_quanta',
 CDS_PART_NAME='ISL28022FRZT-ISL28022FRZ-T,SMLF,IC,AL028022003',
 PART_NUMBER='AL028022003',
 VALUE='ISL28022FRZ-T',
 PRIM_FILE='./archive_libs/logical/isl28022frzt/chips/chips.prt';

PART_NAME
 U266 'ISL28022FRZT-ISL28022FRZ-T,SMLF,IC,AL028022003':;

SECTION_NUMBER 1
 '@T6G_MB_LIB.T6G(SCH_1):PAGE295_I30@PURE_QUANTA.ISL28022FRZT(CHIPS)':
 C_PATH='@t6g_mb_lib.t6g(sch_1):page295_i30@pure_quanta.isl28022frzt(chips)',
 P_PATH='@t6g_mb_lib.t6g(sch_1):page236_i30@pure_quanta.isl28022frzt(chips)',
 PATH='I30',
 DRAWING='@T6G_MB_LIB.T6G(SCH_1):PAGE295',
 SEC_TYPE='',
 PART_TYPE='SMLF',
 MATERIAL='IC',
 PHYS_PAGE='236',
 XY='(2925,3075)',
 ROT='0',
 VER='1',
 LOCATION='U266',
 SEC='1',
 CDS_LIB='pure_quanta',
 CDS_PART_NAME='ISL28022FRZT-ISL28022FRZ-T,SMLF,IC,AL028022003',
 PART_NUMBER='AL028022003',
 VALUE='ISL28022FRZ-T',
 PRIM_FILE='./archive_libs/logical/isl28022frzt/chips/chips.prt';

PART_NAME
 U268 'GL852GOHY60-GL852G-OHY60,SMLF,IC,AL000852001':
 ROOM='USB2 BOM1';

SECTION_NUMBER 1
 '@T6G_MB_LIB.T6G(SCH_1):PAGE358_I100@PURE_QUANTA.GL852GOHY60(CHIPS)':
 C_PATH='@t6g_mb_lib.t6g(sch_1):page358_i100@pure_quanta.gl852gohy60(chips)',
 P_PATH='@t6g_mb_lib.t6g(sch_1):page234_i100@pure_quanta.gl852gohy60(chips)',
 PATH='I100',
 DRAWING='@T6G_MB_LIB.T6G(SCH_1):PAGE358',
 PART_TYPE='SMLF',
 MATERIAL='IC',
 PHYS_PAGE='234',
 XY='(125,3825)',
 ROT='0',
 VER='1',
 LOCATION='U268',
 CDS_LIB='pure_quanta',
 CDS_PART_NAME='GL852GOHY60-GL852G-OHY60,SMLF,IC,AL000852001',
 ROOM='USB2 BOM1',
 PART_NUMBER='AL000852001',
 VALUE='GL852G-OHY60',
 PRIM_FILE='./archive_libs/logical/gl852gohy60/chips/chips.prt';

PART_NAME
 U269 'ADC128D818CIMTXNOPB-ADC128D818CIMTX/NOPB,SMLF,IC,AA':
 ROOM='ADC_TI_BOM1';

SECTION_NUMBER 1
 '@T6G_MB_LIB.T6G(SCH_1):PAGE369_I142@PURE_QUANTA.ADC128D818CIMTXNOPB(CHIPS)':
 C_PATH='@t6g_mb_lib.t6g(sch_1):page369_i142@pure_quanta.adc128d818cimtxnopb(chi~
ps)',
 P_PATH='@t6g_mb_lib.t6g(sch_1):page257_i142@pure_quanta.adc128d818cimtxnopb(chi~
ps)',
 PATH='I142',
 DRAWING='@T6G_MB_LIB.T6G(SCH_1):PAGE369',
 PIN_NAMES_ROTATE='True',
 PART_TYPE='SMLF',
 MATERIAL='IC',
 PHYS_PAGE='257',
 XY='(-1625,2100)',
 ROT='0',
 VER='1',
 LOCATION='U269',
 CDS_LIB='pure_quanta',
 CDS_PART_NAME='ADC128D818CIMTXNOPB-ADC128D818CIMTX/NOPB,SMLF,IC,AA',
 ROOM='ADC_TI_BOM1',
 PART_NUMBER='AL000128K00',
 VALUE='ADC128D818CIMTX/NOPB',
 PRIM_FILE='./archive_libs/logical/adc128d818cimtxnopb/chips/chips.prt';

PART_NAME
 U270 'LM75BD-LM75BD,SMLF,IC,AL0075BD000':;

SECTION_NUMBER 1
 '@T6G_MB_LIB.T6G(SCH_1):PAGE359_I164@PURE_QUANTA.LM75BD(CHIPS)':
 C_PATH='@t6g_mb_lib.t6g(sch_1):page359_i164@pure_quanta.lm75bd(chips)',
 P_PATH='@t6g_mb_lib.t6g(sch_1):page235_i164@pure_quanta.lm75bd(chips)',
 PATH='I164',
 DRAWING='@T6G_MB_LIB.T6G(SCH_1):PAGE359',
 PART_TYPE='SMLF',
 MATERIAL='IC',
 PHYS_PAGE='235',
 XY='(2150,1375)',
 ROT='0',
 VER='1',
 LOCATION='U270',
 CDS_LIB='pure_quanta',
 CDS_PART_NAME='LM75BD-LM75BD,SMLF,IC,AL0075BD000',
 PART_NUMBER='AL0075BD000',
 VALUE='LM75BD',
 PRIM_FILE='./archive_libs/logical/lm75bd/chips/chips.prt';

PART_NAME
 U271 'LM75BD-LM75BD,SMLF,IC,AL0075BD000':;

SECTION_NUMBER 1
 '@T6G_MB_LIB.T6G(SCH_1):PAGE359_I165@PURE_QUANTA.LM75BD(CHIPS)':
 C_PATH='@t6g_mb_lib.t6g(sch_1):page359_i165@pure_quanta.lm75bd(chips)',
 P_PATH='@t6g_mb_lib.t6g(sch_1):page235_i165@pure_quanta.lm75bd(chips)',
 PATH='I165',
 DRAWING='@T6G_MB_LIB.T6G(SCH_1):PAGE359',
 PART_TYPE='SMLF',
 MATERIAL='IC',
 PHYS_PAGE='235',
 XY='(2100,-100)',
 ROT='0',
 VER='1',
 LOCATION='U271',
 CDS_LIB='pure_quanta',
 CDS_PART_NAME='LM75BD-LM75BD,SMLF,IC,AL0075BD000',
 PART_NUMBER='AL0075BD000',
 VALUE='LM75BD',
 PRIM_FILE='./archive_libs/logical/lm75bd/chips/chips.prt';

PART_NAME
 U272 'LM75BD-LM75BD,SMLF,IC,AL0075BD000':;

SECTION_NUMBER 1
 '@T6G_MB_LIB.T6G(SCH_1):PAGE359_I166@PURE_QUANTA.LM75BD(CHIPS)':
 C_PATH='@t6g_mb_lib.t6g(sch_1):page359_i166@pure_quanta.lm75bd(chips)',
 P_PATH='@t6g_mb_lib.t6g(sch_1):page235_i166@pure_quanta.lm75bd(chips)',
 PATH='I166',
 DRAWING='@T6G_MB_LIB.T6G(SCH_1):PAGE359',
 PART_TYPE='SMLF',
 MATERIAL='IC',
 PHYS_PAGE='235',
 XY='(2075,-1575)',
 ROT='0',
 VER='1',
 LOCATION='U272',
 CDS_LIB='pure_quanta',
 CDS_PART_NAME='LM75BD-LM75BD,SMLF,IC,AL0075BD000',
 PART_NUMBER='AL0075BD000',
 VALUE='LM75BD',
 PRIM_FILE='./archive_libs/logical/lm75bd/chips/chips.prt';

PART_NAME
 U273 'LM75BD-LM75BD,SMLF,IC,AL0075BD000':;

SECTION_NUMBER 1
 '@T6G_MB_LIB.T6G(SCH_1):PAGE359_I167@PURE_QUANTA.LM75BD(CHIPS)':
 C_PATH='@t6g_mb_lib.t6g(sch_1):page359_i167@pure_quanta.lm75bd(chips)',
 P_PATH='@t6g_mb_lib.t6g(sch_1):page235_i167@pure_quanta.lm75bd(chips)',
 PATH='I167',
 DRAWING='@T6G_MB_LIB.T6G(SCH_1):PAGE359',
 PART_TYPE='SMLF',
 MATERIAL='IC',
 PHYS_PAGE='235',
 XY='(2025,-3050)',
 ROT='0',
 VER='1',
 LOCATION='U273',
 CDS_LIB='pure_quanta',
 CDS_PART_NAME='LM75BD-LM75BD,SMLF,IC,AL0075BD000',
 PART_NUMBER='AL0075BD000',
 VALUE='LM75BD',
 PRIM_FILE='./archive_libs/logical/lm75bd/chips/chips.prt';

PART_NAME
 U276 'ISL28022FRZT-ISL28022FRZ-T,SMLF,IC,AL028022003':;

SECTION_NUMBER 1
 '@T6G_MB_LIB.T6G(SCH_1):PAGE295_I129@PURE_QUANTA.ISL28022FRZT(CHIPS)':
 C_PATH='@t6g_mb_lib.t6g(sch_1):page295_i129@pure_quanta.isl28022frzt(chips)',
 P_PATH='@t6g_mb_lib.t6g(sch_1):page236_i129@pure_quanta.isl28022frzt(chips)',
 PATH='I129',
 DRAWING='@T6G_MB_LIB.T6G(SCH_1):PAGE295',
 SEC_TYPE='',
 PART_TYPE='SMLF',
 MATERIAL='IC',
 PHYS_PAGE='236',
 XY='(2925,475)',
 ROT='0',
 VER='1',
 LOCATION='U276',
 SEC='1',
 CDS_LIB='pure_quanta',
 CDS_PART_NAME='ISL28022FRZT-ISL28022FRZ-T,SMLF,IC,AL028022003',
 PART_NUMBER='AL028022003',
 VALUE='ISL28022FRZ-T',
 PRIM_FILE='./archive_libs/logical/isl28022frzt/chips/chips.prt';

PART_NAME
 U278 '74LVC1G08W57-74LVC1G08W5-7,SMLF,IC,AL1G0008020':;

SECTION_NUMBER 1
 '@T6G_MB_LIB.T6G(SCH_1):PAGE364_I31@PURE_QUANTA.74LVC1G08W57(CHIPS)':
 C_PATH='@t6g_mb_lib.t6g(sch_1):page364_i31@pure_quanta.\74lvc1g08w57\(chips)',
 P_PATH='@t6g_mb_lib.t6g(sch_1):page241_i31@pure_quanta.\74lvc1g08w57\(chips)',
 PATH='I31',
 DRAWING='@T6G_MB_LIB.T6G(SCH_1):PAGE364',
 PART_TYPE='SMLF',
 MATERIAL='IC',
 PHYS_PAGE='241',
 XY='(250,2125)',
 ROT='0',
 VER='1',
 LOCATION='U278',
 CDS_LIB='pure_quanta',
 CDS_PART_NAME='74LVC1G08W57-74LVC1G08W5-7,SMLF,IC,AL1G0008020',
 PART_NUMBER='AL1G0008020',
 VALUE='74LVC1G08W5-7',
 PRIM_FILE='./archive_libs/logical/74lvc1g08w57/chips/chips.prt';

PART_NAME
 U279 'PCA9617ADP-PCA9617ADP,SMLF,IC,AL009617K02':;

SECTION_NUMBER 1
 '@T6G_MB_LIB.T6G(SCH_1):PAGE346_I93@PURE_QUANTA.PCA9617ADP(CHIPS)':
 C_PATH='@t6g_mb_lib.t6g(sch_1):page346_i93@pure_quanta.pca9617adp(chips)',
 P_PATH='@t6g_mb_lib.t6g(sch_1):page148_i93@pure_quanta.pca9617adp(chips)',
 PATH='I93',
 DRAWING='@T6G_MB_LIB.T6G(SCH_1):PAGE346',
 PART_TYPE='SMLF',
 MATERIAL='IC',
 PHYS_PAGE='148',
 XY='(850,1175)',
 ROT='2',
 VER='1',
 LOCATION='U279',
 CDS_LIB='pure_quanta',
 CDS_PART_NAME='PCA9617ADP-PCA9617ADP,SMLF,IC,AL009617K02',
 PART_NUMBER='AL009617K02',
 VALUE='PCA9617ADP',
 PRIM_FILE='./archive_libs/logical/pca9617adp/chips/chips.prt';

PART_NAME
 U286 '74LVC1G126SE7-74LVC1G126SE-7,SMLF,IC,AL1G0126009':;

SECTION_NUMBER 1
 '@T6G_MB_LIB.T6G(SCH_1):PAGE307_I80@PURE_QUANTA.74LVC1G126SE7(CHIPS)':
 C_PATH='@t6g_mb_lib.t6g(sch_1):page307_i80@pure_quanta.\74lvc1g126se7\(chips)',
 P_PATH='@t6g_mb_lib.t6g(sch_1):page138_i80@pure_quanta.\74lvc1g126se7\(chips)',
 PATH='I80',
 DRAWING='@T6G_MB_LIB.T6G(SCH_1):PAGE307',
 PART_TYPE='SMLF',
 MATERIAL='IC',
 PHYS_PAGE='138',
 XY='(-1300,-425)',
 ROT='0',
 VER='1',
 LOCATION='U286',
 CDS_LIB='pure_quanta',
 CDS_PART_NAME='74LVC1G126SE7-74LVC1G126SE-7,SMLF,IC,AL1G0126009',
 PART_NUMBER='AL1G0126009',
 VALUE='74LVC1G126SE-7',
 PRIM_FILE='./archive_libs/logical/74lvc1g126se7/chips/chips.prt';

PART_NAME
 U290 'MOSFET_NCH_GDS_ESD_PROTECTED-2N7002K,SMLF,IC,BAM70A':;

SECTION_NUMBER 1
 '@T6G_MB_LIB.T6G(SCH_1):PAGE372_I11@PURE_QUANTA.MOSFET_NCH_GDS_ESD_PROTECTED(CHIPS)':
 C_PATH='@t6g_mb_lib.t6g(sch_1):page372_i11@pure_quanta.mosfet_nch_gds_esd_prote~
cted(chips)',
 P_PATH='@t6g_mb_lib.t6g(sch_1):page268_i11@pure_quanta.mosfet_nch_gds_esd_prote~
cted(chips)',
 PATH='I11',
 DRAWING='@T6G_MB_LIB.T6G(SCH_1):PAGE372',
 PART_TYPE='SMLF',
 MATERIAL='IC',
 PHYS_PAGE='268',
 XY='(-7450,775)',
 ROT='0',
 VER='1',
 LOCATION='U290',
 CDS_LIB='pure_quanta',
 CDS_PART_NAME='MOSFET_NCH_GDS_ESD_PROTECTED-2N7002K,SMLF,IC,BAM70A',
 PART_NUMBER='BAM70020002',
 VALUE='2N7002K',
 PRIM_FILE='./archive_libs/logical/mosfet_nch_gds_esd_protected/chips/chips.prt';

PART_NAME
 U308 '74LVC2G07DW7-74LVC2G07DW-7,SMLF,IC,AL002G07003':;

SECTION_NUMBER 1
 '@T6G_MB_LIB.T6G(SCH_1):PAGE364_I37@PURE_QUANTA.74LVC2G07DW7(CHIPS)':
 C_PATH='@t6g_mb_lib.t6g(sch_1):page364_i37@pure_quanta.\74lvc2g07dw7\(chips)',
 P_PATH='@t6g_mb_lib.t6g(sch_1):page241_i37@pure_quanta.\74lvc2g07dw7\(chips)',
 PATH='I37',
 DRAWING='@T6G_MB_LIB.T6G(SCH_1):PAGE364',
 PART_TYPE='SMLF',
 MATERIAL='IC',
 PHYS_PAGE='241',
 XY='(550,225)',
 ROT='0',
 VER='1',
 LOCATION='U308',
 CDS_LIB='pure_quanta',
 CDS_PART_NAME='74LVC2G07DW7-74LVC2G07DW-7,SMLF,IC,AL002G07003',
 PART_NUMBER='AL002G07003',
 VALUE='74LVC2G07DW-7',
 PRIM_FILE='./archive_libs/logical/74lvc2g07dw7/chips/chips.prt';

PART_NAME
 U314 '9ZXL0451EKILFT-9ZXL0451EKILFT,SMLF,IC,AL000451003':;

SECTION_NUMBER 1
 '@T6G_MB_LIB.T6G(SCH_1):PAGE160_I63@PURE_QUANTA.9ZXL0451EKILFT(CHIPS)':
 C_PATH='@t6g_mb_lib.t6g(sch_1):page160_i63@pure_quanta.\9zxl0451ekilft\(chips)',
 P_PATH='@t6g_mb_lib.t6g(sch_1):page182_i63@pure_quanta.\9zxl0451ekilft\(chips)',
 PATH='I63',
 DRAWING='@T6G_MB_LIB.T6G(SCH_1):PAGE160',
 PART_TYPE='SMLF',
 MATERIAL='IC',
 PHYS_PAGE='182',
 XY='(-4850,3700)',
 ROT='0',
 VER='1',
 LOCATION='U314',
 CDS_LIB='pure_quanta',
 CDS_PART_NAME='9ZXL0451EKILFT-9ZXL0451EKILFT,SMLF,IC,AL000451003',
 PART_NUMBER='AL000451003',
 VALUE='9ZXL0451EKILFT',
 PRIM_FILE='./archive_libs/logical/9zxl0451ekilft/chips/chips.prt';

PART_NAME
 U316 '74LVC2G17GW-74LVC2G17GW,SMLF,IC,AL2G0017005':;

SECTION_NUMBER 1
 '@T6G_MB_LIB.T6G(SCH_1):PAGE331_I86@PURE_QUANTA.74LVC2G17GW(CHIPS)':
 C_PATH='@t6g_mb_lib.t6g(sch_1):page331_i86@pure_quanta.\74lvc2g17gw\(chips)',
 P_PATH='@t6g_mb_lib.t6g(sch_1):page124_i86@pure_quanta.\74lvc2g17gw\(chips)',
 PATH='I86',
 DRAWING='@T6G_MB_LIB.T6G(SCH_1):PAGE331',
 SEC_TYPE='',
 PART_TYPE='SMLF',
 MATERIAL='IC',
 PHYS_PAGE='124',
 XY='(3975,4600)',
 ROT='0',
 VER='1',
 LOCATION='U316',
 SEC='1',
 CDS_LIB='pure_quanta',
 CDS_PART_NAME='74LVC2G17GW-74LVC2G17GW,SMLF,IC,AL2G0017005',
 PART_NUMBER='AL2G0017005',
 VALUE='74LVC2G17GW',
 PRIM_FILE='./archive_libs/logical/74lvc2g17gw/chips/chips.prt';

PART_NAME
 U320 '74LVC1G66GV-74LVC1G66GV,SMLF,IC,AL001G66000':;

SECTION_NUMBER 1
 '@T6G_MB_LIB.T6G(SCH_1):PAGE337_I82@PURE_QUANTA.74LVC1G66GV(CHIPS)':
 C_PATH='@t6g_mb_lib.t6g(sch_1):page337_i82@pure_quanta.\74lvc1g66gv\(chips)',
 P_PATH='@t6g_mb_lib.t6g(sch_1):page133_i82@pure_quanta.\74lvc1g66gv\(chips)',
 PATH='I82',
 DRAWING='@T6G_MB_LIB.T6G(SCH_1):PAGE337',
 SEC_TYPE='',
 PIN_NAMES_ROTATE='True',
 PART_TYPE='SMLF',
 MATERIAL='IC',
 PHYS_PAGE='133',
 XY='(-3175,3275)',
 ROT='0',
 VER='1',
 LOCATION='U320',
 SEC='1',
 CDS_LIB='pure_quanta',
 CDS_PART_NAME='74LVC1G66GV-74LVC1G66GV,SMLF,IC,AL001G66000',
 PART_NUMBER='AL001G66000',
 VALUE='74LVC1G66GV',
 PRIM_FILE='./archive_libs/logical/74lvc1g66gv/chips/chips.prt';

PART_NAME
 U321 '74LVC1G66GV-74LVC1G66GV,SMLF,IC,AL001G66000':;

SECTION_NUMBER 1
 '@T6G_MB_LIB.T6G(SCH_1):PAGE342_I76@PURE_QUANTA.74LVC1G66GV(CHIPS)':
 C_PATH='@t6g_mb_lib.t6g(sch_1):page342_i76@pure_quanta.\74lvc1g66gv\(chips)',
 P_PATH='@t6g_mb_lib.t6g(sch_1):page139_i76@pure_quanta.\74lvc1g66gv\(chips)',
 PATH='I76',
 DRAWING='@T6G_MB_LIB.T6G(SCH_1):PAGE342',
 SEC_TYPE='',
 PIN_NAMES_ROTATE='True',
 PART_TYPE='SMLF',
 MATERIAL='IC',
 PHYS_PAGE='139',
 XY='(10125,-3425)',
 ROT='0',
 VER='1',
 LOCATION='U321',
 SEC='1',
 CDS_LIB='pure_quanta',
 CDS_PART_NAME='74LVC1G66GV-74LVC1G66GV,SMLF,IC,AL001G66000',
 PART_NUMBER='AL001G66000',
 VALUE='74LVC1G66GV',
 PRIM_FILE='./archive_libs/logical/74lvc1g66gv/chips/chips.prt';

PART_NAME
 U324 'MOSFET_NCH_GDS_ESD_PROTECTED-2N7002K,SMLF,IC,BAM70A':;

SECTION_NUMBER 1
 '@T6G_MB_LIB.T6G(SCH_1):PAGE273_I62@PURE_QUANTA.MOSFET_NCH_GDS_ESD_PROTECTED(CHIPS)':
 C_PATH='@t6g_mb_lib.t6g(sch_1):page273_i62@pure_quanta.mosfet_nch_gds_esd_prote~
cted(chips)',
 P_PATH='@t6g_mb_lib.t6g(sch_1):page188_i62@pure_quanta.mosfet_nch_gds_esd_prote~
cted(chips)',
 PATH='I62',
 DRAWING='@T6G_MB_LIB.T6G(SCH_1):PAGE273',
 PART_TYPE='SMLF',
 MATERIAL='IC',
 PHYS_PAGE='188',
 XY='(-2375,6625)',
 ROT='0',
 VER='1',
 LOCATION='U324',
 CDS_LIB='pure_quanta',
 CDS_PART_NAME='MOSFET_NCH_GDS_ESD_PROTECTED-2N7002K,SMLF,IC,BAM70A',
 PART_NUMBER='BAM70020002',
 VALUE='2N7002K',
 PRIM_FILE='./archive_libs/logical/mosfet_nch_gds_esd_protected/chips/chips.prt';

PART_NAME
 U325 'MOSFET_N_SMLF-BSS138K,BSS138K,EMPTY,BAM138K0000':;

SECTION_NUMBER 1
 '@T6G_MB_LIB.T6G(SCH_1):PAGE372_I42@PURE_QUANTA.MOSFET_N(CHIPS)':
 C_PATH='@t6g_mb_lib.t6g(sch_1):page372_i42@pure_quanta.mosfet_n(chips)',
 P_PATH='@t6g_mb_lib.t6g(sch_1):page268_i42@pure_quanta.mosfet_n(chips)',
 PATH='I42',
 DRAWING='@T6G_MB_LIB.T6G(SCH_1):PAGE372',
 MANUF_PN='BSS138K',
 MATERIAL='EMPTY',
 PHYS_PAGE='268',
 XY='(-1675,5150)',
 ROT='0',
 VER='1',
 PACK_TYPE='SMLF',
 LOCATION='U325',
 CDS_LIB='pure_quanta',
 CDS_PART_NAME='MOSFET_N_SMLF-BSS138K,BSS138K,EMPTY,BAM138K0000',
 PART_NUMBER='BAM138K0000',
 VALUE='BSS138K',
 PRIM_FILE='./archive_libs/logical/mosfet_n/chips/chips.prt';

PART_NAME
 U326 'MPQ8633AGLEC807Z-MPQ8633AGLE-C807-Z,SMLF,IC,AL0086A':;

SECTION_NUMBER 1
 '@T6G_MB_LIB.T6G(SCH_1):PAGE244_I38@PURE_QUANTA.MPQ8633AGLEC807Z(CHIPS)':
 C_PATH='@t6g_mb_lib.t6g(sch_1):page244_i38@pure_quanta.mpq8633aglec807z(chips)',
 P_PATH='@t6g_mb_lib.t6g(sch_1):page189_i38@pure_quanta.mpq8633aglec807z(chips)',
 PATH='I38',
 DRAWING='@T6G_MB_LIB.T6G(SCH_1):PAGE244',
 PART_TYPE='SMLF',
 MATERIAL='IC',
 PHYS_PAGE='189',
 XY='(-5000,7575)',
 ROT='0',
 VER='1',
 LOCATION='U326',
 CDS_LIB='pure_quanta',
 CDS_PART_NAME='MPQ8633AGLEC807Z-MPQ8633AGLE-C807-Z,SMLF,IC,AL0086A',
 PART_NUMBER='AL008633007',
 VALUE='MPQ8633AGLE-C807-Z',
 PRIM_FILE='./archive_libs/logical/mpq8633aglec807z/chips/chips.prt';

PART_NAME
 U5201 'TUSB211IRWBR-TUSB211IRWBR,SMLF,EMPTY,AL000211007':
 ROOM='USB2 BOM2';

SECTION_NUMBER 1
 '@T6G_MB_LIB.T6G(SCH_1):PAGE358_I84@PURE_QUANTA.TUSB211IRWBR(CHIPS)':
 C_PATH='@t6g_mb_lib.t6g(sch_1):page358_i84@pure_quanta.tusb211irwbr(chips)',
 P_PATH='@t6g_mb_lib.t6g(sch_1):page234_i84@pure_quanta.tusb211irwbr(chips)',
 PATH='I84',
 DRAWING='@T6G_MB_LIB.T6G(SCH_1):PAGE358',
 PART_TYPE='SMLF',
 MATERIAL='EMPTY',
 PHYS_PAGE='234',
 XY='(-125,100)',
 ROT='0',
 VER='1',
 LOCATION='U5201',
 CDS_LIB='pure_quanta',
 CDS_PART_NAME='TUSB211IRWBR-TUSB211IRWBR,SMLF,EMPTY,AL000211007',
 ROOM='USB2 BOM2',
 PART_NUMBER='AL000211007',
 VALUE='TUSB211IRWBR',
 PRIM_FILE='./archive_libs/logical/tusb211irwbr/chips/chips.prt';

PART_NAME
 U6000 'DS125BR111RTWR-DS125BR111RTWR,SMLF,IC,AL000125003':
 ROOM='PCIE REDRIVER BOM2';

SECTION_NUMBER 1
 '@T6G_MB_LIB.T6G(SCH_1):PAGE111_I1@PURE_QUANTA.DS125BR111RTWR(CHIPS)':
 C_PATH='@t6g_mb_lib.t6g(sch_1):page111_i1@pure_quanta.ds125br111rtwr(chips)',
 P_PATH='@t6g_mb_lib.t6g(sch_1):page112_i1@pure_quanta.ds125br111rtwr(chips)',
 PATH='I1',
 DRAWING='@T6G_MB_LIB.T6G(SCH_1):PAGE111',
 SEC_TYPE='',
 PART_TYPE='SMLF',
 MATERIAL='IC',
 PHYS_PAGE='112',
 XY='(-4725,5325)',
 ROT='0',
 VER='1',
 LOCATION='U6000',
 SEC='1',
 CDS_LIB='pure_quanta',
 CDS_PART_NAME='DS125BR111RTWR-DS125BR111RTWR,SMLF,IC,AL000125003',
 ROOM='PCIE REDRIVER BOM2',
 PART_NUMBER='AL000125003',
 VALUE='DS125BR111RTWR',
 PRIM_FILE='./archive_libs/logical/ds125br111rtwr/chips/chips.prt';

PART_NAME
 U6001 'CYUSB330468LTXI-CYUSB3304-68LTXI,SMLF,IC,AJ0330400A':
 ROOM='USB3_HUB1_CYP';

SECTION_NUMBER 1
 '@T6G_MB_LIB.T6G(SCH_1):PAGE153_I1@PURE_QUANTA.CYUSB330468LTXI(CHIPS)':
 C_PATH='@t6g_mb_lib.t6g(sch_1):page153_i1@pure_quanta.cyusb330468ltxi(chips)',
 P_PATH='@t6g_mb_lib.t6g(sch_1):page176_i1@pure_quanta.cyusb330468ltxi(chips)',
 PATH='I1',
 DRAWING='@T6G_MB_LIB.T6G(SCH_1):PAGE153',
 SEC_TYPE='',
 PART_TYPE='SMLF',
 MATERIAL='IC',
 PHYS_PAGE='176',
 XY='(-4650,3650)',
 ROT='0',
 VER='1',
 LOCATION='U6001',
 SEC='1',
 CDS_LIB='pure_quanta',
 CDS_PART_NAME='CYUSB330468LTXI-CYUSB3304-68LTXI,SMLF,IC,AJ0330400A',
 ROOM='USB3_HUB1_CYP',
 PART_NUMBER='AJ033040001',
 VALUE='CYUSB3304-68LTXI',
 PRIM_FILE='./archive_libs/logical/cyusb330468ltxi/chips/chips.prt';

SECTION_NUMBER 2
 '@T6G_MB_LIB.T6G(SCH_1):PAGE154_I1@PURE_QUANTA.CYUSB330468LTXI(CHIPS)':
 C_PATH='@t6g_mb_lib.t6g(sch_1):page154_i1@pure_quanta.cyusb330468ltxi(chips)',
 P_PATH='@t6g_mb_lib.t6g(sch_1):page177_i1@pure_quanta.cyusb330468ltxi(chips)',
 PATH='I1',
 DRAWING='@T6G_MB_LIB.T6G(SCH_1):PAGE154',
 PART_TYPE='SMLF',
 MATERIAL='IC',
 PHYS_PAGE='177',
 XY='(-4700,3600)',
 ROT='0',
 VER='2',
 LOCATION='U6001',
 CDS_LIB='pure_quanta',
 CDS_PART_NAME='CYUSB330468LTXI-CYUSB3304-68LTXI,SMLF,IC,AJ0330400A',
 ROOM='USB3_HUB1_CYP',
 PART_NUMBER='AJ033040001',
 VALUE='CYUSB3304-68LTXI',
 PRIM_FILE='./archive_libs/logical/cyusb330468ltxi/chips/chips.prt';

PART_NAME
 U6002 'TUSB8042AIRGCR-TUSB8042AIRGCR,SMLF,IC,AL008042000':
 ROOM='USB3_HUB2';

SECTION_NUMBER 1
 '@T6G_MB_LIB.T6G(SCH_1):PAGE155_I101@PURE_QUANTA.TUSB8042AIRGCR(CHIPS)':
 C_PATH='@t6g_mb_lib.t6g(sch_1):page155_i101@pure_quanta.tusb8042airgcr(chips)',
 P_PATH='@t6g_mb_lib.t6g(sch_1):page178_i101@pure_quanta.tusb8042airgcr(chips)',
 PATH='I101',
 DRAWING='@T6G_MB_LIB.T6G(SCH_1):PAGE155',
 SEC_TYPE='',
 PART_TYPE='SMLF',
 MATERIAL='IC',
 PHYS_PAGE='178',
 XY='(-4850,3400)',
 ROT='0',
 VER='1',
 LOCATION='U6002',
 SEC='1',
 CDS_LIB='pure_quanta',
 CDS_PART_NAME='TUSB8042AIRGCR-TUSB8042AIRGCR,SMLF,IC,AL008042000',
 ROOM='USB3_HUB2',
 PART_NUMBER='AL008042000',
 VALUE='TUSB8042AIRGCR',
 PRIM_FILE='./archive_libs/logical/tusb8042airgcr/chips/chips.prt';

SECTION_NUMBER 2
 '@T6G_MB_LIB.T6G(SCH_1):PAGE157_I119@PURE_QUANTA.TUSB8042AIRGCR(CHIPS)':
 C_PATH='@t6g_mb_lib.t6g(sch_1):page157_i119@pure_quanta.tusb8042airgcr(chips)',
 P_PATH='@t6g_mb_lib.t6g(sch_1):page179_i119@pure_quanta.tusb8042airgcr(chips)',
 PATH='I119',
 DRAWING='@T6G_MB_LIB.T6G(SCH_1):PAGE157',
 SEC_TYPE='',
 PART_TYPE='SMLF',
 MATERIAL='IC',
 PHYS_PAGE='179',
 XY='(-4400,4500)',
 ROT='0',
 VER='2',
 LOCATION='U6002',
 SEC='2',
 CDS_LIB='pure_quanta',
 CDS_PART_NAME='TUSB8042AIRGCR-TUSB8042AIRGCR,SMLF,IC,AL008042000',
 ROOM='USB3_HUB2',
 PART_NUMBER='AL008042000',
 VALUE='TUSB8042AIRGCR',
 PRIM_FILE='./archive_libs/logical/tusb8042airgcr/chips/chips.prt';

PART_NAME
 U6003 'M24128BWMN6TP-M24128-BWMN6TP,SMLF,IC,AKE30Z00613':
 ROOM='USB3_HUB1_CYP';

SECTION_NUMBER 1
 '@T6G_MB_LIB.T6G(SCH_1):PAGE153_I64@PURE_QUANTA.M24128BWMN6TP(CHIPS)':
 C_PATH='@t6g_mb_lib.t6g(sch_1):page153_i64@pure_quanta.m24128bwmn6tp(chips)',
 P_PATH='@t6g_mb_lib.t6g(sch_1):page176_i64@pure_quanta.m24128bwmn6tp(chips)',
 PATH='I64',
 DRAWING='@T6G_MB_LIB.T6G(SCH_1):PAGE153',
 SEC_TYPE='',
 PART_TYPE='SMLF',
 MATERIAL='IC',
 PHYS_PAGE='176',
 XY='(-2050,2825)',
 ROT='0',
 VER='1',
 LOCATION='U6003',
 SEC='1',
 CDS_LIB='pure_quanta',
 CDS_PART_NAME='M24128BWMN6TP-M24128-BWMN6TP,SMLF,IC,AKE30Z00613',
 ROOM='USB3_HUB1_CYP',
 PART_NUMBER='AKE30Z00613',
 VALUE='M24128-BWMN6TP',
 PRIM_FILE='./archive_libs/logical/m24128bwmn6tp/chips/chips.prt';

PART_NAME
 U6004 'MOSFET_NCH_GDS_ESD_PROTECTED-2N7002K,SMLF,EMPTY,BAA':
 ROOM='HSC BOM2';

SECTION_NUMBER 1
 '@T6G_MB_LIB.T6G(SCH_1):PAGE371_I68@PURE_QUANTA.MOSFET_NCH_GDS_ESD_PROTECTED(CHIPS)':
 C_PATH='@t6g_mb_lib.t6g(sch_1):page371_i68@pure_quanta.mosfet_nch_gds_esd_prote~
cted(chips)',
 P_PATH='@t6g_mb_lib.t6g(sch_1):page267_i68@pure_quanta.mosfet_nch_gds_esd_prote~
cted(chips)',
 PATH='I68',
 DRAWING='@T6G_MB_LIB.T6G(SCH_1):PAGE371',
 PART_TYPE='SMLF',
 MATERIAL='EMPTY',
 PHYS_PAGE='267',
 XY='(-3450,6275)',
 ROT='0',
 VER='1',
 LOCATION='U6004',
 CDS_LIB='pure_quanta',
 CDS_PART_NAME='MOSFET_NCH_GDS_ESD_PROTECTED-2N7002K,SMLF,EMPTY,BAA',
 ROOM='HSC BOM2',
 PART_NUMBER='BAM70020002',
 VALUE='2N7002K',
 PRIM_FILE='./archive_libs/logical/mosfet_nch_gds_esd_protected/chips/chips.prt';

PART_NAME
 U6005 'ISL28022FRZT-ISL28022FRZ-T,SMLF,IC,AL028022003':;

SECTION_NUMBER 1
 '@T6G_MB_LIB.T6G(SCH_1):PAGE271_I28@PURE_QUANTA.ISL28022FRZT(CHIPS)':
 C_PATH='@t6g_mb_lib.t6g(sch_1):page271_i28@pure_quanta.isl28022frzt(chips)',
 P_PATH='@t6g_mb_lib.t6g(sch_1):page271_i28@pure_quanta.isl28022frzt(chips)',
 PATH='I28',
 DRAWING='@T6G_MB_LIB.T6G(SCH_1):PAGE271',
 SEC_TYPE='',
 PART_TYPE='SMLF',
 MATERIAL='IC',
 PHYS_PAGE='271',
 XY='(-4575,5350)',
 ROT='0',
 VER='1',
 LOCATION='U6005',
 SEC='1',
 CDS_LIB='pure_quanta',
 CDS_PART_NAME='ISL28022FRZT-ISL28022FRZ-T,SMLF,IC,AL028022003',
 PART_NUMBER='AL028022003',
 VALUE='ISL28022FRZ-T',
 PRIM_FILE='./archive_libs/logical/isl28022frzt/chips/chips.prt';

PART_NAME
 U6006 'APX80929SAG7-APX809-29SAG-7,SMLF,IC,AL080929000':;

SECTION_NUMBER 1
 '@T6G_MB_LIB.T6G(SCH_1):PAGE273_I131@PURE_QUANTA.APX80929SAG7(CHIPS)':
 C_PATH='@t6g_mb_lib.t6g(sch_1):page273_i131@pure_quanta.apx80929sag7(chips)',
 P_PATH='@t6g_mb_lib.t6g(sch_1):page188_i131@pure_quanta.apx80929sag7(chips)',
 PATH='I131',
 DRAWING='@T6G_MB_LIB.T6G(SCH_1):PAGE273',
 SEC_TYPE='',
 PART_TYPE='SMLF',
 MATERIAL='IC',
 PHYS_PAGE='188',
 XY='(-7125,2325)',
 ROT='2',
 VER='1',
 LOCATION='U6006',
 SEC='1',
 CDS_LIB='pure_quanta',
 CDS_PART_NAME='APX80929SAG7-APX809-29SAG-7,SMLF,IC,AL080929000',
 PART_NUMBER='AL080929000',
 VALUE='APX809-29SAG-7',
 PRIM_FILE='./archive_libs/logical/apx80929sag7/chips/chips.prt';

PART_NAME
 U6010 'PT5161LRS-PT5161LRS,SMLF,IC,AJ051610U03':;

SECTION_NUMBER 1
 '@T6G_MB_LIB.T6G(SCH_1):PAGE383_I4@PURE_QUANTA.PT5161LRS(CHIPS)':
 C_PATH='@t6g_mb_lib.t6g(sch_1):page383_i4@pure_quanta.pt5161lrs(chips)',
 P_PATH='@t6g_mb_lib.t6g(sch_1):page274_i4@pure_quanta.pt5161lrs(chips)',
 PATH='I4',
 DRAWING='@T6G_MB_LIB.T6G(SCH_1):PAGE383',
 PART_TYPE='SMLF',
 MATERIAL='IC',
 PHYS_PAGE='274',
 XY='(-8100,4075)',
 ROT='0',
 VER='1',
 LOCATION='U6010',
 CDS_LIB='pure_quanta',
 CDS_PART_NAME='PT5161LRS-PT5161LRS,SMLF,IC,AJ051610U03',
 PART_NUMBER='AJ051610U03',
 VALUE='PT5161LRS',
 PRIM_FILE='./archive_libs/logical/pt5161lrs/chips/chips.prt';

SECTION_NUMBER 2
 '@T6G_MB_LIB.T6G(SCH_1):PAGE383_I3@PURE_QUANTA.PT5161LRS(CHIPS)':
 C_PATH='@t6g_mb_lib.t6g(sch_1):page383_i3@pure_quanta.pt5161lrs(chips)',
 P_PATH='@t6g_mb_lib.t6g(sch_1):page274_i3@pure_quanta.pt5161lrs(chips)',
 PATH='I3',
 DRAWING='@T6G_MB_LIB.T6G(SCH_1):PAGE383',
 PART_TYPE='SMLF',
 MATERIAL='IC',
 PHYS_PAGE='274',
 XY='(-3650,4100)',
 ROT='0',
 VER='2',
 LOCATION='U6010',
 CDS_LIB='pure_quanta',
 CDS_PART_NAME='PT5161LRS-PT5161LRS,SMLF,IC,AJ051610U03',
 PART_NUMBER='AJ051610U03',
 VALUE='PT5161LRS',
 PRIM_FILE='./archive_libs/logical/pt5161lrs/chips/chips.prt';

SECTION_NUMBER 3
 '@T6G_MB_LIB.T6G(SCH_1):PAGE385_I53@PURE_QUANTA.PT5161LRS(CHIPS)':
 C_PATH='@t6g_mb_lib.t6g(sch_1):page385_i53@pure_quanta.pt5161lrs(chips)',
 P_PATH='@t6g_mb_lib.t6g(sch_1):page276_i53@pure_quanta.pt5161lrs(chips)',
 PATH='I53',
 DRAWING='@T6G_MB_LIB.T6G(SCH_1):PAGE385',
 PART_TYPE='SMLF',
 MATERIAL='IC',
 PHYS_PAGE='276',
 XY='(-4375,2300)',
 ROT='0',
 VER='3',
 LOCATION='U6010',
 CDS_LIB='pure_quanta',
 CDS_PART_NAME='PT5161LRS-PT5161LRS,SMLF,IC,AJ051610U03',
 PART_NUMBER='AJ051610U03',
 VALUE='PT5161LRS',
 PRIM_FILE='./archive_libs/logical/pt5161lrs/chips/chips.prt';

SECTION_NUMBER 4
 '@T6G_MB_LIB.T6G(SCH_1):PAGE386_I3@PURE_QUANTA.PT5161LRS(CHIPS)':
 C_PATH='@t6g_mb_lib.t6g(sch_1):page386_i3@pure_quanta.pt5161lrs(chips)',
 P_PATH='@t6g_mb_lib.t6g(sch_1):page277_i3@pure_quanta.pt5161lrs(chips)',
 PATH='I3',
 DRAWING='@T6G_MB_LIB.T6G(SCH_1):PAGE386',
 PART_TYPE='SMLF',
 MATERIAL='IC',
 PHYS_PAGE='277',
 XY='(-6250,4150)',
 ROT='0',
 VER='4',
 LOCATION='U6010',
 CDS_LIB='pure_quanta',
 CDS_PART_NAME='PT5161LRS-PT5161LRS,SMLF,IC,AJ051610U03',
 PART_NUMBER='AJ051610U03',
 VALUE='PT5161LRS',
 PRIM_FILE='./archive_libs/logical/pt5161lrs/chips/chips.prt';

SECTION_NUMBER 5
 '@T6G_MB_LIB.T6G(SCH_1):PAGE386_I17@PURE_QUANTA.PT5161LRS(CHIPS)':
 C_PATH='@t6g_mb_lib.t6g(sch_1):page386_i17@pure_quanta.pt5161lrs(chips)',
 P_PATH='@t6g_mb_lib.t6g(sch_1):page277_i17@pure_quanta.pt5161lrs(chips)',
 PATH='I17',
 DRAWING='@T6G_MB_LIB.T6G(SCH_1):PAGE386',
 PART_TYPE='SMLF',
 MATERIAL='IC',
 PHYS_PAGE='277',
 XY='(-2175,3575)',
 ROT='0',
 VER='5',
 LOCATION='U6010',
 CDS_LIB='pure_quanta',
 CDS_PART_NAME='PT5161LRS-PT5161LRS,SMLF,IC,AJ051610U03',
 PART_NUMBER='AJ051610U03',
 VALUE='PT5161LRS',
 PRIM_FILE='./archive_libs/logical/pt5161lrs/chips/chips.prt';

SECTION_NUMBER 6
 '@T6G_MB_LIB.T6G(SCH_1):PAGE382_I2@PURE_QUANTA.PT5161LRS(CHIPS)':
 C_PATH='@t6g_mb_lib.t6g(sch_1):page382_i2@pure_quanta.pt5161lrs(chips)',
 P_PATH='@t6g_mb_lib.t6g(sch_1):page273_i2@pure_quanta.pt5161lrs(chips)',
 PATH='I2',
 DRAWING='@T6G_MB_LIB.T6G(SCH_1):PAGE382',
 PART_TYPE='SMLF',
 MATERIAL='IC',
 PHYS_PAGE='273',
 XY='(-7850,4375)',
 ROT='0',
 VER='6',
 LOCATION='U6010',
 CDS_LIB='pure_quanta',
 CDS_PART_NAME='PT5161LRS-PT5161LRS,SMLF,IC,AJ051610U03',
 PART_NUMBER='AJ051610U03',
 VALUE='PT5161LRS',
 PRIM_FILE='./archive_libs/logical/pt5161lrs/chips/chips.prt';

SECTION_NUMBER 7
 '@T6G_MB_LIB.T6G(SCH_1):PAGE382_I3@PURE_QUANTA.PT5161LRS(CHIPS)':
 C_PATH='@t6g_mb_lib.t6g(sch_1):page382_i3@pure_quanta.pt5161lrs(chips)',
 P_PATH='@t6g_mb_lib.t6g(sch_1):page273_i3@pure_quanta.pt5161lrs(chips)',
 PATH='I3',
 DRAWING='@T6G_MB_LIB.T6G(SCH_1):PAGE382',
 PART_TYPE='SMLF',
 MATERIAL='IC',
 PHYS_PAGE='273',
 XY='(-3475,4400)',
 ROT='0',
 VER='7',
 LOCATION='U6010',
 CDS_LIB='pure_quanta',
 CDS_PART_NAME='PT5161LRS-PT5161LRS,SMLF,IC,AJ051610U03',
 PART_NUMBER='AJ051610U03',
 VALUE='PT5161LRS',
 PRIM_FILE='./archive_libs/logical/pt5161lrs/chips/chips.prt';

SECTION_NUMBER 8
 '@T6G_MB_LIB.T6G(SCH_1):PAGE381_I3@PURE_QUANTA.PT5161LRS(CHIPS)':
 C_PATH='@t6g_mb_lib.t6g(sch_1):page381_i3@pure_quanta.pt5161lrs(chips)',
 P_PATH='@t6g_mb_lib.t6g(sch_1):page272_i3@pure_quanta.pt5161lrs(chips)',
 PATH='I3',
 DRAWING='@T6G_MB_LIB.T6G(SCH_1):PAGE381',
 PART_TYPE='SMLF',
 MATERIAL='IC',
 PHYS_PAGE='272',
 XY='(-8000,4275)',
 ROT='0',
 VER='8',
 LOCATION='U6010',
 CDS_LIB='pure_quanta',
 CDS_PART_NAME='PT5161LRS-PT5161LRS,SMLF,IC,AJ051610U03',
 PART_NUMBER='AJ051610U03',
 VALUE='PT5161LRS',
 PRIM_FILE='./archive_libs/logical/pt5161lrs/chips/chips.prt';

SECTION_NUMBER 9
 '@T6G_MB_LIB.T6G(SCH_1):PAGE381_I4@PURE_QUANTA.PT5161LRS(CHIPS)':
 C_PATH='@t6g_mb_lib.t6g(sch_1):page381_i4@pure_quanta.pt5161lrs(chips)',
 P_PATH='@t6g_mb_lib.t6g(sch_1):page272_i4@pure_quanta.pt5161lrs(chips)',
 PATH='I4',
 DRAWING='@T6G_MB_LIB.T6G(SCH_1):PAGE381',
 PART_TYPE='SMLF',
 MATERIAL='IC',
 PHYS_PAGE='272',
 XY='(-3375,4225)',
 ROT='0',
 VER='9',
 LOCATION='U6010',
 CDS_LIB='pure_quanta',
 CDS_PART_NAME='PT5161LRS-PT5161LRS,SMLF,IC,AJ051610U03',
 PART_NUMBER='AJ051610U03',
 VALUE='PT5161LRS',
 PRIM_FILE='./archive_libs/logical/pt5161lrs/chips/chips.prt';

SECTION_NUMBER 10
 '@T6G_MB_LIB.T6G(SCH_1):PAGE384_I1@PURE_QUANTA.PT5161LRS(CHIPS)':
 C_PATH='@t6g_mb_lib.t6g(sch_1):page384_i1@pure_quanta.pt5161lrs(chips)',
 P_PATH='@t6g_mb_lib.t6g(sch_1):page275_i1@pure_quanta.pt5161lrs(chips)',
 PATH='I1',
 DRAWING='@T6G_MB_LIB.T6G(SCH_1):PAGE384',
 PART_TYPE='SMLF',
 MATERIAL='IC',
 PHYS_PAGE='275',
 XY='(-7800,4800)',
 ROT='0',
 VER='10',
 LOCATION='U6010',
 CDS_LIB='pure_quanta',
 CDS_PART_NAME='PT5161LRS-PT5161LRS,SMLF,IC,AJ051610U03',
 PART_NUMBER='AJ051610U03',
 VALUE='PT5161LRS',
 PRIM_FILE='./archive_libs/logical/pt5161lrs/chips/chips.prt';

SECTION_NUMBER 11
 '@T6G_MB_LIB.T6G(SCH_1):PAGE384_I2@PURE_QUANTA.PT5161LRS(CHIPS)':
 C_PATH='@t6g_mb_lib.t6g(sch_1):page384_i2@pure_quanta.pt5161lrs(chips)',
 P_PATH='@t6g_mb_lib.t6g(sch_1):page275_i2@pure_quanta.pt5161lrs(chips)',
 PATH='I2',
 DRAWING='@T6G_MB_LIB.T6G(SCH_1):PAGE384',
 PART_TYPE='SMLF',
 MATERIAL='IC',
 PHYS_PAGE='275',
 XY='(-2625,4775)',
 ROT='0',
 VER='11',
 LOCATION='U6010',
 CDS_LIB='pure_quanta',
 CDS_PART_NAME='PT5161LRS-PT5161LRS,SMLF,IC,AJ051610U03',
 PART_NUMBER='AJ051610U03',
 VALUE='PT5161LRS',
 PRIM_FILE='./archive_libs/logical/pt5161lrs/chips/chips.prt';

PART_NAME
 U6011 'PT5161LRS-PT5161LRS,SMLF,IC,AJ051610U03':;

SECTION_NUMBER 1
 '@T6G_MB_LIB.T6G(SCH_1):PAGE406_I1@PURE_QUANTA.PT5161LRS(CHIPS)':
 C_PATH='@t6g_mb_lib.t6g(sch_1):page406_i1@pure_quanta.pt5161lrs(chips)',
 P_PATH='@t6g_mb_lib.t6g(sch_1):page285_i1@pure_quanta.pt5161lrs(chips)',
 PATH='I1',
 DRAWING='@T6G_MB_LIB.T6G(SCH_1):PAGE406',
 PART_TYPE='SMLF',
 MATERIAL='IC',
 PHYS_PAGE='285',
 XY='(-7875,4150)',
 ROT='0',
 VER='1',
 LOCATION='U6011',
 CDS_LIB='pure_quanta',
 CDS_PART_NAME='PT5161LRS-PT5161LRS,SMLF,IC,AJ051610U03',
 PART_NUMBER='AJ051610U03',
 VALUE='PT5161LRS',
 PRIM_FILE='./archive_libs/logical/pt5161lrs/chips/chips.prt';

SECTION_NUMBER 2
 '@T6G_MB_LIB.T6G(SCH_1):PAGE406_I38@PURE_QUANTA.PT5161LRS(CHIPS)':
 C_PATH='@t6g_mb_lib.t6g(sch_1):page406_i38@pure_quanta.pt5161lrs(chips)',
 P_PATH='@t6g_mb_lib.t6g(sch_1):page285_i38@pure_quanta.pt5161lrs(chips)',
 PATH='I38',
 DRAWING='@T6G_MB_LIB.T6G(SCH_1):PAGE406',
 PART_TYPE='SMLF',
 MATERIAL='IC',
 PHYS_PAGE='285',
 XY='(-3425,4175)',
 ROT='0',
 VER='2',
 LOCATION='U6011',
 CDS_LIB='pure_quanta',
 CDS_PART_NAME='PT5161LRS-PT5161LRS,SMLF,IC,AJ051610U03',
 PART_NUMBER='AJ051610U03',
 VALUE='PT5161LRS',
 PRIM_FILE='./archive_libs/logical/pt5161lrs/chips/chips.prt';

SECTION_NUMBER 3
 '@T6G_MB_LIB.T6G(SCH_1):PAGE408_I83@PURE_QUANTA.PT5161LRS(CHIPS)':
 C_PATH='@t6g_mb_lib.t6g(sch_1):page408_i83@pure_quanta.pt5161lrs(chips)',
 P_PATH='@t6g_mb_lib.t6g(sch_1):page287_i83@pure_quanta.pt5161lrs(chips)',
 PATH='I83',
 DRAWING='@T6G_MB_LIB.T6G(SCH_1):PAGE408',
 PART_TYPE='SMLF',
 MATERIAL='IC',
 PHYS_PAGE='287',
 XY='(-4375,2350)',
 ROT='0',
 VER='3',
 LOCATION='U6011',
 CDS_LIB='pure_quanta',
 CDS_PART_NAME='PT5161LRS-PT5161LRS,SMLF,IC,AJ051610U03',
 PART_NUMBER='AJ051610U03',
 VALUE='PT5161LRS',
 PRIM_FILE='./archive_libs/logical/pt5161lrs/chips/chips.prt';

SECTION_NUMBER 4
 '@T6G_MB_LIB.T6G(SCH_1):PAGE409_I5@PURE_QUANTA.PT5161LRS(CHIPS)':
 C_PATH='@t6g_mb_lib.t6g(sch_1):page409_i5@pure_quanta.pt5161lrs(chips)',
 P_PATH='@t6g_mb_lib.t6g(sch_1):page288_i5@pure_quanta.pt5161lrs(chips)',
 PATH='I5',
 DRAWING='@T6G_MB_LIB.T6G(SCH_1):PAGE409',
 PART_TYPE='SMLF',
 MATERIAL='IC',
 PHYS_PAGE='288',
 XY='(-6725,4150)',
 ROT='0',
 VER='4',
 LOCATION='U6011',
 CDS_LIB='pure_quanta',
 CDS_PART_NAME='PT5161LRS-PT5161LRS,SMLF,IC,AJ051610U03',
 PART_NUMBER='AJ051610U03',
 VALUE='PT5161LRS',
 PRIM_FILE='./archive_libs/logical/pt5161lrs/chips/chips.prt';

SECTION_NUMBER 5
 '@T6G_MB_LIB.T6G(SCH_1):PAGE409_I17@PURE_QUANTA.PT5161LRS(CHIPS)':
 C_PATH='@t6g_mb_lib.t6g(sch_1):page409_i17@pure_quanta.pt5161lrs(chips)',
 P_PATH='@t6g_mb_lib.t6g(sch_1):page288_i17@pure_quanta.pt5161lrs(chips)',
 PATH='I17',
 DRAWING='@T6G_MB_LIB.T6G(SCH_1):PAGE409',
 PART_TYPE='SMLF',
 MATERIAL='IC',
 PHYS_PAGE='288',
 XY='(-2650,3575)',
 ROT='0',
 VER='5',
 LOCATION='U6011',
 CDS_LIB='pure_quanta',
 CDS_PART_NAME='PT5161LRS-PT5161LRS,SMLF,IC,AJ051610U03',
 PART_NUMBER='AJ051610U03',
 VALUE='PT5161LRS',
 PRIM_FILE='./archive_libs/logical/pt5161lrs/chips/chips.prt';

SECTION_NUMBER 6
 '@T6G_MB_LIB.T6G(SCH_1):PAGE405_I1@PURE_QUANTA.PT5161LRS(CHIPS)':
 C_PATH='@t6g_mb_lib.t6g(sch_1):page405_i1@pure_quanta.pt5161lrs(chips)',
 P_PATH='@t6g_mb_lib.t6g(sch_1):page284_i1@pure_quanta.pt5161lrs(chips)',
 PATH='I1',
 DRAWING='@T6G_MB_LIB.T6G(SCH_1):PAGE405',
 PART_TYPE='SMLF',
 MATERIAL='IC',
 PHYS_PAGE='284',
 XY='(-7750,4425)',
 ROT='0',
 VER='6',
 LOCATION='U6011',
 CDS_LIB='pure_quanta',
 CDS_PART_NAME='PT5161LRS-PT5161LRS,SMLF,IC,AJ051610U03',
 PART_NUMBER='AJ051610U03',
 VALUE='PT5161LRS',
 PRIM_FILE='./archive_libs/logical/pt5161lrs/chips/chips.prt';

SECTION_NUMBER 7
 '@T6G_MB_LIB.T6G(SCH_1):PAGE405_I38@PURE_QUANTA.PT5161LRS(CHIPS)':
 C_PATH='@t6g_mb_lib.t6g(sch_1):page405_i38@pure_quanta.pt5161lrs(chips)',
 P_PATH='@t6g_mb_lib.t6g(sch_1):page284_i38@pure_quanta.pt5161lrs(chips)',
 PATH='I38',
 DRAWING='@T6G_MB_LIB.T6G(SCH_1):PAGE405',
 PART_TYPE='SMLF',
 MATERIAL='IC',
 PHYS_PAGE='284',
 XY='(-3200,4425)',
 ROT='0',
 VER='7',
 LOCATION='U6011',
 CDS_LIB='pure_quanta',
 CDS_PART_NAME='PT5161LRS-PT5161LRS,SMLF,IC,AJ051610U03',
 PART_NUMBER='AJ051610U03',
 VALUE='PT5161LRS',
 PRIM_FILE='./archive_libs/logical/pt5161lrs/chips/chips.prt';

SECTION_NUMBER 8
 '@T6G_MB_LIB.T6G(SCH_1):PAGE404_I1@PURE_QUANTA.PT5161LRS(CHIPS)':
 C_PATH='@t6g_mb_lib.t6g(sch_1):page404_i1@pure_quanta.pt5161lrs(chips)',
 P_PATH='@t6g_mb_lib.t6g(sch_1):page283_i1@pure_quanta.pt5161lrs(chips)',
 PATH='I1',
 DRAWING='@T6G_MB_LIB.T6G(SCH_1):PAGE404',
 PART_TYPE='SMLF',
 MATERIAL='IC',
 PHYS_PAGE='283',
 XY='(-7875,3900)',
 ROT='0',
 VER='8',
 LOCATION='U6011',
 CDS_LIB='pure_quanta',
 CDS_PART_NAME='PT5161LRS-PT5161LRS,SMLF,IC,AJ051610U03',
 PART_NUMBER='AJ051610U03',
 VALUE='PT5161LRS',
 PRIM_FILE='./archive_libs/logical/pt5161lrs/chips/chips.prt';

SECTION_NUMBER 9
 '@T6G_MB_LIB.T6G(SCH_1):PAGE404_I38@PURE_QUANTA.PT5161LRS(CHIPS)':
 C_PATH='@t6g_mb_lib.t6g(sch_1):page404_i38@pure_quanta.pt5161lrs(chips)',
 P_PATH='@t6g_mb_lib.t6g(sch_1):page283_i38@pure_quanta.pt5161lrs(chips)',
 PATH='I38',
 DRAWING='@T6G_MB_LIB.T6G(SCH_1):PAGE404',
 PART_TYPE='SMLF',
 MATERIAL='IC',
 PHYS_PAGE='283',
 XY='(-3250,3850)',
 ROT='0',
 VER='9',
 LOCATION='U6011',
 CDS_LIB='pure_quanta',
 CDS_PART_NAME='PT5161LRS-PT5161LRS,SMLF,IC,AJ051610U03',
 PART_NUMBER='AJ051610U03',
 VALUE='PT5161LRS',
 PRIM_FILE='./archive_libs/logical/pt5161lrs/chips/chips.prt';

SECTION_NUMBER 10
 '@T6G_MB_LIB.T6G(SCH_1):PAGE407_I43@PURE_QUANTA.PT5161LRS(CHIPS)':
 C_PATH='@t6g_mb_lib.t6g(sch_1):page407_i43@pure_quanta.pt5161lrs(chips)',
 P_PATH='@t6g_mb_lib.t6g(sch_1):page286_i43@pure_quanta.pt5161lrs(chips)',
 PATH='I43',
 DRAWING='@T6G_MB_LIB.T6G(SCH_1):PAGE407',
 PART_TYPE='SMLF',
 MATERIAL='IC',
 PHYS_PAGE='286',
 XY='(-7775,4575)',
 ROT='0',
 VER='10',
 LOCATION='U6011',
 CDS_LIB='pure_quanta',
 CDS_PART_NAME='PT5161LRS-PT5161LRS,SMLF,IC,AJ051610U03',
 PART_NUMBER='AJ051610U03',
 VALUE='PT5161LRS',
 PRIM_FILE='./archive_libs/logical/pt5161lrs/chips/chips.prt';

SECTION_NUMBER 11
 '@T6G_MB_LIB.T6G(SCH_1):PAGE407_I142@PURE_QUANTA.PT5161LRS(CHIPS)':
 C_PATH='@t6g_mb_lib.t6g(sch_1):page407_i142@pure_quanta.pt5161lrs(chips)',
 P_PATH='@t6g_mb_lib.t6g(sch_1):page286_i142@pure_quanta.pt5161lrs(chips)',
 PATH='I142',
 DRAWING='@T6G_MB_LIB.T6G(SCH_1):PAGE407',
 PART_TYPE='SMLF',
 MATERIAL='IC',
 PHYS_PAGE='286',
 XY='(-2600,4550)',
 ROT='0',
 VER='11',
 LOCATION='U6011',
 CDS_LIB='pure_quanta',
 CDS_PART_NAME='PT5161LRS-PT5161LRS,SMLF,IC,AJ051610U03',
 PART_NUMBER='AJ051610U03',
 VALUE='PT5161LRS',
 PRIM_FILE='./archive_libs/logical/pt5161lrs/chips/chips.prt';

PART_NAME
 U6012 'PT5161LRS-PT5161LRS,SMLF,IC,AJ051610U03':;

SECTION_NUMBER 1
 '@T6G_MB_LIB.T6G(SCH_1):PAGE417_I1@PURE_QUANTA.PT5161LRS(CHIPS)':
 C_PATH='@t6g_mb_lib.t6g(sch_1):page417_i1@pure_quanta.pt5161lrs(chips)',
 P_PATH='@t6g_mb_lib.t6g(sch_1):page296_i1@pure_quanta.pt5161lrs(chips)',
 PATH='I1',
 DRAWING='@T6G_MB_LIB.T6G(SCH_1):PAGE417',
 PART_TYPE='SMLF',
 MATERIAL='IC',
 PHYS_PAGE='296',
 XY='(-7525,3800)',
 ROT='0',
 VER='1',
 LOCATION='U6012',
 CDS_LIB='pure_quanta',
 CDS_PART_NAME='PT5161LRS-PT5161LRS,SMLF,IC,AJ051610U03',
 PART_NUMBER='AJ051610U03',
 VALUE='PT5161LRS',
 PRIM_FILE='./archive_libs/logical/pt5161lrs/chips/chips.prt';

SECTION_NUMBER 2
 '@T6G_MB_LIB.T6G(SCH_1):PAGE417_I38@PURE_QUANTA.PT5161LRS(CHIPS)':
 C_PATH='@t6g_mb_lib.t6g(sch_1):page417_i38@pure_quanta.pt5161lrs(chips)',
 P_PATH='@t6g_mb_lib.t6g(sch_1):page296_i38@pure_quanta.pt5161lrs(chips)',
 PATH='I38',
 DRAWING='@T6G_MB_LIB.T6G(SCH_1):PAGE417',
 PART_TYPE='SMLF',
 MATERIAL='IC',
 PHYS_PAGE='296',
 XY='(-3075,3825)',
 ROT='0',
 VER='2',
 LOCATION='U6012',
 CDS_LIB='pure_quanta',
 CDS_PART_NAME='PT5161LRS-PT5161LRS,SMLF,IC,AJ051610U03',
 PART_NUMBER='AJ051610U03',
 VALUE='PT5161LRS',
 PRIM_FILE='./archive_libs/logical/pt5161lrs/chips/chips.prt';

SECTION_NUMBER 3
 '@T6G_MB_LIB.T6G(SCH_1):PAGE419_I83@PURE_QUANTA.PT5161LRS(CHIPS)':
 C_PATH='@t6g_mb_lib.t6g(sch_1):page419_i83@pure_quanta.pt5161lrs(chips)',
 P_PATH='@t6g_mb_lib.t6g(sch_1):page298_i83@pure_quanta.pt5161lrs(chips)',
 PATH='I83',
 DRAWING='@T6G_MB_LIB.T6G(SCH_1):PAGE419',
 PART_TYPE='SMLF',
 MATERIAL='IC',
 PHYS_PAGE='298',
 XY='(-4400,2250)',
 ROT='0',
 VER='3',
 LOCATION='U6012',
 CDS_LIB='pure_quanta',
 CDS_PART_NAME='PT5161LRS-PT5161LRS,SMLF,IC,AJ051610U03',
 PART_NUMBER='AJ051610U03',
 VALUE='PT5161LRS',
 PRIM_FILE='./archive_libs/logical/pt5161lrs/chips/chips.prt';

SECTION_NUMBER 4
 '@T6G_MB_LIB.T6G(SCH_1):PAGE420_I6@PURE_QUANTA.PT5161LRS(CHIPS)':
 C_PATH='@t6g_mb_lib.t6g(sch_1):page420_i6@pure_quanta.pt5161lrs(chips)',
 P_PATH='@t6g_mb_lib.t6g(sch_1):page299_i6@pure_quanta.pt5161lrs(chips)',
 PATH='I6',
 DRAWING='@T6G_MB_LIB.T6G(SCH_1):PAGE420',
 PART_TYPE='SMLF',
 MATERIAL='IC',
 PHYS_PAGE='299',
 XY='(-6525,3975)',
 ROT='0',
 VER='4',
 LOCATION='U6012',
 CDS_LIB='pure_quanta',
 CDS_PART_NAME='PT5161LRS-PT5161LRS,SMLF,IC,AJ051610U03',
 PART_NUMBER='AJ051610U03',
 VALUE='PT5161LRS',
 PRIM_FILE='./archive_libs/logical/pt5161lrs/chips/chips.prt';

SECTION_NUMBER 5
 '@T6G_MB_LIB.T6G(SCH_1):PAGE420_I17@PURE_QUANTA.PT5161LRS(CHIPS)':
 C_PATH='@t6g_mb_lib.t6g(sch_1):page420_i17@pure_quanta.pt5161lrs(chips)',
 P_PATH='@t6g_mb_lib.t6g(sch_1):page299_i17@pure_quanta.pt5161lrs(chips)',
 PATH='I17',
 DRAWING='@T6G_MB_LIB.T6G(SCH_1):PAGE420',
 PART_TYPE='SMLF',
 MATERIAL='IC',
 PHYS_PAGE='299',
 XY='(-2450,3400)',
 ROT='0',
 VER='5',
 LOCATION='U6012',
 CDS_LIB='pure_quanta',
 CDS_PART_NAME='PT5161LRS-PT5161LRS,SMLF,IC,AJ051610U03',
 PART_NUMBER='AJ051610U03',
 VALUE='PT5161LRS',
 PRIM_FILE='./archive_libs/logical/pt5161lrs/chips/chips.prt';

SECTION_NUMBER 6
 '@T6G_MB_LIB.T6G(SCH_1):PAGE416_I1@PURE_QUANTA.PT5161LRS(CHIPS)':
 C_PATH='@t6g_mb_lib.t6g(sch_1):page416_i1@pure_quanta.pt5161lrs(chips)',
 P_PATH='@t6g_mb_lib.t6g(sch_1):page295_i1@pure_quanta.pt5161lrs(chips)',
 PATH='I1',
 DRAWING='@T6G_MB_LIB.T6G(SCH_1):PAGE416',
 PART_TYPE='SMLF',
 MATERIAL='IC',
 PHYS_PAGE='295',
 XY='(-7750,4400)',
 ROT='0',
 VER='6',
 LOCATION='U6012',
 CDS_LIB='pure_quanta',
 CDS_PART_NAME='PT5161LRS-PT5161LRS,SMLF,IC,AJ051610U03',
 PART_NUMBER='AJ051610U03',
 VALUE='PT5161LRS',
 PRIM_FILE='./archive_libs/logical/pt5161lrs/chips/chips.prt';

SECTION_NUMBER 7
 '@T6G_MB_LIB.T6G(SCH_1):PAGE416_I38@PURE_QUANTA.PT5161LRS(CHIPS)':
 C_PATH='@t6g_mb_lib.t6g(sch_1):page416_i38@pure_quanta.pt5161lrs(chips)',
 P_PATH='@t6g_mb_lib.t6g(sch_1):page295_i38@pure_quanta.pt5161lrs(chips)',
 PATH='I38',
 DRAWING='@T6G_MB_LIB.T6G(SCH_1):PAGE416',
 PART_TYPE='SMLF',
 MATERIAL='IC',
 PHYS_PAGE='295',
 XY='(-3225,4350)',
 ROT='0',
 VER='7',
 LOCATION='U6012',
 CDS_LIB='pure_quanta',
 CDS_PART_NAME='PT5161LRS-PT5161LRS,SMLF,IC,AJ051610U03',
 PART_NUMBER='AJ051610U03',
 VALUE='PT5161LRS',
 PRIM_FILE='./archive_libs/logical/pt5161lrs/chips/chips.prt';

SECTION_NUMBER 8
 '@T6G_MB_LIB.T6G(SCH_1):PAGE415_I38@PURE_QUANTA.PT5161LRS(CHIPS)':
 C_PATH='@t6g_mb_lib.t6g(sch_1):page415_i38@pure_quanta.pt5161lrs(chips)',
 P_PATH='@t6g_mb_lib.t6g(sch_1):page294_i38@pure_quanta.pt5161lrs(chips)',
 PATH='I38',
 DRAWING='@T6G_MB_LIB.T6G(SCH_1):PAGE415',
 PART_TYPE='SMLF',
 MATERIAL='IC',
 PHYS_PAGE='294',
 XY='(-7975,3825)',
 ROT='0',
 VER='8',
 LOCATION='U6012',
 CDS_LIB='pure_quanta',
 CDS_PART_NAME='PT5161LRS-PT5161LRS,SMLF,IC,AJ051610U03',
 PART_NUMBER='AJ051610U03',
 VALUE='PT5161LRS',
 PRIM_FILE='./archive_libs/logical/pt5161lrs/chips/chips.prt';

SECTION_NUMBER 9
 '@T6G_MB_LIB.T6G(SCH_1):PAGE415_I37@PURE_QUANTA.PT5161LRS(CHIPS)':
 C_PATH='@t6g_mb_lib.t6g(sch_1):page415_i37@pure_quanta.pt5161lrs(chips)',
 P_PATH='@t6g_mb_lib.t6g(sch_1):page294_i37@pure_quanta.pt5161lrs(chips)',
 PATH='I37',
 DRAWING='@T6G_MB_LIB.T6G(SCH_1):PAGE415',
 PART_TYPE='SMLF',
 MATERIAL='IC',
 PHYS_PAGE='294',
 XY='(-3350,3775)',
 ROT='0',
 VER='9',
 LOCATION='U6012',
 CDS_LIB='pure_quanta',
 CDS_PART_NAME='PT5161LRS-PT5161LRS,SMLF,IC,AJ051610U03',
 PART_NUMBER='AJ051610U03',
 VALUE='PT5161LRS',
 PRIM_FILE='./archive_libs/logical/pt5161lrs/chips/chips.prt';

SECTION_NUMBER 10
 '@T6G_MB_LIB.T6G(SCH_1):PAGE418_I47@PURE_QUANTA.PT5161LRS(CHIPS)':
 C_PATH='@t6g_mb_lib.t6g(sch_1):page418_i47@pure_quanta.pt5161lrs(chips)',
 P_PATH='@t6g_mb_lib.t6g(sch_1):page297_i47@pure_quanta.pt5161lrs(chips)',
 PATH='I47',
 DRAWING='@T6G_MB_LIB.T6G(SCH_1):PAGE418',
 PART_TYPE='SMLF',
 MATERIAL='IC',
 PHYS_PAGE='297',
 XY='(-7825,4375)',
 ROT='0',
 VER='10',
 LOCATION='U6012',
 CDS_LIB='pure_quanta',
 CDS_PART_NAME='PT5161LRS-PT5161LRS,SMLF,IC,AJ051610U03',
 PART_NUMBER='AJ051610U03',
 VALUE='PT5161LRS',
 PRIM_FILE='./archive_libs/logical/pt5161lrs/chips/chips.prt';

SECTION_NUMBER 11
 '@T6G_MB_LIB.T6G(SCH_1):PAGE418_I142@PURE_QUANTA.PT5161LRS(CHIPS)':
 C_PATH='@t6g_mb_lib.t6g(sch_1):page418_i142@pure_quanta.pt5161lrs(chips)',
 P_PATH='@t6g_mb_lib.t6g(sch_1):page297_i142@pure_quanta.pt5161lrs(chips)',
 PATH='I142',
 DRAWING='@T6G_MB_LIB.T6G(SCH_1):PAGE418',
 PART_TYPE='SMLF',
 MATERIAL='IC',
 PHYS_PAGE='297',
 XY='(-2650,4350)',
 ROT='0',
 VER='11',
 LOCATION='U6012',
 CDS_LIB='pure_quanta',
 CDS_PART_NAME='PT5161LRS-PT5161LRS,SMLF,IC,AJ051610U03',
 PART_NUMBER='AJ051610U03',
 VALUE='PT5161LRS',
 PRIM_FILE='./archive_libs/logical/pt5161lrs/chips/chips.prt';

PART_NAME
 U6013 'PT5161LRS-PT5161LRS,SMLF,IC,AJ051610U03':;

SECTION_NUMBER 1
 '@T6G_MB_LIB.T6G(SCH_1):PAGE428_I1@PURE_QUANTA.PT5161LRS(CHIPS)':
 C_PATH='@t6g_mb_lib.t6g(sch_1):page428_i1@pure_quanta.pt5161lrs(chips)',
 P_PATH='@t6g_mb_lib.t6g(sch_1):page307_i1@pure_quanta.pt5161lrs(chips)',
 PATH='I1',
 DRAWING='@T6G_MB_LIB.T6G(SCH_1):PAGE428',
 PART_TYPE='SMLF',
 MATERIAL='IC',
 PHYS_PAGE='307',
 XY='(-7700,3775)',
 ROT='0',
 VER='1',
 LOCATION='U6013',
 CDS_LIB='pure_quanta',
 CDS_PART_NAME='PT5161LRS-PT5161LRS,SMLF,IC,AJ051610U03',
 PART_NUMBER='AJ051610U03',
 VALUE='PT5161LRS',
 PRIM_FILE='./archive_libs/logical/pt5161lrs/chips/chips.prt';

SECTION_NUMBER 2
 '@T6G_MB_LIB.T6G(SCH_1):PAGE428_I38@PURE_QUANTA.PT5161LRS(CHIPS)':
 C_PATH='@t6g_mb_lib.t6g(sch_1):page428_i38@pure_quanta.pt5161lrs(chips)',
 P_PATH='@t6g_mb_lib.t6g(sch_1):page307_i38@pure_quanta.pt5161lrs(chips)',
 PATH='I38',
 DRAWING='@T6G_MB_LIB.T6G(SCH_1):PAGE428',
 PART_TYPE='SMLF',
 MATERIAL='IC',
 PHYS_PAGE='307',
 XY='(-3250,3800)',
 ROT='0',
 VER='2',
 LOCATION='U6013',
 CDS_LIB='pure_quanta',
 CDS_PART_NAME='PT5161LRS-PT5161LRS,SMLF,IC,AJ051610U03',
 PART_NUMBER='AJ051610U03',
 VALUE='PT5161LRS',
 PRIM_FILE='./archive_libs/logical/pt5161lrs/chips/chips.prt';

SECTION_NUMBER 3
 '@T6G_MB_LIB.T6G(SCH_1):PAGE430_I83@PURE_QUANTA.PT5161LRS(CHIPS)':
 C_PATH='@t6g_mb_lib.t6g(sch_1):page430_i83@pure_quanta.pt5161lrs(chips)',
 P_PATH='@t6g_mb_lib.t6g(sch_1):page309_i83@pure_quanta.pt5161lrs(chips)',
 PATH='I83',
 DRAWING='@T6G_MB_LIB.T6G(SCH_1):PAGE430',
 PART_TYPE='SMLF',
 MATERIAL='IC',
 PHYS_PAGE='309',
 XY='(-4375,2350)',
 ROT='0',
 VER='3',
 LOCATION='U6013',
 CDS_LIB='pure_quanta',
 CDS_PART_NAME='PT5161LRS-PT5161LRS,SMLF,IC,AJ051610U03',
 PART_NUMBER='AJ051610U03',
 VALUE='PT5161LRS',
 PRIM_FILE='./archive_libs/logical/pt5161lrs/chips/chips.prt';

SECTION_NUMBER 4
 '@T6G_MB_LIB.T6G(SCH_1):PAGE431_I6@PURE_QUANTA.PT5161LRS(CHIPS)':
 C_PATH='@t6g_mb_lib.t6g(sch_1):page431_i6@pure_quanta.pt5161lrs(chips)',
 P_PATH='@t6g_mb_lib.t6g(sch_1):page310_i6@pure_quanta.pt5161lrs(chips)',
 PATH='I6',
 DRAWING='@T6G_MB_LIB.T6G(SCH_1):PAGE431',
 PART_TYPE='SMLF',
 MATERIAL='IC',
 PHYS_PAGE='310',
 XY='(-6400,4100)',
 ROT='0',
 VER='4',
 LOCATION='U6013',
 CDS_LIB='pure_quanta',
 CDS_PART_NAME='PT5161LRS-PT5161LRS,SMLF,IC,AJ051610U03',
 PART_NUMBER='AJ051610U03',
 VALUE='PT5161LRS',
 PRIM_FILE='./archive_libs/logical/pt5161lrs/chips/chips.prt';

SECTION_NUMBER 5
 '@T6G_MB_LIB.T6G(SCH_1):PAGE431_I17@PURE_QUANTA.PT5161LRS(CHIPS)':
 C_PATH='@t6g_mb_lib.t6g(sch_1):page431_i17@pure_quanta.pt5161lrs(chips)',
 P_PATH='@t6g_mb_lib.t6g(sch_1):page310_i17@pure_quanta.pt5161lrs(chips)',
 PATH='I17',
 DRAWING='@T6G_MB_LIB.T6G(SCH_1):PAGE431',
 PART_TYPE='SMLF',
 MATERIAL='IC',
 PHYS_PAGE='310',
 XY='(-2325,3525)',
 ROT='0',
 VER='5',
 LOCATION='U6013',
 CDS_LIB='pure_quanta',
 CDS_PART_NAME='PT5161LRS-PT5161LRS,SMLF,IC,AJ051610U03',
 PART_NUMBER='AJ051610U03',
 VALUE='PT5161LRS',
 PRIM_FILE='./archive_libs/logical/pt5161lrs/chips/chips.prt';

SECTION_NUMBER 6
 '@T6G_MB_LIB.T6G(SCH_1):PAGE427_I1@PURE_QUANTA.PT5161LRS(CHIPS)':
 C_PATH='@t6g_mb_lib.t6g(sch_1):page427_i1@pure_quanta.pt5161lrs(chips)',
 P_PATH='@t6g_mb_lib.t6g(sch_1):page306_i1@pure_quanta.pt5161lrs(chips)',
 PATH='I1',
 DRAWING='@T6G_MB_LIB.T6G(SCH_1):PAGE427',
 PART_TYPE='SMLF',
 MATERIAL='IC',
 PHYS_PAGE='306',
 XY='(-7675,4375)',
 ROT='0',
 VER='6',
 LOCATION='U6013',
 CDS_LIB='pure_quanta',
 CDS_PART_NAME='PT5161LRS-PT5161LRS,SMLF,IC,AJ051610U03',
 PART_NUMBER='AJ051610U03',
 VALUE='PT5161LRS',
 PRIM_FILE='./archive_libs/logical/pt5161lrs/chips/chips.prt';

SECTION_NUMBER 7
 '@T6G_MB_LIB.T6G(SCH_1):PAGE427_I38@PURE_QUANTA.PT5161LRS(CHIPS)':
 C_PATH='@t6g_mb_lib.t6g(sch_1):page427_i38@pure_quanta.pt5161lrs(chips)',
 P_PATH='@t6g_mb_lib.t6g(sch_1):page306_i38@pure_quanta.pt5161lrs(chips)',
 PATH='I38',
 DRAWING='@T6G_MB_LIB.T6G(SCH_1):PAGE427',
 PART_TYPE='SMLF',
 MATERIAL='IC',
 PHYS_PAGE='306',
 XY='(-3175,4325)',
 ROT='0',
 VER='7',
 LOCATION='U6013',
 CDS_LIB='pure_quanta',
 CDS_PART_NAME='PT5161LRS-PT5161LRS,SMLF,IC,AJ051610U03',
 PART_NUMBER='AJ051610U03',
 VALUE='PT5161LRS',
 PRIM_FILE='./archive_libs/logical/pt5161lrs/chips/chips.prt';

SECTION_NUMBER 8
 '@T6G_MB_LIB.T6G(SCH_1):PAGE426_I1@PURE_QUANTA.PT5161LRS(CHIPS)':
 C_PATH='@t6g_mb_lib.t6g(sch_1):page426_i1@pure_quanta.pt5161lrs(chips)',
 P_PATH='@t6g_mb_lib.t6g(sch_1):page305_i1@pure_quanta.pt5161lrs(chips)',
 PATH='I1',
 DRAWING='@T6G_MB_LIB.T6G(SCH_1):PAGE426',
 PART_TYPE='SMLF',
 MATERIAL='IC',
 PHYS_PAGE='305',
 XY='(-7825,4175)',
 ROT='0',
 VER='8',
 LOCATION='U6013',
 CDS_LIB='pure_quanta',
 CDS_PART_NAME='PT5161LRS-PT5161LRS,SMLF,IC,AJ051610U03',
 PART_NUMBER='AJ051610U03',
 VALUE='PT5161LRS',
 PRIM_FILE='./archive_libs/logical/pt5161lrs/chips/chips.prt';

SECTION_NUMBER 9
 '@T6G_MB_LIB.T6G(SCH_1):PAGE426_I38@PURE_QUANTA.PT5161LRS(CHIPS)':
 C_PATH='@t6g_mb_lib.t6g(sch_1):page426_i38@pure_quanta.pt5161lrs(chips)',
 P_PATH='@t6g_mb_lib.t6g(sch_1):page305_i38@pure_quanta.pt5161lrs(chips)',
 PATH='I38',
 DRAWING='@T6G_MB_LIB.T6G(SCH_1):PAGE426',
 PART_TYPE='SMLF',
 MATERIAL='IC',
 PHYS_PAGE='305',
 XY='(-3200,4125)',
 ROT='0',
 VER='9',
 LOCATION='U6013',
 CDS_LIB='pure_quanta',
 CDS_PART_NAME='PT5161LRS-PT5161LRS,SMLF,IC,AJ051610U03',
 PART_NUMBER='AJ051610U03',
 VALUE='PT5161LRS',
 PRIM_FILE='./archive_libs/logical/pt5161lrs/chips/chips.prt';

SECTION_NUMBER 10
 '@T6G_MB_LIB.T6G(SCH_1):PAGE429_I51@PURE_QUANTA.PT5161LRS(CHIPS)':
 C_PATH='@t6g_mb_lib.t6g(sch_1):page429_i51@pure_quanta.pt5161lrs(chips)',
 P_PATH='@t6g_mb_lib.t6g(sch_1):page308_i51@pure_quanta.pt5161lrs(chips)',
 PATH='I51',
 DRAWING='@T6G_MB_LIB.T6G(SCH_1):PAGE429',
 PART_TYPE='SMLF',
 MATERIAL='IC',
 PHYS_PAGE='308',
 XY='(-7775,4525)',
 ROT='0',
 VER='10',
 LOCATION='U6013',
 CDS_LIB='pure_quanta',
 CDS_PART_NAME='PT5161LRS-PT5161LRS,SMLF,IC,AJ051610U03',
 PART_NUMBER='AJ051610U03',
 VALUE='PT5161LRS',
 PRIM_FILE='./archive_libs/logical/pt5161lrs/chips/chips.prt';

SECTION_NUMBER 11
 '@T6G_MB_LIB.T6G(SCH_1):PAGE429_I142@PURE_QUANTA.PT5161LRS(CHIPS)':
 C_PATH='@t6g_mb_lib.t6g(sch_1):page429_i142@pure_quanta.pt5161lrs(chips)',
 P_PATH='@t6g_mb_lib.t6g(sch_1):page308_i142@pure_quanta.pt5161lrs(chips)',
 PATH='I142',
 DRAWING='@T6G_MB_LIB.T6G(SCH_1):PAGE429',
 PART_TYPE='SMLF',
 MATERIAL='IC',
 PHYS_PAGE='308',
 XY='(-2600,4500)',
 ROT='0',
 VER='11',
 LOCATION='U6013',
 CDS_LIB='pure_quanta',
 CDS_PART_NAME='PT5161LRS-PT5161LRS,SMLF,IC,AJ051610U03',
 PART_NUMBER='AJ051610U03',
 VALUE='PT5161LRS',
 PRIM_FILE='./archive_libs/logical/pt5161lrs/chips/chips.prt';

PART_NAME
 U6014 'PT5161LRS-PT5161LRS,SMLF,IC,AJ051610U03':;

SECTION_NUMBER 1
 '@T6G_MB_LIB.T6G(SCH_1):PAGE402_I1@PURE_QUANTA.PT5161LRS(CHIPS)':
 C_PATH='@t6g_mb_lib.t6g(sch_1):page402_i1@pure_quanta.pt5161lrs(chips)',
 P_PATH='@t6g_mb_lib.t6g(sch_1):page318_i1@pure_quanta.pt5161lrs(chips)',
 PATH='I1',
 DRAWING='@T6G_MB_LIB.T6G(SCH_1):PAGE402',
 PART_TYPE='SMLF',
 MATERIAL='IC',
 PHYS_PAGE='318',
 XY='(-7675,3775)',
 ROT='0',
 VER='1',
 LOCATION='U6014',
 CDS_LIB='pure_quanta',
 CDS_PART_NAME='PT5161LRS-PT5161LRS,SMLF,IC,AJ051610U03',
 PART_NUMBER='AJ051610U03',
 VALUE='PT5161LRS',
 PRIM_FILE='./archive_libs/logical/pt5161lrs/chips/chips.prt';

SECTION_NUMBER 2
 '@T6G_MB_LIB.T6G(SCH_1):PAGE402_I38@PURE_QUANTA.PT5161LRS(CHIPS)':
 C_PATH='@t6g_mb_lib.t6g(sch_1):page402_i38@pure_quanta.pt5161lrs(chips)',
 P_PATH='@t6g_mb_lib.t6g(sch_1):page318_i38@pure_quanta.pt5161lrs(chips)',
 PATH='I38',
 DRAWING='@T6G_MB_LIB.T6G(SCH_1):PAGE402',
 PART_TYPE='SMLF',
 MATERIAL='IC',
 PHYS_PAGE='318',
 XY='(-3225,3800)',
 ROT='0',
 VER='2',
 LOCATION='U6014',
 CDS_LIB='pure_quanta',
 CDS_PART_NAME='PT5161LRS-PT5161LRS,SMLF,IC,AJ051610U03',
 PART_NUMBER='AJ051610U03',
 VALUE='PT5161LRS',
 PRIM_FILE='./archive_libs/logical/pt5161lrs/chips/chips.prt';

SECTION_NUMBER 3
 '@T6G_MB_LIB.T6G(SCH_1):PAGE401_I1@PURE_QUANTA.PT5161LRS(CHIPS)':
 C_PATH='@t6g_mb_lib.t6g(sch_1):page401_i1@pure_quanta.pt5161lrs(chips)',
 P_PATH='@t6g_mb_lib.t6g(sch_1):page320_i1@pure_quanta.pt5161lrs(chips)',
 PATH='I1',
 DRAWING='@T6G_MB_LIB.T6G(SCH_1):PAGE401',
 PART_TYPE='SMLF',
 MATERIAL='IC',
 PHYS_PAGE='320',
 XY='(-4375,2450)',
 ROT='0',
 VER='3',
 LOCATION='U6014',
 CDS_LIB='pure_quanta',
 CDS_PART_NAME='PT5161LRS-PT5161LRS,SMLF,IC,AJ051610U03',
 PART_NUMBER='AJ051610U03',
 VALUE='PT5161LRS',
 PRIM_FILE='./archive_libs/logical/pt5161lrs/chips/chips.prt';

SECTION_NUMBER 4
 '@T6G_MB_LIB.T6G(SCH_1):PAGE400_I1@PURE_QUANTA.PT5161LRS(CHIPS)':
 C_PATH='@t6g_mb_lib.t6g(sch_1):page400_i1@pure_quanta.pt5161lrs(chips)',
 P_PATH='@t6g_mb_lib.t6g(sch_1):page321_i1@pure_quanta.pt5161lrs(chips)',
 PATH='I1',
 DRAWING='@T6G_MB_LIB.T6G(SCH_1):PAGE400',
 PART_TYPE='SMLF',
 MATERIAL='IC',
 PHYS_PAGE='321',
 XY='(-5925,4450)',
 ROT='0',
 VER='4',
 LOCATION='U6014',
 CDS_LIB='pure_quanta',
 CDS_PART_NAME='PT5161LRS-PT5161LRS,SMLF,IC,AJ051610U03',
 PART_NUMBER='AJ051610U03',
 VALUE='PT5161LRS',
 PRIM_FILE='./archive_libs/logical/pt5161lrs/chips/chips.prt';

SECTION_NUMBER 5
 '@T6G_MB_LIB.T6G(SCH_1):PAGE400_I2@PURE_QUANTA.PT5161LRS(CHIPS)':
 C_PATH='@t6g_mb_lib.t6g(sch_1):page400_i2@pure_quanta.pt5161lrs(chips)',
 P_PATH='@t6g_mb_lib.t6g(sch_1):page321_i2@pure_quanta.pt5161lrs(chips)',
 PATH='I2',
 DRAWING='@T6G_MB_LIB.T6G(SCH_1):PAGE400',
 PART_TYPE='SMLF',
 MATERIAL='IC',
 PHYS_PAGE='321',
 XY='(-1850,3875)',
 ROT='0',
 VER='5',
 LOCATION='U6014',
 CDS_LIB='pure_quanta',
 CDS_PART_NAME='PT5161LRS-PT5161LRS,SMLF,IC,AJ051610U03',
 PART_NUMBER='AJ051610U03',
 VALUE='PT5161LRS',
 PRIM_FILE='./archive_libs/logical/pt5161lrs/chips/chips.prt';

SECTION_NUMBER 6
 '@T6G_MB_LIB.T6G(SCH_1):PAGE438_I1@PURE_QUANTA.PT5161LRS(CHIPS)':
 C_PATH='@t6g_mb_lib.t6g(sch_1):page438_i1@pure_quanta.pt5161lrs(chips)',
 P_PATH='@t6g_mb_lib.t6g(sch_1):page317_i1@pure_quanta.pt5161lrs(chips)',
 PATH='I1',
 DRAWING='@T6G_MB_LIB.T6G(SCH_1):PAGE438',
 PART_TYPE='SMLF',
 MATERIAL='IC',
 PHYS_PAGE='317',
 XY='(-7575,4475)',
 ROT='0',
 VER='6',
 LOCATION='U6014',
 CDS_LIB='pure_quanta',
 CDS_PART_NAME='PT5161LRS-PT5161LRS,SMLF,IC,AJ051610U03',
 PART_NUMBER='AJ051610U03',
 VALUE='PT5161LRS',
 PRIM_FILE='./archive_libs/logical/pt5161lrs/chips/chips.prt';

SECTION_NUMBER 7
 '@T6G_MB_LIB.T6G(SCH_1):PAGE438_I38@PURE_QUANTA.PT5161LRS(CHIPS)':
 C_PATH='@t6g_mb_lib.t6g(sch_1):page438_i38@pure_quanta.pt5161lrs(chips)',
 P_PATH='@t6g_mb_lib.t6g(sch_1):page317_i38@pure_quanta.pt5161lrs(chips)',
 PATH='I38',
 DRAWING='@T6G_MB_LIB.T6G(SCH_1):PAGE438',
 PART_TYPE='SMLF',
 MATERIAL='IC',
 PHYS_PAGE='317',
 XY='(-3050,4550)',
 ROT='0',
 VER='7',
 LOCATION='U6014',
 CDS_LIB='pure_quanta',
 CDS_PART_NAME='PT5161LRS-PT5161LRS,SMLF,IC,AJ051610U03',
 PART_NUMBER='AJ051610U03',
 VALUE='PT5161LRS',
 PRIM_FILE='./archive_libs/logical/pt5161lrs/chips/chips.prt';

SECTION_NUMBER 8
 '@T6G_MB_LIB.T6G(SCH_1):PAGE437_I1@PURE_QUANTA.PT5161LRS(CHIPS)':
 C_PATH='@t6g_mb_lib.t6g(sch_1):page437_i1@pure_quanta.pt5161lrs(chips)',
 P_PATH='@t6g_mb_lib.t6g(sch_1):page316_i1@pure_quanta.pt5161lrs(chips)',
 PATH='I1',
 DRAWING='@T6G_MB_LIB.T6G(SCH_1):PAGE437',
 PART_TYPE='SMLF',
 MATERIAL='IC',
 PHYS_PAGE='316',
 XY='(-7550,4100)',
 ROT='0',
 VER='8',
 LOCATION='U6014',
 CDS_LIB='pure_quanta',
 CDS_PART_NAME='PT5161LRS-PT5161LRS,SMLF,IC,AJ051610U03',
 PART_NUMBER='AJ051610U03',
 VALUE='PT5161LRS',
 PRIM_FILE='./archive_libs/logical/pt5161lrs/chips/chips.prt';

SECTION_NUMBER 9
 '@T6G_MB_LIB.T6G(SCH_1):PAGE437_I38@PURE_QUANTA.PT5161LRS(CHIPS)':
 C_PATH='@t6g_mb_lib.t6g(sch_1):page437_i38@pure_quanta.pt5161lrs(chips)',
 P_PATH='@t6g_mb_lib.t6g(sch_1):page316_i38@pure_quanta.pt5161lrs(chips)',
 PATH='I38',
 DRAWING='@T6G_MB_LIB.T6G(SCH_1):PAGE437',
 PART_TYPE='SMLF',
 MATERIAL='IC',
 PHYS_PAGE='316',
 XY='(-2925,4050)',
 ROT='0',
 VER='9',
 LOCATION='U6014',
 CDS_LIB='pure_quanta',
 CDS_PART_NAME='PT5161LRS-PT5161LRS,SMLF,IC,AJ051610U03',
 PART_NUMBER='AJ051610U03',
 VALUE='PT5161LRS',
 PRIM_FILE='./archive_libs/logical/pt5161lrs/chips/chips.prt';

SECTION_NUMBER 10
 '@T6G_MB_LIB.T6G(SCH_1):PAGE439_I43@PURE_QUANTA.PT5161LRS(CHIPS)':
 C_PATH='@t6g_mb_lib.t6g(sch_1):page439_i43@pure_quanta.pt5161lrs(chips)',
 P_PATH='@t6g_mb_lib.t6g(sch_1):page319_i43@pure_quanta.pt5161lrs(chips)',
 PATH='I43',
 DRAWING='@T6G_MB_LIB.T6G(SCH_1):PAGE439',
 PART_TYPE='SMLF',
 MATERIAL='IC',
 PHYS_PAGE='319',
 XY='(-7700,4475)',
 ROT='0',
 VER='10',
 LOCATION='U6014',
 CDS_LIB='pure_quanta',
 CDS_PART_NAME='PT5161LRS-PT5161LRS,SMLF,IC,AJ051610U03',
 PART_NUMBER='AJ051610U03',
 VALUE='PT5161LRS',
 PRIM_FILE='./archive_libs/logical/pt5161lrs/chips/chips.prt';

SECTION_NUMBER 11
 '@T6G_MB_LIB.T6G(SCH_1):PAGE439_I142@PURE_QUANTA.PT5161LRS(CHIPS)':
 C_PATH='@t6g_mb_lib.t6g(sch_1):page439_i142@pure_quanta.pt5161lrs(chips)',
 P_PATH='@t6g_mb_lib.t6g(sch_1):page319_i142@pure_quanta.pt5161lrs(chips)',
 PATH='I142',
 DRAWING='@T6G_MB_LIB.T6G(SCH_1):PAGE439',
 PART_TYPE='SMLF',
 MATERIAL='IC',
 PHYS_PAGE='319',
 XY='(-2525,4450)',
 ROT='0',
 VER='11',
 LOCATION='U6014',
 CDS_LIB='pure_quanta',
 CDS_PART_NAME='PT5161LRS-PT5161LRS,SMLF,IC,AJ051610U03',
 PART_NUMBER='AJ051610U03',
 VALUE='PT5161LRS',
 PRIM_FILE='./archive_libs/logical/pt5161lrs/chips/chips.prt';

PART_NAME
 U6015 'PT5161LRS-PT5161LRS,SMLF,IC,AJ051610U03':;

SECTION_NUMBER 1
 '@T6G_MB_LIB.T6G(SCH_1):PAGE394_I1@PURE_QUANTA.PT5161LRS(CHIPS)':
 C_PATH='@t6g_mb_lib.t6g(sch_1):page394_i1@pure_quanta.pt5161lrs(chips)',
 P_PATH='@t6g_mb_lib.t6g(sch_1):page329_i1@pure_quanta.pt5161lrs(chips)',
 PATH='I1',
 DRAWING='@T6G_MB_LIB.T6G(SCH_1):PAGE394',
 PART_TYPE='SMLF',
 MATERIAL='IC',
 PHYS_PAGE='329',
 XY='(-7525,3875)',
 ROT='0',
 VER='1',
 LOCATION='U6015',
 CDS_LIB='pure_quanta',
 CDS_PART_NAME='PT5161LRS-PT5161LRS,SMLF,IC,AJ051610U03',
 PART_NUMBER='AJ051610U03',
 VALUE='PT5161LRS',
 PRIM_FILE='./archive_libs/logical/pt5161lrs/chips/chips.prt';

SECTION_NUMBER 2
 '@T6G_MB_LIB.T6G(SCH_1):PAGE394_I38@PURE_QUANTA.PT5161LRS(CHIPS)':
 C_PATH='@t6g_mb_lib.t6g(sch_1):page394_i38@pure_quanta.pt5161lrs(chips)',
 P_PATH='@t6g_mb_lib.t6g(sch_1):page329_i38@pure_quanta.pt5161lrs(chips)',
 PATH='I38',
 DRAWING='@T6G_MB_LIB.T6G(SCH_1):PAGE394',
 PART_TYPE='SMLF',
 MATERIAL='IC',
 PHYS_PAGE='329',
 XY='(-3075,3900)',
 ROT='0',
 VER='2',
 LOCATION='U6015',
 CDS_LIB='pure_quanta',
 CDS_PART_NAME='PT5161LRS-PT5161LRS,SMLF,IC,AJ051610U03',
 PART_NUMBER='AJ051610U03',
 VALUE='PT5161LRS',
 PRIM_FILE='./archive_libs/logical/pt5161lrs/chips/chips.prt';

SECTION_NUMBER 3
 '@T6G_MB_LIB.T6G(SCH_1):PAGE392_I47@PURE_QUANTA.PT5161LRS(CHIPS)':
 C_PATH='@t6g_mb_lib.t6g(sch_1):page392_i47@pure_quanta.pt5161lrs(chips)',
 P_PATH='@t6g_mb_lib.t6g(sch_1):page331_i47@pure_quanta.pt5161lrs(chips)',
 PATH='I47',
 DRAWING='@T6G_MB_LIB.T6G(SCH_1):PAGE392',
 PART_TYPE='SMLF',
 MATERIAL='IC',
 PHYS_PAGE='331',
 XY='(-4225,2200)',
 ROT='0',
 VER='3',
 LOCATION='U6015',
 CDS_LIB='pure_quanta',
 CDS_PART_NAME='PT5161LRS-PT5161LRS,SMLF,IC,AJ051610U03',
 PART_NUMBER='AJ051610U03',
 VALUE='PT5161LRS',
 PRIM_FILE='./archive_libs/logical/pt5161lrs/chips/chips.prt';

SECTION_NUMBER 4
 '@T6G_MB_LIB.T6G(SCH_1):PAGE391_I5@PURE_QUANTA.PT5161LRS(CHIPS)':
 C_PATH='@t6g_mb_lib.t6g(sch_1):page391_i5@pure_quanta.pt5161lrs(chips)',
 P_PATH='@t6g_mb_lib.t6g(sch_1):page332_i5@pure_quanta.pt5161lrs(chips)',
 PATH='I5',
 DRAWING='@T6G_MB_LIB.T6G(SCH_1):PAGE391',
 PART_TYPE='SMLF',
 MATERIAL='IC',
 PHYS_PAGE='332',
 XY='(-6325,4175)',
 ROT='0',
 VER='4',
 LOCATION='U6015',
 CDS_LIB='pure_quanta',
 CDS_PART_NAME='PT5161LRS-PT5161LRS,SMLF,IC,AJ051610U03',
 PART_NUMBER='AJ051610U03',
 VALUE='PT5161LRS',
 PRIM_FILE='./archive_libs/logical/pt5161lrs/chips/chips.prt';

SECTION_NUMBER 5
 '@T6G_MB_LIB.T6G(SCH_1):PAGE391_I19@PURE_QUANTA.PT5161LRS(CHIPS)':
 C_PATH='@t6g_mb_lib.t6g(sch_1):page391_i19@pure_quanta.pt5161lrs(chips)',
 P_PATH='@t6g_mb_lib.t6g(sch_1):page332_i19@pure_quanta.pt5161lrs(chips)',
 PATH='I19',
 DRAWING='@T6G_MB_LIB.T6G(SCH_1):PAGE391',
 PART_TYPE='SMLF',
 MATERIAL='IC',
 PHYS_PAGE='332',
 XY='(-2250,3600)',
 ROT='0',
 VER='5',
 LOCATION='U6015',
 CDS_LIB='pure_quanta',
 CDS_PART_NAME='PT5161LRS-PT5161LRS,SMLF,IC,AJ051610U03',
 PART_NUMBER='AJ051610U03',
 VALUE='PT5161LRS',
 PRIM_FILE='./archive_libs/logical/pt5161lrs/chips/chips.prt';

SECTION_NUMBER 6
 '@T6G_MB_LIB.T6G(SCH_1):PAGE395_I1@PURE_QUANTA.PT5161LRS(CHIPS)':
 C_PATH='@t6g_mb_lib.t6g(sch_1):page395_i1@pure_quanta.pt5161lrs(chips)',
 P_PATH='@t6g_mb_lib.t6g(sch_1):page328_i1@pure_quanta.pt5161lrs(chips)',
 PATH='I1',
 DRAWING='@T6G_MB_LIB.T6G(SCH_1):PAGE395',
 PART_TYPE='SMLF',
 MATERIAL='IC',
 PHYS_PAGE='328',
 XY='(-7450,4425)',
 ROT='0',
 VER='6',
 LOCATION='U6015',
 CDS_LIB='pure_quanta',
 CDS_PART_NAME='PT5161LRS-PT5161LRS,SMLF,IC,AJ051610U03',
 PART_NUMBER='AJ051610U03',
 VALUE='PT5161LRS',
 PRIM_FILE='./archive_libs/logical/pt5161lrs/chips/chips.prt';

SECTION_NUMBER 7
 '@T6G_MB_LIB.T6G(SCH_1):PAGE395_I38@PURE_QUANTA.PT5161LRS(CHIPS)':
 C_PATH='@t6g_mb_lib.t6g(sch_1):page395_i38@pure_quanta.pt5161lrs(chips)',
 P_PATH='@t6g_mb_lib.t6g(sch_1):page328_i38@pure_quanta.pt5161lrs(chips)',
 PATH='I38',
 DRAWING='@T6G_MB_LIB.T6G(SCH_1):PAGE395',
 PART_TYPE='SMLF',
 MATERIAL='IC',
 PHYS_PAGE='328',
 XY='(-2925,4500)',
 ROT='0',
 VER='7',
 LOCATION='U6015',
 CDS_LIB='pure_quanta',
 CDS_PART_NAME='PT5161LRS-PT5161LRS,SMLF,IC,AJ051610U03',
 PART_NUMBER='AJ051610U03',
 VALUE='PT5161LRS',
 PRIM_FILE='./archive_libs/logical/pt5161lrs/chips/chips.prt';

SECTION_NUMBER 8
 '@T6G_MB_LIB.T6G(SCH_1):PAGE396_I1@PURE_QUANTA.PT5161LRS(CHIPS)':
 C_PATH='@t6g_mb_lib.t6g(sch_1):page396_i1@pure_quanta.pt5161lrs(chips)',
 P_PATH='@t6g_mb_lib.t6g(sch_1):page327_i1@pure_quanta.pt5161lrs(chips)',
 PATH='I1',
 DRAWING='@T6G_MB_LIB.T6G(SCH_1):PAGE396',
 PART_TYPE='SMLF',
 MATERIAL='IC',
 PHYS_PAGE='327',
 XY='(-7825,3950)',
 ROT='0',
 VER='8',
 LOCATION='U6015',
 CDS_LIB='pure_quanta',
 CDS_PART_NAME='PT5161LRS-PT5161LRS,SMLF,IC,AJ051610U03',
 PART_NUMBER='AJ051610U03',
 VALUE='PT5161LRS',
 PRIM_FILE='./archive_libs/logical/pt5161lrs/chips/chips.prt';

SECTION_NUMBER 9
 '@T6G_MB_LIB.T6G(SCH_1):PAGE396_I38@PURE_QUANTA.PT5161LRS(CHIPS)':
 C_PATH='@t6g_mb_lib.t6g(sch_1):page396_i38@pure_quanta.pt5161lrs(chips)',
 P_PATH='@t6g_mb_lib.t6g(sch_1):page327_i38@pure_quanta.pt5161lrs(chips)',
 PATH='I38',
 DRAWING='@T6G_MB_LIB.T6G(SCH_1):PAGE396',
 PART_TYPE='SMLF',
 MATERIAL='IC',
 PHYS_PAGE='327',
 XY='(-3200,3900)',
 ROT='0',
 VER='9',
 LOCATION='U6015',
 CDS_LIB='pure_quanta',
 CDS_PART_NAME='PT5161LRS-PT5161LRS,SMLF,IC,AJ051610U03',
 PART_NUMBER='AJ051610U03',
 VALUE='PT5161LRS',
 PRIM_FILE='./archive_libs/logical/pt5161lrs/chips/chips.prt';

SECTION_NUMBER 10
 '@T6G_MB_LIB.T6G(SCH_1):PAGE393_I41@PURE_QUANTA.PT5161LRS(CHIPS)':
 C_PATH='@t6g_mb_lib.t6g(sch_1):page393_i41@pure_quanta.pt5161lrs(chips)',
 P_PATH='@t6g_mb_lib.t6g(sch_1):page330_i41@pure_quanta.pt5161lrs(chips)',
 PATH='I41',
 DRAWING='@T6G_MB_LIB.T6G(SCH_1):PAGE393',
 PART_TYPE='SMLF',
 MATERIAL='IC',
 PHYS_PAGE='330',
 XY='(-7525,4575)',
 ROT='0',
 VER='10',
 LOCATION='U6015',
 CDS_LIB='pure_quanta',
 CDS_PART_NAME='PT5161LRS-PT5161LRS,SMLF,IC,AJ051610U03',
 PART_NUMBER='AJ051610U03',
 VALUE='PT5161LRS',
 PRIM_FILE='./archive_libs/logical/pt5161lrs/chips/chips.prt';

SECTION_NUMBER 11
 '@T6G_MB_LIB.T6G(SCH_1):PAGE393_I142@PURE_QUANTA.PT5161LRS(CHIPS)':
 C_PATH='@t6g_mb_lib.t6g(sch_1):page393_i142@pure_quanta.pt5161lrs(chips)',
 P_PATH='@t6g_mb_lib.t6g(sch_1):page330_i142@pure_quanta.pt5161lrs(chips)',
 PATH='I142',
 DRAWING='@T6G_MB_LIB.T6G(SCH_1):PAGE393',
 PART_TYPE='SMLF',
 MATERIAL='IC',
 PHYS_PAGE='330',
 XY='(-2350,4550)',
 ROT='0',
 VER='11',
 LOCATION='U6015',
 CDS_LIB='pure_quanta',
 CDS_PART_NAME='PT5161LRS-PT5161LRS,SMLF,IC,AJ051610U03',
 PART_NUMBER='AJ051610U03',
 VALUE='PT5161LRS',
 PRIM_FILE='./archive_libs/logical/pt5161lrs/chips/chips.prt';

PART_NAME
 U6016 'PT5161LRS-PT5161LRS,SMLF,IC,AJ051610U03':;

SECTION_NUMBER 1
 '@T6G_MB_LIB.T6G(SCH_1):PAGE449_I1@PURE_QUANTA.PT5161LRS(CHIPS)':
 C_PATH='@t6g_mb_lib.t6g(sch_1):page449_i1@pure_quanta.pt5161lrs(chips)',
 P_PATH='@t6g_mb_lib.t6g(sch_1):page340_i1@pure_quanta.pt5161lrs(chips)',
 PATH='I1',
 DRAWING='@T6G_MB_LIB.T6G(SCH_1):PAGE449',
 PART_TYPE='SMLF',
 MATERIAL='IC',
 PHYS_PAGE='340',
 XY='(-7800,3850)',
 ROT='0',
 VER='1',
 LOCATION='U6016',
 CDS_LIB='pure_quanta',
 CDS_PART_NAME='PT5161LRS-PT5161LRS,SMLF,IC,AJ051610U03',
 PART_NUMBER='AJ051610U03',
 VALUE='PT5161LRS',
 PRIM_FILE='./archive_libs/logical/pt5161lrs/chips/chips.prt';

SECTION_NUMBER 2
 '@T6G_MB_LIB.T6G(SCH_1):PAGE449_I38@PURE_QUANTA.PT5161LRS(CHIPS)':
 C_PATH='@t6g_mb_lib.t6g(sch_1):page449_i38@pure_quanta.pt5161lrs(chips)',
 P_PATH='@t6g_mb_lib.t6g(sch_1):page340_i38@pure_quanta.pt5161lrs(chips)',
 PATH='I38',
 DRAWING='@T6G_MB_LIB.T6G(SCH_1):PAGE449',
 PART_TYPE='SMLF',
 MATERIAL='IC',
 PHYS_PAGE='340',
 XY='(-3350,3875)',
 ROT='0',
 VER='2',
 LOCATION='U6016',
 CDS_LIB='pure_quanta',
 CDS_PART_NAME='PT5161LRS-PT5161LRS,SMLF,IC,AJ051610U03',
 PART_NUMBER='AJ051610U03',
 VALUE='PT5161LRS',
 PRIM_FILE='./archive_libs/logical/pt5161lrs/chips/chips.prt';

SECTION_NUMBER 3
 '@T6G_MB_LIB.T6G(SCH_1):PAGE451_I97@PURE_QUANTA.PT5161LRS(CHIPS)':
 C_PATH='@t6g_mb_lib.t6g(sch_1):page451_i97@pure_quanta.pt5161lrs(chips)',
 P_PATH='@t6g_mb_lib.t6g(sch_1):page342_i97@pure_quanta.pt5161lrs(chips)',
 PATH='I97',
 DRAWING='@T6G_MB_LIB.T6G(SCH_1):PAGE451',
 PART_TYPE='SMLF',
 MATERIAL='IC',
 PHYS_PAGE='342',
 XY='(-4350,2325)',
 ROT='0',
 VER='3',
 LOCATION='U6016',
 CDS_LIB='pure_quanta',
 CDS_PART_NAME='PT5161LRS-PT5161LRS,SMLF,IC,AJ051610U03',
 PART_NUMBER='AJ051610U03',
 VALUE='PT5161LRS',
 PRIM_FILE='./archive_libs/logical/pt5161lrs/chips/chips.prt';

SECTION_NUMBER 4
 '@T6G_MB_LIB.T6G(SCH_1):PAGE452_I7@PURE_QUANTA.PT5161LRS(CHIPS)':
 C_PATH='@t6g_mb_lib.t6g(sch_1):page452_i7@pure_quanta.pt5161lrs(chips)',
 P_PATH='@t6g_mb_lib.t6g(sch_1):page343_i7@pure_quanta.pt5161lrs(chips)',
 PATH='I7',
 DRAWING='@T6G_MB_LIB.T6G(SCH_1):PAGE452',
 PART_TYPE='SMLF',
 MATERIAL='IC',
 PHYS_PAGE='343',
 XY='(-6250,4400)',
 ROT='0',
 VER='4',
 LOCATION='U6016',
 CDS_LIB='pure_quanta',
 CDS_PART_NAME='PT5161LRS-PT5161LRS,SMLF,IC,AJ051610U03',
 PART_NUMBER='AJ051610U03',
 VALUE='PT5161LRS',
 PRIM_FILE='./archive_libs/logical/pt5161lrs/chips/chips.prt';

SECTION_NUMBER 5
 '@T6G_MB_LIB.T6G(SCH_1):PAGE452_I19@PURE_QUANTA.PT5161LRS(CHIPS)':
 C_PATH='@t6g_mb_lib.t6g(sch_1):page452_i19@pure_quanta.pt5161lrs(chips)',
 P_PATH='@t6g_mb_lib.t6g(sch_1):page343_i19@pure_quanta.pt5161lrs(chips)',
 PATH='I19',
 DRAWING='@T6G_MB_LIB.T6G(SCH_1):PAGE452',
 PART_TYPE='SMLF',
 MATERIAL='IC',
 PHYS_PAGE='343',
 XY='(-2175,3825)',
 ROT='0',
 VER='5',
 LOCATION='U6016',
 CDS_LIB='pure_quanta',
 CDS_PART_NAME='PT5161LRS-PT5161LRS,SMLF,IC,AJ051610U03',
 PART_NUMBER='AJ051610U03',
 VALUE='PT5161LRS',
 PRIM_FILE='./archive_libs/logical/pt5161lrs/chips/chips.prt';

SECTION_NUMBER 6
 '@T6G_MB_LIB.T6G(SCH_1):PAGE448_I1@PURE_QUANTA.PT5161LRS(CHIPS)':
 C_PATH='@t6g_mb_lib.t6g(sch_1):page448_i1@pure_quanta.pt5161lrs(chips)',
 P_PATH='@t6g_mb_lib.t6g(sch_1):page339_i1@pure_quanta.pt5161lrs(chips)',
 PATH='I1',
 DRAWING='@T6G_MB_LIB.T6G(SCH_1):PAGE448',
 PART_TYPE='SMLF',
 MATERIAL='IC',
 PHYS_PAGE='339',
 XY='(-7700,4375)',
 ROT='0',
 VER='6',
 LOCATION='U6016',
 CDS_LIB='pure_quanta',
 CDS_PART_NAME='PT5161LRS-PT5161LRS,SMLF,IC,AJ051610U03',
 PART_NUMBER='AJ051610U03',
 VALUE='PT5161LRS',
 PRIM_FILE='./archive_libs/logical/pt5161lrs/chips/chips.prt';

SECTION_NUMBER 7
 '@T6G_MB_LIB.T6G(SCH_1):PAGE448_I38@PURE_QUANTA.PT5161LRS(CHIPS)':
 C_PATH='@t6g_mb_lib.t6g(sch_1):page448_i38@pure_quanta.pt5161lrs(chips)',
 P_PATH='@t6g_mb_lib.t6g(sch_1):page339_i38@pure_quanta.pt5161lrs(chips)',
 PATH='I38',
 DRAWING='@T6G_MB_LIB.T6G(SCH_1):PAGE448',
 PART_TYPE='SMLF',
 MATERIAL='IC',
 PHYS_PAGE='339',
 XY='(-3175,4450)',
 ROT='0',
 VER='7',
 LOCATION='U6016',
 CDS_LIB='pure_quanta',
 CDS_PART_NAME='PT5161LRS-PT5161LRS,SMLF,IC,AJ051610U03',
 PART_NUMBER='AJ051610U03',
 VALUE='PT5161LRS',
 PRIM_FILE='./archive_libs/logical/pt5161lrs/chips/chips.prt';

SECTION_NUMBER 8
 '@T6G_MB_LIB.T6G(SCH_1):PAGE447_I1@PURE_QUANTA.PT5161LRS(CHIPS)':
 C_PATH='@t6g_mb_lib.t6g(sch_1):page447_i1@pure_quanta.pt5161lrs(chips)',
 P_PATH='@t6g_mb_lib.t6g(sch_1):page338_i1@pure_quanta.pt5161lrs(chips)',
 PATH='I1',
 DRAWING='@T6G_MB_LIB.T6G(SCH_1):PAGE447',
 PART_TYPE='SMLF',
 MATERIAL='IC',
 PHYS_PAGE='338',
 XY='(-7575,3800)',
 ROT='0',
 VER='8',
 LOCATION='U6016',
 CDS_LIB='pure_quanta',
 CDS_PART_NAME='PT5161LRS-PT5161LRS,SMLF,IC,AJ051610U03',
 PART_NUMBER='AJ051610U03',
 VALUE='PT5161LRS',
 PRIM_FILE='./archive_libs/logical/pt5161lrs/chips/chips.prt';

SECTION_NUMBER 9
 '@T6G_MB_LIB.T6G(SCH_1):PAGE447_I38@PURE_QUANTA.PT5161LRS(CHIPS)':
 C_PATH='@t6g_mb_lib.t6g(sch_1):page447_i38@pure_quanta.pt5161lrs(chips)',
 P_PATH='@t6g_mb_lib.t6g(sch_1):page338_i38@pure_quanta.pt5161lrs(chips)',
 PATH='I38',
 DRAWING='@T6G_MB_LIB.T6G(SCH_1):PAGE447',
 PART_TYPE='SMLF',
 MATERIAL='IC',
 PHYS_PAGE='338',
 XY='(-2950,3750)',
 ROT='0',
 VER='9',
 LOCATION='U6016',
 CDS_LIB='pure_quanta',
 CDS_PART_NAME='PT5161LRS-PT5161LRS,SMLF,IC,AJ051610U03',
 PART_NUMBER='AJ051610U03',
 VALUE='PT5161LRS',
 PRIM_FILE='./archive_libs/logical/pt5161lrs/chips/chips.prt';

SECTION_NUMBER 10
 '@T6G_MB_LIB.T6G(SCH_1):PAGE450_I33@PURE_QUANTA.PT5161LRS(CHIPS)':
 C_PATH='@t6g_mb_lib.t6g(sch_1):page450_i33@pure_quanta.pt5161lrs(chips)',
 P_PATH='@t6g_mb_lib.t6g(sch_1):page341_i33@pure_quanta.pt5161lrs(chips)',
 PATH='I33',
 DRAWING='@T6G_MB_LIB.T6G(SCH_1):PAGE450',
 PART_TYPE='SMLF',
 MATERIAL='IC',
 PHYS_PAGE='341',
 XY='(-7775,4625)',
 ROT='0',
 VER='10',
 LOCATION='U6016',
 CDS_LIB='pure_quanta',
 CDS_PART_NAME='PT5161LRS-PT5161LRS,SMLF,IC,AJ051610U03',
 PART_NUMBER='AJ051610U03',
 VALUE='PT5161LRS',
 PRIM_FILE='./archive_libs/logical/pt5161lrs/chips/chips.prt';

SECTION_NUMBER 11
 '@T6G_MB_LIB.T6G(SCH_1):PAGE450_I142@PURE_QUANTA.PT5161LRS(CHIPS)':
 C_PATH='@t6g_mb_lib.t6g(sch_1):page450_i142@pure_quanta.pt5161lrs(chips)',
 P_PATH='@t6g_mb_lib.t6g(sch_1):page341_i142@pure_quanta.pt5161lrs(chips)',
 PATH='I142',
 DRAWING='@T6G_MB_LIB.T6G(SCH_1):PAGE450',
 PART_TYPE='SMLF',
 MATERIAL='IC',
 PHYS_PAGE='341',
 XY='(-2600,4600)',
 ROT='0',
 VER='11',
 LOCATION='U6016',
 CDS_LIB='pure_quanta',
 CDS_PART_NAME='PT5161LRS-PT5161LRS,SMLF,IC,AJ051610U03',
 PART_NUMBER='AJ051610U03',
 VALUE='PT5161LRS',
 PRIM_FILE='./archive_libs/logical/pt5161lrs/chips/chips.prt';

PART_NAME
 U6017 'PT5161LRS-PT5161LRS,SMLF,IC,AJ051610U03':;

SECTION_NUMBER 1
 '@T6G_MB_LIB.T6G(SCH_1):PAGE460_I1@PURE_QUANTA.PT5161LRS(CHIPS)':
 C_PATH='@t6g_mb_lib.t6g(sch_1):page460_i1@pure_quanta.pt5161lrs(chips)',
 P_PATH='@t6g_mb_lib.t6g(sch_1):page351_i1@pure_quanta.pt5161lrs(chips)',
 PATH='I1',
 DRAWING='@T6G_MB_LIB.T6G(SCH_1):PAGE460',
 PART_TYPE='SMLF',
 MATERIAL='IC',
 PHYS_PAGE='351',
 XY='(-7775,3750)',
 ROT='0',
 VER='1',
 LOCATION='U6017',
 CDS_LIB='pure_quanta',
 CDS_PART_NAME='PT5161LRS-PT5161LRS,SMLF,IC,AJ051610U03',
 PART_NUMBER='AJ051610U03',
 VALUE='PT5161LRS',
 PRIM_FILE='./archive_libs/logical/pt5161lrs/chips/chips.prt';

SECTION_NUMBER 2
 '@T6G_MB_LIB.T6G(SCH_1):PAGE460_I38@PURE_QUANTA.PT5161LRS(CHIPS)':
 C_PATH='@t6g_mb_lib.t6g(sch_1):page460_i38@pure_quanta.pt5161lrs(chips)',
 P_PATH='@t6g_mb_lib.t6g(sch_1):page351_i38@pure_quanta.pt5161lrs(chips)',
 PATH='I38',
 DRAWING='@T6G_MB_LIB.T6G(SCH_1):PAGE460',
 PART_TYPE='SMLF',
 MATERIAL='IC',
 PHYS_PAGE='351',
 XY='(-3325,3775)',
 ROT='0',
 VER='2',
 LOCATION='U6017',
 CDS_LIB='pure_quanta',
 CDS_PART_NAME='PT5161LRS-PT5161LRS,SMLF,IC,AJ051610U03',
 PART_NUMBER='AJ051610U03',
 VALUE='PT5161LRS',
 PRIM_FILE='./archive_libs/logical/pt5161lrs/chips/chips.prt';

SECTION_NUMBER 3
 '@T6G_MB_LIB.T6G(SCH_1):PAGE462_I97@PURE_QUANTA.PT5161LRS(CHIPS)':
 C_PATH='@t6g_mb_lib.t6g(sch_1):page462_i97@pure_quanta.pt5161lrs(chips)',
 P_PATH='@t6g_mb_lib.t6g(sch_1):page353_i97@pure_quanta.pt5161lrs(chips)',
 PATH='I97',
 DRAWING='@T6G_MB_LIB.T6G(SCH_1):PAGE462',
 PART_TYPE='SMLF',
 MATERIAL='IC',
 PHYS_PAGE='353',
 XY='(-4425,2350)',
 ROT='0',
 VER='3',
 LOCATION='U6017',
 CDS_LIB='pure_quanta',
 CDS_PART_NAME='PT5161LRS-PT5161LRS,SMLF,IC,AJ051610U03',
 PART_NUMBER='AJ051610U03',
 VALUE='PT5161LRS',
 PRIM_FILE='./archive_libs/logical/pt5161lrs/chips/chips.prt';

SECTION_NUMBER 4
 '@T6G_MB_LIB.T6G(SCH_1):PAGE463_I5@PURE_QUANTA.PT5161LRS(CHIPS)':
 C_PATH='@t6g_mb_lib.t6g(sch_1):page463_i5@pure_quanta.pt5161lrs(chips)',
 P_PATH='@t6g_mb_lib.t6g(sch_1):page354_i5@pure_quanta.pt5161lrs(chips)',
 PATH='I5',
 DRAWING='@T6G_MB_LIB.T6G(SCH_1):PAGE463',
 PART_TYPE='SMLF',
 MATERIAL='IC',
 PHYS_PAGE='354',
 XY='(-6500,4175)',
 ROT='0',
 VER='4',
 LOCATION='U6017',
 CDS_LIB='pure_quanta',
 CDS_PART_NAME='PT5161LRS-PT5161LRS,SMLF,IC,AJ051610U03',
 PART_NUMBER='AJ051610U03',
 VALUE='PT5161LRS',
 PRIM_FILE='./archive_libs/logical/pt5161lrs/chips/chips.prt';

SECTION_NUMBER 5
 '@T6G_MB_LIB.T6G(SCH_1):PAGE463_I17@PURE_QUANTA.PT5161LRS(CHIPS)':
 C_PATH='@t6g_mb_lib.t6g(sch_1):page463_i17@pure_quanta.pt5161lrs(chips)',
 P_PATH='@t6g_mb_lib.t6g(sch_1):page354_i17@pure_quanta.pt5161lrs(chips)',
 PATH='I17',
 DRAWING='@T6G_MB_LIB.T6G(SCH_1):PAGE463',
 PART_TYPE='SMLF',
 MATERIAL='IC',
 PHYS_PAGE='354',
 XY='(-2425,3600)',
 ROT='0',
 VER='5',
 LOCATION='U6017',
 CDS_LIB='pure_quanta',
 CDS_PART_NAME='PT5161LRS-PT5161LRS,SMLF,IC,AJ051610U03',
 PART_NUMBER='AJ051610U03',
 VALUE='PT5161LRS',
 PRIM_FILE='./archive_libs/logical/pt5161lrs/chips/chips.prt';

SECTION_NUMBER 6
 '@T6G_MB_LIB.T6G(SCH_1):PAGE459_I1@PURE_QUANTA.PT5161LRS(CHIPS)':
 C_PATH='@t6g_mb_lib.t6g(sch_1):page459_i1@pure_quanta.pt5161lrs(chips)',
 P_PATH='@t6g_mb_lib.t6g(sch_1):page350_i1@pure_quanta.pt5161lrs(chips)',
 PATH='I1',
 DRAWING='@T6G_MB_LIB.T6G(SCH_1):PAGE459',
 PART_TYPE='SMLF',
 MATERIAL='IC',
 PHYS_PAGE='350',
 XY='(-7625,4400)',
 ROT='0',
 VER='6',
 LOCATION='U6017',
 CDS_LIB='pure_quanta',
 CDS_PART_NAME='PT5161LRS-PT5161LRS,SMLF,IC,AJ051610U03',
 PART_NUMBER='AJ051610U03',
 VALUE='PT5161LRS',
 PRIM_FILE='./archive_libs/logical/pt5161lrs/chips/chips.prt';

SECTION_NUMBER 7
 '@T6G_MB_LIB.T6G(SCH_1):PAGE459_I38@PURE_QUANTA.PT5161LRS(CHIPS)':
 C_PATH='@t6g_mb_lib.t6g(sch_1):page459_i38@pure_quanta.pt5161lrs(chips)',
 P_PATH='@t6g_mb_lib.t6g(sch_1):page350_i38@pure_quanta.pt5161lrs(chips)',
 PATH='I38',
 DRAWING='@T6G_MB_LIB.T6G(SCH_1):PAGE459',
 PART_TYPE='SMLF',
 MATERIAL='IC',
 PHYS_PAGE='350',
 XY='(-3100,4475)',
 ROT='0',
 VER='7',
 LOCATION='U6017',
 CDS_LIB='pure_quanta',
 CDS_PART_NAME='PT5161LRS-PT5161LRS,SMLF,IC,AJ051610U03',
 PART_NUMBER='AJ051610U03',
 VALUE='PT5161LRS',
 PRIM_FILE='./archive_libs/logical/pt5161lrs/chips/chips.prt';

SECTION_NUMBER 8
 '@T6G_MB_LIB.T6G(SCH_1):PAGE458_I1@PURE_QUANTA.PT5161LRS(CHIPS)':
 C_PATH='@t6g_mb_lib.t6g(sch_1):page458_i1@pure_quanta.pt5161lrs(chips)',
 P_PATH='@t6g_mb_lib.t6g(sch_1):page349_i1@pure_quanta.pt5161lrs(chips)',
 PATH='I1',
 DRAWING='@T6G_MB_LIB.T6G(SCH_1):PAGE458',
 PART_TYPE='SMLF',
 MATERIAL='IC',
 PHYS_PAGE='349',
 XY='(-7825,3925)',
 ROT='0',
 VER='8',
 LOCATION='U6017',
 CDS_LIB='pure_quanta',
 CDS_PART_NAME='PT5161LRS-PT5161LRS,SMLF,IC,AJ051610U03',
 PART_NUMBER='AJ051610U03',
 VALUE='PT5161LRS',
 PRIM_FILE='./archive_libs/logical/pt5161lrs/chips/chips.prt';

SECTION_NUMBER 9
 '@T6G_MB_LIB.T6G(SCH_1):PAGE458_I38@PURE_QUANTA.PT5161LRS(CHIPS)':
 C_PATH='@t6g_mb_lib.t6g(sch_1):page458_i38@pure_quanta.pt5161lrs(chips)',
 P_PATH='@t6g_mb_lib.t6g(sch_1):page349_i38@pure_quanta.pt5161lrs(chips)',
 PATH='I38',
 DRAWING='@T6G_MB_LIB.T6G(SCH_1):PAGE458',
 PART_TYPE='SMLF',
 MATERIAL='IC',
 PHYS_PAGE='349',
 XY='(-3200,3875)',
 ROT='0',
 VER='9',
 LOCATION='U6017',
 CDS_LIB='pure_quanta',
 CDS_PART_NAME='PT5161LRS-PT5161LRS,SMLF,IC,AJ051610U03',
 PART_NUMBER='AJ051610U03',
 VALUE='PT5161LRS',
 PRIM_FILE='./archive_libs/logical/pt5161lrs/chips/chips.prt';

SECTION_NUMBER 10
 '@T6G_MB_LIB.T6G(SCH_1):PAGE461_I46@PURE_QUANTA.PT5161LRS(CHIPS)':
 C_PATH='@t6g_mb_lib.t6g(sch_1):page461_i46@pure_quanta.pt5161lrs(chips)',
 P_PATH='@t6g_mb_lib.t6g(sch_1):page352_i46@pure_quanta.pt5161lrs(chips)',
 PATH='I46',
 DRAWING='@T6G_MB_LIB.T6G(SCH_1):PAGE461',
 PART_TYPE='SMLF',
 MATERIAL='IC',
 PHYS_PAGE='352',
 XY='(-7775,4525)',
 ROT='0',
 VER='10',
 LOCATION='U6017',
 CDS_LIB='pure_quanta',
 CDS_PART_NAME='PT5161LRS-PT5161LRS,SMLF,IC,AJ051610U03',
 PART_NUMBER='AJ051610U03',
 VALUE='PT5161LRS',
 PRIM_FILE='./archive_libs/logical/pt5161lrs/chips/chips.prt';

SECTION_NUMBER 11
 '@T6G_MB_LIB.T6G(SCH_1):PAGE461_I142@PURE_QUANTA.PT5161LRS(CHIPS)':
 C_PATH='@t6g_mb_lib.t6g(sch_1):page461_i142@pure_quanta.pt5161lrs(chips)',
 P_PATH='@t6g_mb_lib.t6g(sch_1):page352_i142@pure_quanta.pt5161lrs(chips)',
 PATH='I142',
 DRAWING='@T6G_MB_LIB.T6G(SCH_1):PAGE461',
 PART_TYPE='SMLF',
 MATERIAL='IC',
 PHYS_PAGE='352',
 XY='(-2600,4500)',
 ROT='0',
 VER='11',
 LOCATION='U6017',
 CDS_LIB='pure_quanta',
 CDS_PART_NAME='PT5161LRS-PT5161LRS,SMLF,IC,AJ051610U03',
 PART_NUMBER='AJ051610U03',
 VALUE='PT5161LRS',
 PRIM_FILE='./archive_libs/logical/pt5161lrs/chips/chips.prt';

PART_NAME
 U6020 'TCA9548APWR-TCA9548APWR,SMLF,IC,AL009548K02':;

SECTION_NUMBER 1
 '@T6G_MB_LIB.T6G(SCH_1):PAGE378_I1@PURE_QUANTA.TCA9548APWR(CHIPS)':
 C_PATH='@t6g_mb_lib.t6g(sch_1):page378_i1@pure_quanta.tca9548apwr(chips)',
 P_PATH='@t6g_mb_lib.t6g(sch_1):page184_i1@pure_quanta.tca9548apwr(chips)',
 PATH='I1',
 DRAWING='@T6G_MB_LIB.T6G(SCH_1):PAGE378',
 PART_TYPE='SMLF',
 MATERIAL='IC',
 PHYS_PAGE='184',
 XY='(-4900,4575)',
 ROT='0',
 VER='1',
 LOCATION='U6020',
 CDS_LIB='pure_quanta',
 CDS_PART_NAME='TCA9548APWR-TCA9548APWR,SMLF,IC,AL009548K02',
 PART_NUMBER='AL009548K02',
 VALUE='TCA9548APWR',
 PRIM_FILE='./archive_libs/logical/tca9548apwr/chips/chips.prt';

PART_NAME
 U8000 'NC7SB3157P6X-NC7SB3157P6X,SMLF,IC,ALSB3157000':;

SECTION_NUMBER 1
 '@T6G_MB_LIB.T6G(SCH_1):PAGE130_I1@PURE_QUANTA.NC7SB3157P6X(CHIPS)':
 C_PATH='@t6g_mb_lib.t6g(sch_1):page130_i1@pure_quanta.nc7sb3157p6x(chips)',
 P_PATH='@t6g_mb_lib.t6g(sch_1):page153_i1@pure_quanta.nc7sb3157p6x(chips)',
 PATH='I1',
 DRAWING='@T6G_MB_LIB.T6G(SCH_1):PAGE130',
 SEC_TYPE='',
 PART_TYPE='SMLF',
 MATERIAL='IC',
 PHYS_PAGE='153',
 XY='(-4900,5025)',
 ROT='2',
 VER='1',
 LOCATION='U8000',
 SEC='1',
 CDS_LIB='pure_quanta',
 CDS_PART_NAME='NC7SB3157P6X-NC7SB3157P6X,SMLF,IC,ALSB3157000',
 PART_NUMBER='ALSB3157000',
 VALUE='NC7SB3157P6X',
 PRIM_FILE='./archive_libs/logical/nc7sb3157p6x/chips/chips.prt';

PART_NAME
 U8001 'APX80929SAG7-APX809-29SAG-7,SMLF,IC,AL080929000':;

SECTION_NUMBER 1
 '@T6G_MB_LIB.T6G(SCH_1):PAGE340_I80@PURE_QUANTA.APX80929SAG7(CHIPS)':
 C_PATH='@t6g_mb_lib.t6g(sch_1):page340_i80@pure_quanta.apx80929sag7(chips)',
 P_PATH='@t6g_mb_lib.t6g(sch_1):page136_i80@pure_quanta.apx80929sag7(chips)',
 PATH='I80',
 DRAWING='@T6G_MB_LIB.T6G(SCH_1):PAGE340',
 SEC_TYPE='',
 PART_TYPE='SMLF',
 MATERIAL='IC',
 PHYS_PAGE='136',
 XY='(-4250,4675)',
 ROT='2',
 VER='1',
 LOCATION='U8001',
 SEC='1',
 CDS_LIB='pure_quanta',
 CDS_PART_NAME='APX80929SAG7-APX809-29SAG-7,SMLF,IC,AL080929000',
 PART_NUMBER='AL080929000',
 VALUE='APX809-29SAG-7',
 PRIM_FILE='./archive_libs/logical/apx80929sag7/chips/chips.prt';

PART_NAME
 U8002 'APX80929SAG7-APX809-29SAG-7,SMLF,IC,AL080929000':;

SECTION_NUMBER 1
 '@T6G_MB_LIB.T6G(SCH_1):PAGE257_I67@PURE_QUANTA.APX80929SAG7(CHIPS)':
 C_PATH='@t6g_mb_lib.t6g(sch_1):page257_i67@pure_quanta.apx80929sag7(chips)',
 P_PATH='@t6g_mb_lib.t6g(sch_1):page142_i67@pure_quanta.apx80929sag7(chips)',
 PATH='I67',
 DRAWING='@T6G_MB_LIB.T6G(SCH_1):PAGE257',
 SEC_TYPE='',
 PART_TYPE='SMLF',
 MATERIAL='IC',
 PHYS_PAGE='142',
 XY='(-4600,-1150)',
 ROT='2',
 VER='1',
 LOCATION='U8002',
 SEC='1',
 CDS_LIB='pure_quanta',
 CDS_PART_NAME='APX80929SAG7-APX809-29SAG-7,SMLF,IC,AL080929000',
 PART_NUMBER='AL080929000',
 VALUE='APX809-29SAG-7',
 PRIM_FILE='./archive_libs/logical/apx80929sag7/chips/chips.prt';

PART_NAME
 U8003 'APX80929SAG7-APX809-29SAG-7,SMLF,IC,AL080929000':
 ROOM='E1S_P3V3_BOM2';

SECTION_NUMBER 1
 '@T6G_MB_LIB.T6G(SCH_1):PAGE323_I65@PURE_QUANTA.APX80929SAG7(CHIPS)':
 C_PATH='@t6g_mb_lib.t6g(sch_1):page323_i65@pure_quanta.apx80929sag7(chips)',
 P_PATH='@t6g_mb_lib.t6g(sch_1):page147_i65@pure_quanta.apx80929sag7(chips)',
 PATH='I65',
 DRAWING='@T6G_MB_LIB.T6G(SCH_1):PAGE323',
 PART_TYPE='SMLF',
 MATERIAL='IC',
 PHYS_PAGE='147',
 XY='(-3325,-2000)',
 ROT='2',
 VER='1',
 LOCATION='U8003',
 CDS_LIB='pure_quanta',
 CDS_PART_NAME='APX80929SAG7-APX809-29SAG-7,SMLF,IC,AL080929000',
 ROOM='E1S_P3V3_BOM2',
 PART_NUMBER='AL080929000',
 VALUE='APX809-29SAG-7',
 PRIM_FILE='./archive_libs/logical/apx80929sag7/chips/chips.prt';

PART_NAME
 U8004 '74LVC2G07DW7-74LVC2G07DW-7,SMLF,EMPTY,AL002G07003':;

SECTION_NUMBER 1
 '@T6G_MB_LIB.T6G(SCH_1):PAGE365_I16@PURE_QUANTA.74LVC2G07DW7(CHIPS)':
 C_PATH='@t6g_mb_lib.t6g(sch_1):page365_i16@pure_quanta.\74lvc2g07dw7\(chips)',
 P_PATH='@t6g_mb_lib.t6g(sch_1):page242_i16@pure_quanta.\74lvc2g07dw7\(chips)',
 PATH='I16',
 DRAWING='@T6G_MB_LIB.T6G(SCH_1):PAGE365',
 SEC_TYPE='',
 PART_TYPE='SMLF',
 MATERIAL='EMPTY',
 PHYS_PAGE='242',
 XY='(11550,1350)',
 ROT='0',
 VER='1',
 LOCATION='U8004',
 SEC='1',
 CDS_LIB='pure_quanta',
 CDS_PART_NAME='74LVC2G07DW7-74LVC2G07DW-7,SMLF,EMPTY,AL002G07003',
 PART_NUMBER='AL002G07003',
 VALUE='74LVC2G07DW-7',
 PRIM_FILE='./archive_libs/logical/74lvc2g07dw7/chips/chips.prt';

PART_NAME
 U8005 'LM4040AIM3X25NOPB-LM4040AIM3X-2.5/NOPB,SMLF,EMPTY,A':
 ROOM='HSC BOM2';

SECTION_NUMBER 1
 '@T6G_MB_LIB.T6G(SCH_1):PAGE371_I101@PURE_QUANTA.LM4040AIM3X25NOPB(CHIPS)':
 C_PATH='@t6g_mb_lib.t6g(sch_1):page371_i101@pure_quanta.lm4040aim3x25nopb(chips~
)',
 P_PATH='@t6g_mb_lib.t6g(sch_1):page267_i101@pure_quanta.lm4040aim3x25nopb(chips~
)',
 PATH='I101',
 DRAWING='@T6G_MB_LIB.T6G(SCH_1):PAGE371',
 PIN_NAMES_ROTATE='True',
 PART_TYPE='SMLF',
 MATERIAL='EMPTY',
 PHYS_PAGE='267',
 XY='(-8525,2875)',
 ROT='0',
 VER='1',
 LOCATION='U8005',
 CDS_LIB='pure_quanta',
 CDS_PART_NAME='LM4040AIM3X25NOPB-LM4040AIM3X-2.5/NOPB,SMLF,EMPTY,A',
 ROOM='HSC BOM2',
 PART_NUMBER='AL404025013',
 VALUE='LM4040AIM3X-2.5/NOPB',
 PRIM_FILE='./archive_libs/logical/lm4040aim3x25nopb/chips/chips.prt';

PART_NAME
 U8006 'AP331AWG7-AP331AWG-7,SMLF,EMPTY,AL000331011':
 ROOM='HSC BOM2';

SECTION_NUMBER 1
 '@T6G_MB_LIB.T6G(SCH_1):PAGE371_I104@PURE_QUANTA.AP331AWG7(CHIPS)':
 C_PATH='@t6g_mb_lib.t6g(sch_1):page371_i104@pure_quanta.ap331awg7(chips)',
 P_PATH='@t6g_mb_lib.t6g(sch_1):page267_i104@pure_quanta.ap331awg7(chips)',
 PATH='I104',
 DRAWING='@T6G_MB_LIB.T6G(SCH_1):PAGE371',
 PART_TYPE='SMLF',
 MATERIAL='EMPTY',
 PHYS_PAGE='267',
 XY='(-6750,3475)',
 ROT='0',
 VER='1',
 LOCATION='U8006',
 CDS_LIB='pure_quanta',
 CDS_PART_NAME='AP331AWG7-AP331AWG-7,SMLF,EMPTY,AL000331011',
 ROOM='HSC BOM2',
 PART_NUMBER='AL000331011',
 VALUE='AP331AWG-7',
 PRIM_FILE='./archive_libs/logical/ap331awg7/chips/chips.prt';

PART_NAME
 U8007 'LM4040AIM3X25NOPB-LM4040AIM3X-2.5/NOPB,SMLF,IC,AL4A':;

SECTION_NUMBER 1
 '@T6G_MB_LIB.T6G(SCH_1):PAGE372_I51@PURE_QUANTA.LM4040AIM3X25NOPB(CHIPS)':
 C_PATH='@t6g_mb_lib.t6g(sch_1):page372_i51@pure_quanta.lm4040aim3x25nopb(chips)~
',
 P_PATH='@t6g_mb_lib.t6g(sch_1):page268_i51@pure_quanta.lm4040aim3x25nopb(chips)~
',
 PATH='I51',
 DRAWING='@T6G_MB_LIB.T6G(SCH_1):PAGE372',
 PIN_NAMES_ROTATE='True',
 PART_TYPE='SMLF',
 MATERIAL='IC',
 PHYS_PAGE='268',
 XY='(-5100,2825)',
 ROT='0',
 VER='1',
 LOCATION='U8007',
 CDS_LIB='pure_quanta',
 CDS_PART_NAME='LM4040AIM3X25NOPB-LM4040AIM3X-2.5/NOPB,SMLF,IC,AL4A',
 PART_NUMBER='AL404025013',
 VALUE='LM4040AIM3X-2.5/NOPB',
 PRIM_FILE='./archive_libs/logical/lm4040aim3x25nopb/chips/chips.prt';

PART_NAME
 U8008 'AP331AWG7-AP331AWG-7,SMLF,IC,AL000331011':;

SECTION_NUMBER 1
 '@T6G_MB_LIB.T6G(SCH_1):PAGE372_I71@PURE_QUANTA.AP331AWG7(CHIPS)':
 C_PATH='@t6g_mb_lib.t6g(sch_1):page372_i71@pure_quanta.ap331awg7(chips)',
 P_PATH='@t6g_mb_lib.t6g(sch_1):page268_i71@pure_quanta.ap331awg7(chips)',
 PATH='I71',
 DRAWING='@T6G_MB_LIB.T6G(SCH_1):PAGE372',
 PART_TYPE='SMLF',
 MATERIAL='IC',
 PHYS_PAGE='268',
 XY='(-3325,3425)',
 ROT='0',
 VER='1',
 LOCATION='U8008',
 CDS_LIB='pure_quanta',
 CDS_PART_NAME='AP331AWG7-AP331AWG-7,SMLF,IC,AL000331011',
 PART_NUMBER='AL000331011',
 VALUE='AP331AWG-7',
 PRIM_FILE='./archive_libs/logical/ap331awg7/chips/chips.prt';

PART_NAME
 U8009 'LM4040AIM3X25NOPB-LM4040AIM3X-2.5/NOPB,SMLF,IC,AL4A':;

SECTION_NUMBER 1
 '@T6G_MB_LIB.T6G(SCH_1):PAGE372_I93@PURE_QUANTA.LM4040AIM3X25NOPB(CHIPS)':
 C_PATH='@t6g_mb_lib.t6g(sch_1):page372_i93@pure_quanta.lm4040aim3x25nopb(chips)~
',
 P_PATH='@t6g_mb_lib.t6g(sch_1):page268_i93@pure_quanta.lm4040aim3x25nopb(chips)~
',
 PATH='I93',
 DRAWING='@T6G_MB_LIB.T6G(SCH_1):PAGE372',
 PIN_NAMES_ROTATE='True',
 PART_TYPE='SMLF',
 MATERIAL='IC',
 PHYS_PAGE='268',
 XY='(-4775,1125)',
 ROT='0',
 VER='1',
 LOCATION='U8009',
 CDS_LIB='pure_quanta',
 CDS_PART_NAME='LM4040AIM3X25NOPB-LM4040AIM3X-2.5/NOPB,SMLF,IC,AL4A',
 PART_NUMBER='AL404025013',
 VALUE='LM4040AIM3X-2.5/NOPB',
 PRIM_FILE='./archive_libs/logical/lm4040aim3x25nopb/chips/chips.prt';

PART_NAME
 U8010 'AP331AWG7-AP331AWG-7,SMLF,IC,AL000331011':;

SECTION_NUMBER 1
 '@T6G_MB_LIB.T6G(SCH_1):PAGE372_I80@PURE_QUANTA.AP331AWG7(CHIPS)':
 C_PATH='@t6g_mb_lib.t6g(sch_1):page372_i80@pure_quanta.ap331awg7(chips)',
 P_PATH='@t6g_mb_lib.t6g(sch_1):page268_i80@pure_quanta.ap331awg7(chips)',
 PATH='I80',
 DRAWING='@T6G_MB_LIB.T6G(SCH_1):PAGE372',
 PART_TYPE='SMLF',
 MATERIAL='IC',
 PHYS_PAGE='268',
 XY='(-3000,1725)',
 ROT='0',
 VER='1',
 LOCATION='U8010',
 CDS_LIB='pure_quanta',
 CDS_PART_NAME='AP331AWG7-AP331AWG-7,SMLF,IC,AL000331011',
 PART_NUMBER='AL000331011',
 VALUE='AP331AWG-7',
 PRIM_FILE='./archive_libs/logical/ap331awg7/chips/chips.prt';

PART_NAME
 U8082 '74LVC1G126SE7-74LVC1G126SE-7,SMLF,IC,AL1G0126009':;

SECTION_NUMBER 1
 '@T6G_MB_LIB.T6G(SCH_1):PAGE337_I8@PURE_QUANTA.74LVC1G126SE7(CHIPS)':
 C_PATH='@t6g_mb_lib.t6g(sch_1):page337_i8@pure_quanta.\74lvc1g126se7\(chips)',
 P_PATH='@t6g_mb_lib.t6g(sch_1):page133_i8@pure_quanta.\74lvc1g126se7\(chips)',
 PATH='I8',
 DRAWING='@T6G_MB_LIB.T6G(SCH_1):PAGE337',
 PART_TYPE='SMLF',
 MATERIAL='IC',
 PHYS_PAGE='133',
 XY='(-8175,4250)',
 ROT='0',
 VER='1',
 LOCATION='U8082',
 CDS_LIB='pure_quanta',
 CDS_PART_NAME='74LVC1G126SE7-74LVC1G126SE-7,SMLF,IC,AL1G0126009',
 PART_NUMBER='AL1G0126009',
 VALUE='74LVC1G126SE-7',
 PRIM_FILE='./archive_libs/logical/74lvc1g126se7/chips/chips.prt';

PART_NAME
 U9001 '74LVC1G08W57-74LVC1G08W5-7,SMLF,IC,AL1G0008020':;

SECTION_NUMBER 1
 '@T6G_MB_LIB.T6G(SCH_1):PAGE340_I25@PURE_QUANTA.74LVC1G08W57(CHIPS)':
 C_PATH='@t6g_mb_lib.t6g(sch_1):page340_i25@pure_quanta.\74lvc1g08w57\(chips)',
 P_PATH='@t6g_mb_lib.t6g(sch_1):page136_i25@pure_quanta.\74lvc1g08w57\(chips)',
 PATH='I25',
 DRAWING='@T6G_MB_LIB.T6G(SCH_1):PAGE340',
 PART_TYPE='SMLF',
 MATERIAL='IC',
 PHYS_PAGE='136',
 XY='(500,6600)',
 ROT='0',
 VER='1',
 LOCATION='U9001',
 CDS_LIB='pure_quanta',
 CDS_PART_NAME='74LVC1G08W57-74LVC1G08W5-7,SMLF,IC,AL1G0008020',
 PART_NUMBER='AL1G0008020',
 VALUE='74LVC1G08W5-7',
 PRIM_FILE='./archive_libs/logical/74lvc1g08w57/chips/chips.prt';

PART_NAME
 U9002 '74LVC1G32GW_SMLF-74LVC1G32GW,IC,ALVC1G32007':;

SECTION_NUMBER 1
 '@T6G_MB_LIB.T6G(SCH_1):PAGE340_I74@PURE_QUANTA.74LVC1G32GW(CHIPS)':
 C_PATH='@t6g_mb_lib.t6g(sch_1):page340_i74@pure_quanta.\74lvc1g32gw\(chips)',
 P_PATH='@t6g_mb_lib.t6g(sch_1):page136_i74@pure_quanta.\74lvc1g32gw\(chips)',
 PATH='I74',
 DRAWING='@T6G_MB_LIB.T6G(SCH_1):PAGE340',
 MATERIAL='IC',
 PHYS_PAGE='136',
 XY='(425,5375)',
 ROT='0',
 VER='1',
 PACK_TYPE='SMLF',
 LOCATION='U9002',
 CDS_LIB='pure_quanta',
 CDS_PART_NAME='74LVC1G32GW_SMLF-74LVC1G32GW,IC,ALVC1G32007',
 PART_NUMBER='ALVC1G32007',
 VALUE='74LVC1G32GW',
 PRIM_FILE='./archive_libs/logical/74lvc1g32gw/chips/chips.prt';

PART_NAME
 U9050 '74LVC1G08W57-74LVC1G08W5-7,SMLF,IC,AL1G0008020':;

SECTION_NUMBER 1
 '@T6G_MB_LIB.T6G(SCH_1):PAGE340_I91@PURE_QUANTA.74LVC1G08W57(CHIPS)':
 C_PATH='@t6g_mb_lib.t6g(sch_1):page340_i91@pure_quanta.\74lvc1g08w57\(chips)',
 P_PATH='@t6g_mb_lib.t6g(sch_1):page136_i91@pure_quanta.\74lvc1g08w57\(chips)',
 PATH='I91',
 DRAWING='@T6G_MB_LIB.T6G(SCH_1):PAGE340',
 PART_TYPE='SMLF',
 MATERIAL='IC',
 PHYS_PAGE='136',
 XY='(-3900,6375)',
 ROT='0',
 VER='1',
 LOCATION='U9050',
 CDS_LIB='pure_quanta',
 CDS_PART_NAME='74LVC1G08W57-74LVC1G08W5-7,SMLF,IC,AL1G0008020',
 PART_NUMBER='AL1G0008020',
 VALUE='74LVC1G08W5-7',
 PRIM_FILE='./archive_libs/logical/74lvc1g08w57/chips/chips.prt';

PART_NAME
 U9051 '74LVC1G08W57-74LVC1G08W5-7,SMLF,IC,AL1G0008020':;

SECTION_NUMBER 1
 '@T6G_MB_LIB.T6G(SCH_1):PAGE257_I78@PURE_QUANTA.74LVC1G08W57(CHIPS)':
 C_PATH='@t6g_mb_lib.t6g(sch_1):page257_i78@pure_quanta.\74lvc1g08w57\(chips)',
 P_PATH='@t6g_mb_lib.t6g(sch_1):page142_i78@pure_quanta.\74lvc1g08w57\(chips)',
 PATH='I78',
 DRAWING='@T6G_MB_LIB.T6G(SCH_1):PAGE257',
 PART_TYPE='SMLF',
 MATERIAL='IC',
 PHYS_PAGE='142',
 XY='(-4275,625)',
 ROT='0',
 VER='1',
 LOCATION='U9051',
 CDS_LIB='pure_quanta',
 CDS_PART_NAME='74LVC1G08W57-74LVC1G08W5-7,SMLF,IC,AL1G0008020',
 PART_NUMBER='AL1G0008020',
 VALUE='74LVC1G08W5-7',
 PRIM_FILE='./archive_libs/logical/74lvc1g08w57/chips/chips.prt';

PART_NAME
 X1 'TP_TDR_4P_FTS_TH-TP_TDR_4P_DIP,EMPTY,TP15':;

SECTION_NUMBER 1
 '@T6G_MB_LIB.T6G(SCH_1):PAGE265_I48@PURE_QUANTA.TP_TDR_4P_FTS(CHIPS)':
 C_PATH='@t6g_mb_lib.t6g(sch_1):page265_i48@pure_quanta.tp_tdr_4p_fts(chips)',
 P_PATH='@t6g_mb_lib.t6g(sch_1):page260_i48@pure_quanta.tp_tdr_4p_fts(chips)',
 PATH='I48',
 DRAWING='@T6G_MB_LIB.T6G(SCH_1):PAGE265',
 MATERIAL='EMPTY',
 PHYS_PAGE='260',
 XY='(-5025,5825)',
 ROT='0',
 VER='1',
 PACK_TYPE='TH',
 LOCATION='X1',
 CDS_LIB='pure_quanta',
 CDS_PART_NAME='TP_TDR_4P_FTS_TH-TP_TDR_4P_DIP,EMPTY,TP15',
 PART_NUMBER='TP15',
 VALUE='TP_TDR_4P_DIP',
 PRIM_FILE='./archive_libs/logical/tp_tdr_4p_fts/chips/chips.prt';

PART_NAME
 X2 'TP_TDR_4P_FTS_TH-TP_TDR_4P_DIP,EMPTY,TP15':;

SECTION_NUMBER 1
 '@T6G_MB_LIB.T6G(SCH_1):PAGE265_I47@PURE_QUANTA.TP_TDR_4P_FTS(CHIPS)':
 C_PATH='@t6g_mb_lib.t6g(sch_1):page265_i47@pure_quanta.tp_tdr_4p_fts(chips)',
 P_PATH='@t6g_mb_lib.t6g(sch_1):page260_i47@pure_quanta.tp_tdr_4p_fts(chips)',
 PATH='I47',
 DRAWING='@T6G_MB_LIB.T6G(SCH_1):PAGE265',
 MATERIAL='EMPTY',
 PHYS_PAGE='260',
 XY='(-5025,5050)',
 ROT='0',
 VER='1',
 PACK_TYPE='TH',
 LOCATION='X2',
 CDS_LIB='pure_quanta',
 CDS_PART_NAME='TP_TDR_4P_FTS_TH-TP_TDR_4P_DIP,EMPTY,TP15',
 PART_NUMBER='TP15',
 VALUE='TP_TDR_4P_DIP',
 PRIM_FILE='./archive_libs/logical/tp_tdr_4p_fts/chips/chips.prt';

PART_NAME
 X3 'TP_TDR_4P_FTS_TH-TP_TDR_4P_DIP,EMPTY,TP15':;

SECTION_NUMBER 1
 '@T6G_MB_LIB.T6G(SCH_1):PAGE265_I37@PURE_QUANTA.TP_TDR_4P_FTS(CHIPS)':
 C_PATH='@t6g_mb_lib.t6g(sch_1):page265_i37@pure_quanta.tp_tdr_4p_fts(chips)',
 P_PATH='@t6g_mb_lib.t6g(sch_1):page260_i37@pure_quanta.tp_tdr_4p_fts(chips)',
 PATH='I37',
 DRAWING='@T6G_MB_LIB.T6G(SCH_1):PAGE265',
 MATERIAL='EMPTY',
 PHYS_PAGE='260',
 XY='(-5025,4275)',
 ROT='0',
 VER='1',
 PACK_TYPE='TH',
 LOCATION='X3',
 CDS_LIB='pure_quanta',
 CDS_PART_NAME='TP_TDR_4P_FTS_TH-TP_TDR_4P_DIP,EMPTY,TP15',
 PART_NUMBER='TP15',
 VALUE='TP_TDR_4P_DIP',
 PRIM_FILE='./archive_libs/logical/tp_tdr_4p_fts/chips/chips.prt';

PART_NAME
 X4 'TP_TDR_4P_FTS_TH-TP_TDR_4P_DIP,EMPTY,TP15':;

SECTION_NUMBER 1
 '@T6G_MB_LIB.T6G(SCH_1):PAGE265_I36@PURE_QUANTA.TP_TDR_4P_FTS(CHIPS)':
 C_PATH='@t6g_mb_lib.t6g(sch_1):page265_i36@pure_quanta.tp_tdr_4p_fts(chips)',
 P_PATH='@t6g_mb_lib.t6g(sch_1):page260_i36@pure_quanta.tp_tdr_4p_fts(chips)',
 PATH='I36',
 DRAWING='@T6G_MB_LIB.T6G(SCH_1):PAGE265',
 MATERIAL='EMPTY',
 PHYS_PAGE='260',
 XY='(-5025,3500)',
 ROT='0',
 VER='1',
 PACK_TYPE='TH',
 LOCATION='X4',
 CDS_LIB='pure_quanta',
 CDS_PART_NAME='TP_TDR_4P_FTS_TH-TP_TDR_4P_DIP,EMPTY,TP15',
 PART_NUMBER='TP15',
 VALUE='TP_TDR_4P_DIP',
 PRIM_FILE='./archive_libs/logical/tp_tdr_4p_fts/chips/chips.prt';

PART_NAME
 X5 'TP_TDR_4P_FTS_TH-TP_TDR_4P_DIP,EMPTY,TP15':;

SECTION_NUMBER 1
 '@T6G_MB_LIB.T6G(SCH_1):PAGE265_I35@PURE_QUANTA.TP_TDR_4P_FTS(CHIPS)':
 C_PATH='@t6g_mb_lib.t6g(sch_1):page265_i35@pure_quanta.tp_tdr_4p_fts(chips)',
 P_PATH='@t6g_mb_lib.t6g(sch_1):page260_i35@pure_quanta.tp_tdr_4p_fts(chips)',
 PATH='I35',
 DRAWING='@T6G_MB_LIB.T6G(SCH_1):PAGE265',
 MATERIAL='EMPTY',
 PHYS_PAGE='260',
 XY='(-5025,2725)',
 ROT='0',
 VER='1',
 PACK_TYPE='TH',
 LOCATION='X5',
 CDS_LIB='pure_quanta',
 CDS_PART_NAME='TP_TDR_4P_FTS_TH-TP_TDR_4P_DIP,EMPTY,TP15',
 PART_NUMBER='TP15',
 VALUE='TP_TDR_4P_DIP',
 PRIM_FILE='./archive_libs/logical/tp_tdr_4p_fts/chips/chips.prt';

PART_NAME
 X6 'TP_TDR_4P_FTS_TH-TP_TDR_4P_DIP,EMPTY,TP15':;

SECTION_NUMBER 1
 '@T6G_MB_LIB.T6G(SCH_1):PAGE265_I29@PURE_QUANTA.TP_TDR_4P_FTS(CHIPS)':
 C_PATH='@t6g_mb_lib.t6g(sch_1):page265_i29@pure_quanta.tp_tdr_4p_fts(chips)',
 P_PATH='@t6g_mb_lib.t6g(sch_1):page260_i29@pure_quanta.tp_tdr_4p_fts(chips)',
 PATH='I29',
 DRAWING='@T6G_MB_LIB.T6G(SCH_1):PAGE265',
 MATERIAL='EMPTY',
 PHYS_PAGE='260',
 XY='(-5025,625)',
 ROT='0',
 VER='1',
 PACK_TYPE='TH',
 LOCATION='X6',
 CDS_LIB='pure_quanta',
 CDS_PART_NAME='TP_TDR_4P_FTS_TH-TP_TDR_4P_DIP,EMPTY,TP15',
 PART_NUMBER='TP15',
 VALUE='TP_TDR_4P_DIP',
 PRIM_FILE='./archive_libs/logical/tp_tdr_4p_fts/chips/chips.prt';

PART_NAME
 X7 'TP_TDR_4P_FTS_TH-TP_TDR_4P_DIP,EMPTY,TP15':;

SECTION_NUMBER 1
 '@T6G_MB_LIB.T6G(SCH_1):PAGE265_I84@PURE_QUANTA.TP_TDR_4P_FTS(CHIPS)':
 C_PATH='@t6g_mb_lib.t6g(sch_1):page265_i84@pure_quanta.tp_tdr_4p_fts(chips)',
 P_PATH='@t6g_mb_lib.t6g(sch_1):page260_i84@pure_quanta.tp_tdr_4p_fts(chips)',
 PATH='I84',
 DRAWING='@T6G_MB_LIB.T6G(SCH_1):PAGE265',
 MATERIAL='EMPTY',
 PHYS_PAGE='260',
 XY='(-3700,5825)',
 ROT='4',
 VER='1',
 PACK_TYPE='TH',
 LOCATION='X7',
 CDS_LIB='pure_quanta',
 CDS_PART_NAME='TP_TDR_4P_FTS_TH-TP_TDR_4P_DIP,EMPTY,TP15',
 PART_NUMBER='TP15',
 VALUE='TP_TDR_4P_DIP',
 PRIM_FILE='./archive_libs/logical/tp_tdr_4p_fts/chips/chips.prt';

PART_NAME
 X8 'TP_TDR_4P_FTS_TH-TP_TDR_4P_DIP,EMPTY,TP15':;

SECTION_NUMBER 1
 '@T6G_MB_LIB.T6G(SCH_1):PAGE265_I82@PURE_QUANTA.TP_TDR_4P_FTS(CHIPS)':
 C_PATH='@t6g_mb_lib.t6g(sch_1):page265_i82@pure_quanta.tp_tdr_4p_fts(chips)',
 P_PATH='@t6g_mb_lib.t6g(sch_1):page260_i82@pure_quanta.tp_tdr_4p_fts(chips)',
 PATH='I82',
 DRAWING='@T6G_MB_LIB.T6G(SCH_1):PAGE265',
 MATERIAL='EMPTY',
 PHYS_PAGE='260',
 XY='(-3700,5050)',
 ROT='4',
 VER='1',
 PACK_TYPE='TH',
 LOCATION='X8',
 CDS_LIB='pure_quanta',
 CDS_PART_NAME='TP_TDR_4P_FTS_TH-TP_TDR_4P_DIP,EMPTY,TP15',
 PART_NUMBER='TP15',
 VALUE='TP_TDR_4P_DIP',
 PRIM_FILE='./archive_libs/logical/tp_tdr_4p_fts/chips/chips.prt';

PART_NAME
 X9 'TP_TDR_4P_FTS_TH-TP_TDR_4P_DIP,EMPTY,TP15':;

SECTION_NUMBER 1
 '@T6G_MB_LIB.T6G(SCH_1):PAGE265_I62@PURE_QUANTA.TP_TDR_4P_FTS(CHIPS)':
 C_PATH='@t6g_mb_lib.t6g(sch_1):page265_i62@pure_quanta.tp_tdr_4p_fts(chips)',
 P_PATH='@t6g_mb_lib.t6g(sch_1):page260_i62@pure_quanta.tp_tdr_4p_fts(chips)',
 PATH='I62',
 DRAWING='@T6G_MB_LIB.T6G(SCH_1):PAGE265',
 MATERIAL='EMPTY',
 PHYS_PAGE='260',
 XY='(-3700,4275)',
 ROT='4',
 VER='1',
 PACK_TYPE='TH',
 LOCATION='X9',
 CDS_LIB='pure_quanta',
 CDS_PART_NAME='TP_TDR_4P_FTS_TH-TP_TDR_4P_DIP,EMPTY,TP15',
 PART_NUMBER='TP15',
 VALUE='TP_TDR_4P_DIP',
 PRIM_FILE='./archive_libs/logical/tp_tdr_4p_fts/chips/chips.prt';

PART_NAME
 X10 'TP_TDR_4P_FTS_TH-TP_TDR_4P_DIP,EMPTY,TP15':;

SECTION_NUMBER 1
 '@T6G_MB_LIB.T6G(SCH_1):PAGE265_I61@PURE_QUANTA.TP_TDR_4P_FTS(CHIPS)':
 C_PATH='@t6g_mb_lib.t6g(sch_1):page265_i61@pure_quanta.tp_tdr_4p_fts(chips)',
 P_PATH='@t6g_mb_lib.t6g(sch_1):page260_i61@pure_quanta.tp_tdr_4p_fts(chips)',
 PATH='I61',
 DRAWING='@T6G_MB_LIB.T6G(SCH_1):PAGE265',
 MATERIAL='EMPTY',
 PHYS_PAGE='260',
 XY='(-3700,3500)',
 ROT='4',
 VER='1',
 PACK_TYPE='TH',
 LOCATION='X10',
 CDS_LIB='pure_quanta',
 CDS_PART_NAME='TP_TDR_4P_FTS_TH-TP_TDR_4P_DIP,EMPTY,TP15',
 PART_NUMBER='TP15',
 VALUE='TP_TDR_4P_DIP',
 PRIM_FILE='./archive_libs/logical/tp_tdr_4p_fts/chips/chips.prt';

PART_NAME
 X11 'TP_TDR_4P_FTS_TH-TP_TDR_4P_DIP,EMPTY,TP15':;

SECTION_NUMBER 1
 '@T6G_MB_LIB.T6G(SCH_1):PAGE265_I96@PURE_QUANTA.TP_TDR_4P_FTS(CHIPS)':
 C_PATH='@t6g_mb_lib.t6g(sch_1):page265_i96@pure_quanta.tp_tdr_4p_fts(chips)',
 P_PATH='@t6g_mb_lib.t6g(sch_1):page260_i96@pure_quanta.tp_tdr_4p_fts(chips)',
 PATH='I96',
 DRAWING='@T6G_MB_LIB.T6G(SCH_1):PAGE265',
 MATERIAL='EMPTY',
 PHYS_PAGE='260',
 XY='(-3700,2725)',
 ROT='4',
 VER='1',
 PACK_TYPE='TH',
 LOCATION='X11',
 CDS_LIB='pure_quanta',
 CDS_PART_NAME='TP_TDR_4P_FTS_TH-TP_TDR_4P_DIP,EMPTY,TP15',
 PART_NUMBER='TP15',
 VALUE='TP_TDR_4P_DIP',
 PRIM_FILE='./archive_libs/logical/tp_tdr_4p_fts/chips/chips.prt';

PART_NAME
 X12 'TP_TDR_4P_FTS_TH-TP_TDR_4P_DIP,EMPTY,TP15':;

SECTION_NUMBER 1
 '@T6G_MB_LIB.T6G(SCH_1):PAGE265_I49@PURE_QUANTA.TP_TDR_4P_FTS(CHIPS)':
 C_PATH='@t6g_mb_lib.t6g(sch_1):page265_i49@pure_quanta.tp_tdr_4p_fts(chips)',
 P_PATH='@t6g_mb_lib.t6g(sch_1):page260_i49@pure_quanta.tp_tdr_4p_fts(chips)',
 PATH='I49',
 DRAWING='@T6G_MB_LIB.T6G(SCH_1):PAGE265',
 MATERIAL='EMPTY',
 PHYS_PAGE='260',
 XY='(-3700,625)',
 ROT='4',
 VER='1',
 PACK_TYPE='TH',
 LOCATION='X12',
 CDS_LIB='pure_quanta',
 CDS_PART_NAME='TP_TDR_4P_FTS_TH-TP_TDR_4P_DIP,EMPTY,TP15',
 PART_NUMBER='TP15',
 VALUE='TP_TDR_4P_DIP',
 PRIM_FILE='./archive_libs/logical/tp_tdr_4p_fts/chips/chips.prt';

PART_NAME
 X25 'TP_TDR_4P_FTS_TH-TP_TDR_4P_DIP,EMPTY,TP15':;

SECTION_NUMBER 1
 '@T6G_MB_LIB.T6G(SCH_1):PAGE265_I31@PURE_QUANTA.TP_TDR_4P_FTS(CHIPS)':
 C_PATH='@t6g_mb_lib.t6g(sch_1):page265_i31@pure_quanta.tp_tdr_4p_fts(chips)',
 P_PATH='@t6g_mb_lib.t6g(sch_1):page260_i31@pure_quanta.tp_tdr_4p_fts(chips)',
 PATH='I31',
 DRAWING='@T6G_MB_LIB.T6G(SCH_1):PAGE265',
 MATERIAL='EMPTY',
 PHYS_PAGE='260',
 XY='(-5025,2050)',
 ROT='0',
 VER='1',
 PACK_TYPE='TH',
 LOCATION='X25',
 CDS_LIB='pure_quanta',
 CDS_PART_NAME='TP_TDR_4P_FTS_TH-TP_TDR_4P_DIP,EMPTY,TP15',
 PART_NUMBER='TP15',
 VALUE='TP_TDR_4P_DIP',
 PRIM_FILE='./archive_libs/logical/tp_tdr_4p_fts/chips/chips.prt';

PART_NAME
 X26 'TP_TDR_4P_FTS_TH-TP_TDR_4P_DIP,EMPTY,TP15':;

SECTION_NUMBER 1
 '@T6G_MB_LIB.T6G(SCH_1):PAGE265_I30@PURE_QUANTA.TP_TDR_4P_FTS(CHIPS)':
 C_PATH='@t6g_mb_lib.t6g(sch_1):page265_i30@pure_quanta.tp_tdr_4p_fts(chips)',
 P_PATH='@t6g_mb_lib.t6g(sch_1):page260_i30@pure_quanta.tp_tdr_4p_fts(chips)',
 PATH='I30',
 DRAWING='@T6G_MB_LIB.T6G(SCH_1):PAGE265',
 MATERIAL='EMPTY',
 PHYS_PAGE='260',
 XY='(-5025,1275)',
 ROT='0',
 VER='1',
 PACK_TYPE='TH',
 LOCATION='X26',
 CDS_LIB='pure_quanta',
 CDS_PART_NAME='TP_TDR_4P_FTS_TH-TP_TDR_4P_DIP,EMPTY,TP15',
 PART_NUMBER='TP15',
 VALUE='TP_TDR_4P_DIP',
 PRIM_FILE='./archive_libs/logical/tp_tdr_4p_fts/chips/chips.prt';

PART_NAME
 X27 'TP_TDR_4P_FTS_TH-TP_TDR_4P_DIP,EMPTY,TP15':;

SECTION_NUMBER 1
 '@T6G_MB_LIB.T6G(SCH_1):PAGE265_I53@PURE_QUANTA.TP_TDR_4P_FTS(CHIPS)':
 C_PATH='@t6g_mb_lib.t6g(sch_1):page265_i53@pure_quanta.tp_tdr_4p_fts(chips)',
 P_PATH='@t6g_mb_lib.t6g(sch_1):page260_i53@pure_quanta.tp_tdr_4p_fts(chips)',
 PATH='I53',
 DRAWING='@T6G_MB_LIB.T6G(SCH_1):PAGE265',
 MATERIAL='EMPTY',
 PHYS_PAGE='260',
 XY='(-3700,2050)',
 ROT='4',
 VER='1',
 PACK_TYPE='TH',
 LOCATION='X27',
 CDS_LIB='pure_quanta',
 CDS_PART_NAME='TP_TDR_4P_FTS_TH-TP_TDR_4P_DIP,EMPTY,TP15',
 PART_NUMBER='TP15',
 VALUE='TP_TDR_4P_DIP',
 PRIM_FILE='./archive_libs/logical/tp_tdr_4p_fts/chips/chips.prt';

PART_NAME
 X28 'TP_TDR_4P_FTS_TH-TP_TDR_4P_DIP,EMPTY,TP15':;

SECTION_NUMBER 1
 '@T6G_MB_LIB.T6G(SCH_1):PAGE265_I52@PURE_QUANTA.TP_TDR_4P_FTS(CHIPS)':
 C_PATH='@t6g_mb_lib.t6g(sch_1):page265_i52@pure_quanta.tp_tdr_4p_fts(chips)',
 P_PATH='@t6g_mb_lib.t6g(sch_1):page260_i52@pure_quanta.tp_tdr_4p_fts(chips)',
 PATH='I52',
 DRAWING='@T6G_MB_LIB.T6G(SCH_1):PAGE265',
 MATERIAL='EMPTY',
 PHYS_PAGE='260',
 XY='(-3700,1275)',
 ROT='4',
 VER='1',
 PACK_TYPE='TH',
 LOCATION='X28',
 CDS_LIB='pure_quanta',
 CDS_PART_NAME='TP_TDR_4P_FTS_TH-TP_TDR_4P_DIP,EMPTY,TP15',
 PART_NUMBER='TP15',
 VALUE='TP_TDR_4P_DIP',
 PRIM_FILE='./archive_libs/logical/tp_tdr_4p_fts/chips/chips.prt';

PART_NAME
 X8001 'TP_TDR_4P_FTS_TH-TP_TDR_4P_DIP,EMPTY,TP15':;

SECTION_NUMBER 1
 '@T6G_MB_LIB.T6G(SCH_1):PAGE265_I89@PURE_QUANTA.TP_TDR_4P_FTS(CHIPS)':
 C_PATH='@t6g_mb_lib.t6g(sch_1):page265_i89@pure_quanta.tp_tdr_4p_fts(chips)',
 P_PATH='@t6g_mb_lib.t6g(sch_1):page260_i89@pure_quanta.tp_tdr_4p_fts(chips)',
 PATH='I89',
 DRAWING='@T6G_MB_LIB.T6G(SCH_1):PAGE265',
 MATERIAL='EMPTY',
 PHYS_PAGE='260',
 XY='(-2200,5850)',
 ROT='0',
 VER='1',
 PACK_TYPE='TH',
 LOCATION='X8001',
 CDS_LIB='pure_quanta',
 CDS_PART_NAME='TP_TDR_4P_FTS_TH-TP_TDR_4P_DIP,EMPTY,TP15',
 PART_NUMBER='TP15',
 VALUE='TP_TDR_4P_DIP',
 PRIM_FILE='./archive_libs/logical/tp_tdr_4p_fts/chips/chips.prt';

PART_NAME
 X8002 'TP_TDR_4P_FTS_TH-TP_TDR_4P_DIP,EMPTY,TP15':;

SECTION_NUMBER 1
 '@T6G_MB_LIB.T6G(SCH_1):PAGE265_I87@PURE_QUANTA.TP_TDR_4P_FTS(CHIPS)':
 C_PATH='@t6g_mb_lib.t6g(sch_1):page265_i87@pure_quanta.tp_tdr_4p_fts(chips)',
 P_PATH='@t6g_mb_lib.t6g(sch_1):page260_i87@pure_quanta.tp_tdr_4p_fts(chips)',
 PATH='I87',
 DRAWING='@T6G_MB_LIB.T6G(SCH_1):PAGE265',
 MATERIAL='EMPTY',
 PHYS_PAGE='260',
 XY='(-2200,5075)',
 ROT='0',
 VER='1',
 PACK_TYPE='TH',
 LOCATION='X8002',
 CDS_LIB='pure_quanta',
 CDS_PART_NAME='TP_TDR_4P_FTS_TH-TP_TDR_4P_DIP,EMPTY,TP15',
 PART_NUMBER='TP15',
 VALUE='TP_TDR_4P_DIP',
 PRIM_FILE='./archive_libs/logical/tp_tdr_4p_fts/chips/chips.prt';

PART_NAME
 X8003 'TP_TDR_4P_FTS_TH-TP_TDR_4P_DIP,EMPTY,TP15':;

SECTION_NUMBER 1
 '@T6G_MB_LIB.T6G(SCH_1):PAGE265_I70@PURE_QUANTA.TP_TDR_4P_FTS(CHIPS)':
 C_PATH='@t6g_mb_lib.t6g(sch_1):page265_i70@pure_quanta.tp_tdr_4p_fts(chips)',
 P_PATH='@t6g_mb_lib.t6g(sch_1):page260_i70@pure_quanta.tp_tdr_4p_fts(chips)',
 PATH='I70',
 DRAWING='@T6G_MB_LIB.T6G(SCH_1):PAGE265',
 MATERIAL='EMPTY',
 PHYS_PAGE='260',
 XY='(-2200,4300)',
 ROT='0',
 VER='1',
 PACK_TYPE='TH',
 LOCATION='X8003',
 CDS_LIB='pure_quanta',
 CDS_PART_NAME='TP_TDR_4P_FTS_TH-TP_TDR_4P_DIP,EMPTY,TP15',
 PART_NUMBER='TP15',
 VALUE='TP_TDR_4P_DIP',
 PRIM_FILE='./archive_libs/logical/tp_tdr_4p_fts/chips/chips.prt';

PART_NAME
 X8004 'TP_TDR_4P_FTS_TH-TP_TDR_4P_DIP,EMPTY,TP15':;

SECTION_NUMBER 1
 '@T6G_MB_LIB.T6G(SCH_1):PAGE265_I68@PURE_QUANTA.TP_TDR_4P_FTS(CHIPS)':
 C_PATH='@t6g_mb_lib.t6g(sch_1):page265_i68@pure_quanta.tp_tdr_4p_fts(chips)',
 P_PATH='@t6g_mb_lib.t6g(sch_1):page260_i68@pure_quanta.tp_tdr_4p_fts(chips)',
 PATH='I68',
 DRAWING='@T6G_MB_LIB.T6G(SCH_1):PAGE265',
 MATERIAL='EMPTY',
 PHYS_PAGE='260',
 XY='(-2200,3525)',
 ROT='0',
 VER='1',
 PACK_TYPE='TH',
 LOCATION='X8004',
 CDS_LIB='pure_quanta',
 CDS_PART_NAME='TP_TDR_4P_FTS_TH-TP_TDR_4P_DIP,EMPTY,TP15',
 PART_NUMBER='TP15',
 VALUE='TP_TDR_4P_DIP',
 PRIM_FILE='./archive_libs/logical/tp_tdr_4p_fts/chips/chips.prt';

PART_NAME
 X8005 'TP_TDR_4P_FTS_TH-TP_TDR_4P_DIP,EMPTY,TP15':;

SECTION_NUMBER 1
 '@T6G_MB_LIB.T6G(SCH_1):PAGE265_I66@PURE_QUANTA.TP_TDR_4P_FTS(CHIPS)':
 C_PATH='@t6g_mb_lib.t6g(sch_1):page265_i66@pure_quanta.tp_tdr_4p_fts(chips)',
 P_PATH='@t6g_mb_lib.t6g(sch_1):page260_i66@pure_quanta.tp_tdr_4p_fts(chips)',
 PATH='I66',
 DRAWING='@T6G_MB_LIB.T6G(SCH_1):PAGE265',
 MATERIAL='EMPTY',
 PHYS_PAGE='260',
 XY='(-2200,2750)',
 ROT='0',
 VER='1',
 PACK_TYPE='TH',
 LOCATION='X8005',
 CDS_LIB='pure_quanta',
 CDS_PART_NAME='TP_TDR_4P_FTS_TH-TP_TDR_4P_DIP,EMPTY,TP15',
 PART_NUMBER='TP15',
 VALUE='TP_TDR_4P_DIP',
 PRIM_FILE='./archive_libs/logical/tp_tdr_4p_fts/chips/chips.prt';

PART_NAME
 X8006 'TP_TDR_4P_FTS_TH-TP_TDR_4P_DIP,EMPTY,TP15':;

SECTION_NUMBER 1
 '@T6G_MB_LIB.T6G(SCH_1):PAGE265_I56@PURE_QUANTA.TP_TDR_4P_FTS(CHIPS)':
 C_PATH='@t6g_mb_lib.t6g(sch_1):page265_i56@pure_quanta.tp_tdr_4p_fts(chips)',
 P_PATH='@t6g_mb_lib.t6g(sch_1):page260_i56@pure_quanta.tp_tdr_4p_fts(chips)',
 PATH='I56',
 DRAWING='@T6G_MB_LIB.T6G(SCH_1):PAGE265',
 MATERIAL='EMPTY',
 PHYS_PAGE='260',
 XY='(-2200,650)',
 ROT='0',
 VER='1',
 PACK_TYPE='TH',
 LOCATION='X8006',
 CDS_LIB='pure_quanta',
 CDS_PART_NAME='TP_TDR_4P_FTS_TH-TP_TDR_4P_DIP,EMPTY,TP15',
 PART_NUMBER='TP15',
 VALUE='TP_TDR_4P_DIP',
 PRIM_FILE='./archive_libs/logical/tp_tdr_4p_fts/chips/chips.prt';

PART_NAME
 X8007 'TP_TDR_4P_FTS_TH-TP_TDR_4P_DIP,EMPTY,TP15':;

SECTION_NUMBER 1
 '@T6G_MB_LIB.T6G(SCH_1):PAGE265_I92@PURE_QUANTA.TP_TDR_4P_FTS(CHIPS)':
 C_PATH='@t6g_mb_lib.t6g(sch_1):page265_i92@pure_quanta.tp_tdr_4p_fts(chips)',
 P_PATH='@t6g_mb_lib.t6g(sch_1):page260_i92@pure_quanta.tp_tdr_4p_fts(chips)',
 PATH='I92',
 DRAWING='@T6G_MB_LIB.T6G(SCH_1):PAGE265',
 MATERIAL='EMPTY',
 PHYS_PAGE='260',
 XY='(-875,5850)',
 ROT='4',
 VER='1',
 PACK_TYPE='TH',
 LOCATION='X8007',
 CDS_LIB='pure_quanta',
 CDS_PART_NAME='TP_TDR_4P_FTS_TH-TP_TDR_4P_DIP,EMPTY,TP15',
 PART_NUMBER='TP15',
 VALUE='TP_TDR_4P_DIP',
 PRIM_FILE='./archive_libs/logical/tp_tdr_4p_fts/chips/chips.prt';

PART_NAME
 X8008 'TP_TDR_4P_FTS_TH-TP_TDR_4P_DIP,EMPTY,TP15':;

SECTION_NUMBER 1
 '@T6G_MB_LIB.T6G(SCH_1):PAGE265_I90@PURE_QUANTA.TP_TDR_4P_FTS(CHIPS)':
 C_PATH='@t6g_mb_lib.t6g(sch_1):page265_i90@pure_quanta.tp_tdr_4p_fts(chips)',
 P_PATH='@t6g_mb_lib.t6g(sch_1):page260_i90@pure_quanta.tp_tdr_4p_fts(chips)',
 PATH='I90',
 DRAWING='@T6G_MB_LIB.T6G(SCH_1):PAGE265',
 MATERIAL='EMPTY',
 PHYS_PAGE='260',
 XY='(-875,5075)',
 ROT='4',
 VER='1',
 PACK_TYPE='TH',
 LOCATION='X8008',
 CDS_LIB='pure_quanta',
 CDS_PART_NAME='TP_TDR_4P_FTS_TH-TP_TDR_4P_DIP,EMPTY,TP15',
 PART_NUMBER='TP15',
 VALUE='TP_TDR_4P_DIP',
 PRIM_FILE='./archive_libs/logical/tp_tdr_4p_fts/chips/chips.prt';

PART_NAME
 X8009 'TP_TDR_4P_FTS_TH-TP_TDR_4P_DIP,EMPTY,TP15':;

SECTION_NUMBER 1
 '@T6G_MB_LIB.T6G(SCH_1):PAGE265_I79@PURE_QUANTA.TP_TDR_4P_FTS(CHIPS)':
 C_PATH='@t6g_mb_lib.t6g(sch_1):page265_i79@pure_quanta.tp_tdr_4p_fts(chips)',
 P_PATH='@t6g_mb_lib.t6g(sch_1):page260_i79@pure_quanta.tp_tdr_4p_fts(chips)',
 PATH='I79',
 DRAWING='@T6G_MB_LIB.T6G(SCH_1):PAGE265',
 MATERIAL='EMPTY',
 PHYS_PAGE='260',
 XY='(-875,4300)',
 ROT='4',
 VER='1',
 PACK_TYPE='TH',
 LOCATION='X8009',
 CDS_LIB='pure_quanta',
 CDS_PART_NAME='TP_TDR_4P_FTS_TH-TP_TDR_4P_DIP,EMPTY,TP15',
 PART_NUMBER='TP15',
 VALUE='TP_TDR_4P_DIP',
 PRIM_FILE='./archive_libs/logical/tp_tdr_4p_fts/chips/chips.prt';

PART_NAME
 X8010 'TP_TDR_4P_FTS_TH-TP_TDR_4P_DIP,EMPTY,TP15':;

SECTION_NUMBER 1
 '@T6G_MB_LIB.T6G(SCH_1):PAGE265_I78@PURE_QUANTA.TP_TDR_4P_FTS(CHIPS)':
 C_PATH='@t6g_mb_lib.t6g(sch_1):page265_i78@pure_quanta.tp_tdr_4p_fts(chips)',
 P_PATH='@t6g_mb_lib.t6g(sch_1):page260_i78@pure_quanta.tp_tdr_4p_fts(chips)',
 PATH='I78',
 DRAWING='@T6G_MB_LIB.T6G(SCH_1):PAGE265',
 MATERIAL='EMPTY',
 PHYS_PAGE='260',
 XY='(-875,3525)',
 ROT='4',
 VER='1',
 PACK_TYPE='TH',
 LOCATION='X8010',
 CDS_LIB='pure_quanta',
 CDS_PART_NAME='TP_TDR_4P_FTS_TH-TP_TDR_4P_DIP,EMPTY,TP15',
 PART_NUMBER='TP15',
 VALUE='TP_TDR_4P_DIP',
 PRIM_FILE='./archive_libs/logical/tp_tdr_4p_fts/chips/chips.prt';

PART_NAME
 X8011 'TP_TDR_4P_FTS_TH-TP_TDR_4P_DIP,EMPTY,TP15':;

SECTION_NUMBER 1
 '@T6G_MB_LIB.T6G(SCH_1):PAGE265_I76@PURE_QUANTA.TP_TDR_4P_FTS(CHIPS)':
 C_PATH='@t6g_mb_lib.t6g(sch_1):page265_i76@pure_quanta.tp_tdr_4p_fts(chips)',
 P_PATH='@t6g_mb_lib.t6g(sch_1):page260_i76@pure_quanta.tp_tdr_4p_fts(chips)',
 PATH='I76',
 DRAWING='@T6G_MB_LIB.T6G(SCH_1):PAGE265',
 MATERIAL='EMPTY',
 PHYS_PAGE='260',
 XY='(-875,2750)',
 ROT='4',
 VER='1',
 PACK_TYPE='TH',
 LOCATION='X8011',
 CDS_LIB='pure_quanta',
 CDS_PART_NAME='TP_TDR_4P_FTS_TH-TP_TDR_4P_DIP,EMPTY,TP15',
 PART_NUMBER='TP15',
 VALUE='TP_TDR_4P_DIP',
 PRIM_FILE='./archive_libs/logical/tp_tdr_4p_fts/chips/chips.prt';

PART_NAME
 X8012 'TP_TDR_4P_FTS_TH-TP_TDR_4P_DIP,EMPTY,TP15':;

SECTION_NUMBER 1
 '@T6G_MB_LIB.T6G(SCH_1):PAGE265_I94@PURE_QUANTA.TP_TDR_4P_FTS(CHIPS)':
 C_PATH='@t6g_mb_lib.t6g(sch_1):page265_i94@pure_quanta.tp_tdr_4p_fts(chips)',
 P_PATH='@t6g_mb_lib.t6g(sch_1):page260_i94@pure_quanta.tp_tdr_4p_fts(chips)',
 PATH='I94',
 DRAWING='@T6G_MB_LIB.T6G(SCH_1):PAGE265',
 MATERIAL='EMPTY',
 PHYS_PAGE='260',
 XY='(-875,650)',
 ROT='4',
 VER='1',
 PACK_TYPE='TH',
 LOCATION='X8012',
 CDS_LIB='pure_quanta',
 CDS_PART_NAME='TP_TDR_4P_FTS_TH-TP_TDR_4P_DIP,EMPTY,TP15',
 PART_NUMBER='TP15',
 VALUE='TP_TDR_4P_DIP',
 PRIM_FILE='./archive_libs/logical/tp_tdr_4p_fts/chips/chips.prt';

PART_NAME
 X8025 'TP_TDR_4P_FTS_TH-TP_TDR_4P_DIP,EMPTY,TP15':;

SECTION_NUMBER 1
 '@T6G_MB_LIB.T6G(SCH_1):PAGE265_I60@PURE_QUANTA.TP_TDR_4P_FTS(CHIPS)':
 C_PATH='@t6g_mb_lib.t6g(sch_1):page265_i60@pure_quanta.tp_tdr_4p_fts(chips)',
 P_PATH='@t6g_mb_lib.t6g(sch_1):page260_i60@pure_quanta.tp_tdr_4p_fts(chips)',
 PATH='I60',
 DRAWING='@T6G_MB_LIB.T6G(SCH_1):PAGE265',
 MATERIAL='EMPTY',
 PHYS_PAGE='260',
 XY='(-2200,2075)',
 ROT='0',
 VER='1',
 PACK_TYPE='TH',
 LOCATION='X8025',
 CDS_LIB='pure_quanta',
 CDS_PART_NAME='TP_TDR_4P_FTS_TH-TP_TDR_4P_DIP,EMPTY,TP15',
 PART_NUMBER='TP15',
 VALUE='TP_TDR_4P_DIP',
 PRIM_FILE='./archive_libs/logical/tp_tdr_4p_fts/chips/chips.prt';

PART_NAME
 X8026 'TP_TDR_4P_FTS_TH-TP_TDR_4P_DIP,EMPTY,TP15':;

SECTION_NUMBER 1
 '@T6G_MB_LIB.T6G(SCH_1):PAGE265_I58@PURE_QUANTA.TP_TDR_4P_FTS(CHIPS)':
 C_PATH='@t6g_mb_lib.t6g(sch_1):page265_i58@pure_quanta.tp_tdr_4p_fts(chips)',
 P_PATH='@t6g_mb_lib.t6g(sch_1):page260_i58@pure_quanta.tp_tdr_4p_fts(chips)',
 PATH='I58',
 DRAWING='@T6G_MB_LIB.T6G(SCH_1):PAGE265',
 MATERIAL='EMPTY',
 PHYS_PAGE='260',
 XY='(-2200,1300)',
 ROT='0',
 VER='1',
 PACK_TYPE='TH',
 LOCATION='X8026',
 CDS_LIB='pure_quanta',
 CDS_PART_NAME='TP_TDR_4P_FTS_TH-TP_TDR_4P_DIP,EMPTY,TP15',
 PART_NUMBER='TP15',
 VALUE='TP_TDR_4P_DIP',
 PRIM_FILE='./archive_libs/logical/tp_tdr_4p_fts/chips/chips.prt';

PART_NAME
 X8027 'TP_TDR_4P_FTS_TH-TP_TDR_4P_DIP,EMPTY,TP15':;

SECTION_NUMBER 1
 '@T6G_MB_LIB.T6G(SCH_1):PAGE265_I74@PURE_QUANTA.TP_TDR_4P_FTS(CHIPS)':
 C_PATH='@t6g_mb_lib.t6g(sch_1):page265_i74@pure_quanta.tp_tdr_4p_fts(chips)',
 P_PATH='@t6g_mb_lib.t6g(sch_1):page260_i74@pure_quanta.tp_tdr_4p_fts(chips)',
 PATH='I74',
 DRAWING='@T6G_MB_LIB.T6G(SCH_1):PAGE265',
 MATERIAL='EMPTY',
 PHYS_PAGE='260',
 XY='(-875,2075)',
 ROT='4',
 VER='1',
 PACK_TYPE='TH',
 LOCATION='X8027',
 CDS_LIB='pure_quanta',
 CDS_PART_NAME='TP_TDR_4P_FTS_TH-TP_TDR_4P_DIP,EMPTY,TP15',
 PART_NUMBER='TP15',
 VALUE='TP_TDR_4P_DIP',
 PRIM_FILE='./archive_libs/logical/tp_tdr_4p_fts/chips/chips.prt';

PART_NAME
 X8028 'TP_TDR_4P_FTS_TH-TP_TDR_4P_DIP,EMPTY,TP15':;

SECTION_NUMBER 1
 '@T6G_MB_LIB.T6G(SCH_1):PAGE265_I73@PURE_QUANTA.TP_TDR_4P_FTS(CHIPS)':
 C_PATH='@t6g_mb_lib.t6g(sch_1):page265_i73@pure_quanta.tp_tdr_4p_fts(chips)',
 P_PATH='@t6g_mb_lib.t6g(sch_1):page260_i73@pure_quanta.tp_tdr_4p_fts(chips)',
 PATH='I73',
 DRAWING='@T6G_MB_LIB.T6G(SCH_1):PAGE265',
 MATERIAL='EMPTY',
 PHYS_PAGE='260',
 XY='(-875,1300)',
 ROT='4',
 VER='1',
 PACK_TYPE='TH',
 LOCATION='X8028',
 CDS_LIB='pure_quanta',
 CDS_PART_NAME='TP_TDR_4P_FTS_TH-TP_TDR_4P_DIP,EMPTY,TP15',
 PART_NUMBER='TP15',
 VALUE='TP_TDR_4P_DIP',
 PRIM_FILE='./archive_libs/logical/tp_tdr_4p_fts/chips/chips.prt';

PART_NAME
 X9002 'TP_TDR_4P_FTS_TH-TP_TDR_4P_DIP,EMPTY,TP15':;

SECTION_NUMBER 1
 '@T6G_MB_LIB.T6G(SCH_1):PAGE266_I12@PURE_QUANTA.TP_TDR_4P_FTS(CHIPS)':
 C_PATH='@t6g_mb_lib.t6g(sch_1):page266_i12@pure_quanta.tp_tdr_4p_fts(chips)',
 P_PATH='@t6g_mb_lib.t6g(sch_1):page261_i12@pure_quanta.tp_tdr_4p_fts(chips)',
 PATH='I12',
 DRAWING='@T6G_MB_LIB.T6G(SCH_1):PAGE266',
 MATERIAL='EMPTY',
 PHYS_PAGE='261',
 XY='(-7000,5775)',
 ROT='0',
 VER='1',
 PACK_TYPE='TH',
 LOCATION='X9002',
 CDS_LIB='pure_quanta',
 CDS_PART_NAME='TP_TDR_4P_FTS_TH-TP_TDR_4P_DIP,EMPTY,TP15',
 PART_NUMBER='TP15',
 VALUE='TP_TDR_4P_DIP',
 PRIM_FILE='./archive_libs/logical/tp_tdr_4p_fts/chips/chips.prt';

PART_NAME
 X9003 'TP_TDR_4P_FTS_TH-TP_TDR_4P_DIP,EMPTY,TP15':;

SECTION_NUMBER 1
 '@T6G_MB_LIB.T6G(SCH_1):PAGE266_I10@PURE_QUANTA.TP_TDR_4P_FTS(CHIPS)':
 C_PATH='@t6g_mb_lib.t6g(sch_1):page266_i10@pure_quanta.tp_tdr_4p_fts(chips)',
 P_PATH='@t6g_mb_lib.t6g(sch_1):page261_i10@pure_quanta.tp_tdr_4p_fts(chips)',
 PATH='I10',
 DRAWING='@T6G_MB_LIB.T6G(SCH_1):PAGE266',
 MATERIAL='EMPTY',
 PHYS_PAGE='261',
 XY='(-7000,5000)',
 ROT='0',
 VER='1',
 PACK_TYPE='TH',
 LOCATION='X9003',
 CDS_LIB='pure_quanta',
 CDS_PART_NAME='TP_TDR_4P_FTS_TH-TP_TDR_4P_DIP,EMPTY,TP15',
 PART_NUMBER='TP15',
 VALUE='TP_TDR_4P_DIP',
 PRIM_FILE='./archive_libs/logical/tp_tdr_4p_fts/chips/chips.prt';

PART_NAME
 X9004 'TP_TDR_4P_FTS_TH-TP_TDR_4P_DIP,EMPTY,TP15':;

SECTION_NUMBER 1
 '@T6G_MB_LIB.T6G(SCH_1):PAGE266_I8@PURE_QUANTA.TP_TDR_4P_FTS(CHIPS)':
 C_PATH='@t6g_mb_lib.t6g(sch_1):page266_i8@pure_quanta.tp_tdr_4p_fts(chips)',
 P_PATH='@t6g_mb_lib.t6g(sch_1):page261_i8@pure_quanta.tp_tdr_4p_fts(chips)',
 PATH='I8',
 DRAWING='@T6G_MB_LIB.T6G(SCH_1):PAGE266',
 MATERIAL='EMPTY',
 PHYS_PAGE='261',
 XY='(-7000,4225)',
 ROT='0',
 VER='1',
 PACK_TYPE='TH',
 LOCATION='X9004',
 CDS_LIB='pure_quanta',
 CDS_PART_NAME='TP_TDR_4P_FTS_TH-TP_TDR_4P_DIP,EMPTY,TP15',
 PART_NUMBER='TP15',
 VALUE='TP_TDR_4P_DIP',
 PRIM_FILE='./archive_libs/logical/tp_tdr_4p_fts/chips/chips.prt';

PART_NAME
 X9005 'TP_TDR_4P_FTS_TH-TP_TDR_4P_DIP,EMPTY,TP15':;

SECTION_NUMBER 1
 '@T6G_MB_LIB.T6G(SCH_1):PAGE266_I7@PURE_QUANTA.TP_TDR_4P_FTS(CHIPS)':
 C_PATH='@t6g_mb_lib.t6g(sch_1):page266_i7@pure_quanta.tp_tdr_4p_fts(chips)',
 P_PATH='@t6g_mb_lib.t6g(sch_1):page261_i7@pure_quanta.tp_tdr_4p_fts(chips)',
 PATH='I7',
 DRAWING='@T6G_MB_LIB.T6G(SCH_1):PAGE266',
 MATERIAL='EMPTY',
 PHYS_PAGE='261',
 XY='(-7000,3450)',
 ROT='0',
 VER='1',
 PACK_TYPE='TH',
 LOCATION='X9005',
 CDS_LIB='pure_quanta',
 CDS_PART_NAME='TP_TDR_4P_FTS_TH-TP_TDR_4P_DIP,EMPTY,TP15',
 PART_NUMBER='TP15',
 VALUE='TP_TDR_4P_DIP',
 PRIM_FILE='./archive_libs/logical/tp_tdr_4p_fts/chips/chips.prt';

PART_NAME
 X9008 'TP_TDR_4P_FTS_TH-TP_TDR_4P_DIP,EMPTY,TP15':;

SECTION_NUMBER 1
 '@T6G_MB_LIB.T6G(SCH_1):PAGE266_I38@PURE_QUANTA.TP_TDR_4P_FTS(CHIPS)':
 C_PATH='@t6g_mb_lib.t6g(sch_1):page266_i38@pure_quanta.tp_tdr_4p_fts(chips)',
 P_PATH='@t6g_mb_lib.t6g(sch_1):page261_i38@pure_quanta.tp_tdr_4p_fts(chips)',
 PATH='I38',
 DRAWING='@T6G_MB_LIB.T6G(SCH_1):PAGE266',
 MATERIAL='EMPTY',
 PHYS_PAGE='261',
 XY='(-5675,5775)',
 ROT='4',
 VER='1',
 PACK_TYPE='TH',
 LOCATION='X9008',
 CDS_LIB='pure_quanta',
 CDS_PART_NAME='TP_TDR_4P_FTS_TH-TP_TDR_4P_DIP,EMPTY,TP15',
 PART_NUMBER='TP15',
 VALUE='TP_TDR_4P_DIP',
 PRIM_FILE='./archive_libs/logical/tp_tdr_4p_fts/chips/chips.prt';

PART_NAME
 X9009 'TP_TDR_4P_FTS_TH-TP_TDR_4P_DIP,EMPTY,TP15':;

SECTION_NUMBER 1
 '@T6G_MB_LIB.T6G(SCH_1):PAGE266_I37@PURE_QUANTA.TP_TDR_4P_FTS(CHIPS)':
 C_PATH='@t6g_mb_lib.t6g(sch_1):page266_i37@pure_quanta.tp_tdr_4p_fts(chips)',
 P_PATH='@t6g_mb_lib.t6g(sch_1):page261_i37@pure_quanta.tp_tdr_4p_fts(chips)',
 PATH='I37',
 DRAWING='@T6G_MB_LIB.T6G(SCH_1):PAGE266',
 MATERIAL='EMPTY',
 PHYS_PAGE='261',
 XY='(-5675,5000)',
 ROT='4',
 VER='1',
 PACK_TYPE='TH',
 LOCATION='X9009',
 CDS_LIB='pure_quanta',
 CDS_PART_NAME='TP_TDR_4P_FTS_TH-TP_TDR_4P_DIP,EMPTY,TP15',
 PART_NUMBER='TP15',
 VALUE='TP_TDR_4P_DIP',
 PRIM_FILE='./archive_libs/logical/tp_tdr_4p_fts/chips/chips.prt';

PART_NAME
 X9010 'TP_TDR_4P_FTS_TH-TP_TDR_4P_DIP,EMPTY,TP15':;

SECTION_NUMBER 1
 '@T6G_MB_LIB.T6G(SCH_1):PAGE266_I16@PURE_QUANTA.TP_TDR_4P_FTS(CHIPS)':
 C_PATH='@t6g_mb_lib.t6g(sch_1):page266_i16@pure_quanta.tp_tdr_4p_fts(chips)',
 P_PATH='@t6g_mb_lib.t6g(sch_1):page261_i16@pure_quanta.tp_tdr_4p_fts(chips)',
 PATH='I16',
 DRAWING='@T6G_MB_LIB.T6G(SCH_1):PAGE266',
 MATERIAL='EMPTY',
 PHYS_PAGE='261',
 XY='(-5675,4225)',
 ROT='4',
 VER='1',
 PACK_TYPE='TH',
 LOCATION='X9010',
 CDS_LIB='pure_quanta',
 CDS_PART_NAME='TP_TDR_4P_FTS_TH-TP_TDR_4P_DIP,EMPTY,TP15',
 PART_NUMBER='TP15',
 VALUE='TP_TDR_4P_DIP',
 PRIM_FILE='./archive_libs/logical/tp_tdr_4p_fts/chips/chips.prt';

PART_NAME
 X9011 'TP_TDR_4P_FTS_TH-TP_TDR_4P_DIP,EMPTY,TP15':;

SECTION_NUMBER 1
 '@T6G_MB_LIB.T6G(SCH_1):PAGE266_I17@PURE_QUANTA.TP_TDR_4P_FTS(CHIPS)':
 C_PATH='@t6g_mb_lib.t6g(sch_1):page266_i17@pure_quanta.tp_tdr_4p_fts(chips)',
 P_PATH='@t6g_mb_lib.t6g(sch_1):page261_i17@pure_quanta.tp_tdr_4p_fts(chips)',
 PATH='I17',
 DRAWING='@T6G_MB_LIB.T6G(SCH_1):PAGE266',
 MATERIAL='EMPTY',
 PHYS_PAGE='261',
 XY='(-5675,3450)',
 ROT='4',
 VER='1',
 PACK_TYPE='TH',
 LOCATION='X9011',
 CDS_LIB='pure_quanta',
 CDS_PART_NAME='TP_TDR_4P_FTS_TH-TP_TDR_4P_DIP,EMPTY,TP15',
 PART_NUMBER='TP15',
 VALUE='TP_TDR_4P_DIP',
 PRIM_FILE='./archive_libs/logical/tp_tdr_4p_fts/chips/chips.prt';

PART_NAME
 X9025 'TP_TDR_4P_FTS_TH-TP_TDR_4P_DIP,EMPTY,TP15':;

SECTION_NUMBER 1
 '@T6G_MB_LIB.T6G(SCH_1):PAGE266_I4@PURE_QUANTA.TP_TDR_4P_FTS(CHIPS)':
 C_PATH='@t6g_mb_lib.t6g(sch_1):page266_i4@pure_quanta.tp_tdr_4p_fts(chips)',
 P_PATH='@t6g_mb_lib.t6g(sch_1):page261_i4@pure_quanta.tp_tdr_4p_fts(chips)',
 PATH='I4',
 DRAWING='@T6G_MB_LIB.T6G(SCH_1):PAGE266',
 MATERIAL='EMPTY',
 PHYS_PAGE='261',
 XY='(-7000,2775)',
 ROT='0',
 VER='1',
 PACK_TYPE='TH',
 LOCATION='X9025',
 CDS_LIB='pure_quanta',
 CDS_PART_NAME='TP_TDR_4P_FTS_TH-TP_TDR_4P_DIP,EMPTY,TP15',
 PART_NUMBER='TP15',
 VALUE='TP_TDR_4P_DIP',
 PRIM_FILE='./archive_libs/logical/tp_tdr_4p_fts/chips/chips.prt';

PART_NAME
 X9026 'TP_TDR_4P_FTS_TH-TP_TDR_4P_DIP,EMPTY,TP15':;

SECTION_NUMBER 1
 '@T6G_MB_LIB.T6G(SCH_1):PAGE266_I2@PURE_QUANTA.TP_TDR_4P_FTS(CHIPS)':
 C_PATH='@t6g_mb_lib.t6g(sch_1):page266_i2@pure_quanta.tp_tdr_4p_fts(chips)',
 P_PATH='@t6g_mb_lib.t6g(sch_1):page261_i2@pure_quanta.tp_tdr_4p_fts(chips)',
 PATH='I2',
 DRAWING='@T6G_MB_LIB.T6G(SCH_1):PAGE266',
 MATERIAL='EMPTY',
 PHYS_PAGE='261',
 XY='(-7000,2000)',
 ROT='0',
 VER='1',
 PACK_TYPE='TH',
 LOCATION='X9026',
 CDS_LIB='pure_quanta',
 CDS_PART_NAME='TP_TDR_4P_FTS_TH-TP_TDR_4P_DIP,EMPTY,TP15',
 PART_NUMBER='TP15',
 VALUE='TP_TDR_4P_DIP',
 PRIM_FILE='./archive_libs/logical/tp_tdr_4p_fts/chips/chips.prt';

PART_NAME
 X9027 'TP_TDR_4P_FTS_TH-TP_TDR_4P_DIP,EMPTY,TP15':;

SECTION_NUMBER 1
 '@T6G_MB_LIB.T6G(SCH_1):PAGE266_I15@PURE_QUANTA.TP_TDR_4P_FTS(CHIPS)':
 C_PATH='@t6g_mb_lib.t6g(sch_1):page266_i15@pure_quanta.tp_tdr_4p_fts(chips)',
 P_PATH='@t6g_mb_lib.t6g(sch_1):page261_i15@pure_quanta.tp_tdr_4p_fts(chips)',
 PATH='I15',
 DRAWING='@T6G_MB_LIB.T6G(SCH_1):PAGE266',
 MATERIAL='EMPTY',
 PHYS_PAGE='261',
 XY='(-5675,2775)',
 ROT='4',
 VER='1',
 PACK_TYPE='TH',
 LOCATION='X9027',
 CDS_LIB='pure_quanta',
 CDS_PART_NAME='TP_TDR_4P_FTS_TH-TP_TDR_4P_DIP,EMPTY,TP15',
 PART_NUMBER='TP15',
 VALUE='TP_TDR_4P_DIP',
 PRIM_FILE='./archive_libs/logical/tp_tdr_4p_fts/chips/chips.prt';

PART_NAME
 X9028 'TP_TDR_4P_FTS_TH-TP_TDR_4P_DIP,EMPTY,TP15':;

SECTION_NUMBER 1
 '@T6G_MB_LIB.T6G(SCH_1):PAGE266_I13@PURE_QUANTA.TP_TDR_4P_FTS(CHIPS)':
 C_PATH='@t6g_mb_lib.t6g(sch_1):page266_i13@pure_quanta.tp_tdr_4p_fts(chips)',
 P_PATH='@t6g_mb_lib.t6g(sch_1):page261_i13@pure_quanta.tp_tdr_4p_fts(chips)',
 PATH='I13',
 DRAWING='@T6G_MB_LIB.T6G(SCH_1):PAGE266',
 MATERIAL='EMPTY',
 PHYS_PAGE='261',
 XY='(-5675,2000)',
 ROT='4',
 VER='1',
 PACK_TYPE='TH',
 LOCATION='X9028',
 CDS_LIB='pure_quanta',
 CDS_PART_NAME='TP_TDR_4P_FTS_TH-TP_TDR_4P_DIP,EMPTY,TP15',
 PART_NUMBER='TP15',
 VALUE='TP_TDR_4P_DIP',
 PRIM_FILE='./archive_libs/logical/tp_tdr_4p_fts/chips/chips.prt';

PART_NAME
 Y2 'Q_XTAL_4P_13BI_24GND-48MHZ,SMLF,MISC,BG648000076':;

SECTION_NUMBER 1
 '@T6G_MB_LIB.T6G(SCH_1):PAGE28_I103@PURE_QUANTA.Q_XTAL_4P_13BI_24GND(CHIPS)':
 C_PATH='@t6g_mb_lib.t6g(sch_1):page28_i103@pure_quanta.q_xtal_4p_13bi_24gnd(chi~
ps)',
 P_PATH='@t6g_mb_lib.t6g(sch_1):page28_i103@pure_quanta.q_xtal_4p_13bi_24gnd(chi~
ps)',
 PATH='I103',
 DRAWING='@T6G_MB_LIB.T6G(SCH_1):PAGE28',
 PIN_NAMES_ROTATE='True',
 PART_TYPE='SMLF',
 MATERIAL='MISC',
 PHYS_PAGE='28',
 XY='(-5575,8650)',
 ROT='0',
 VER='1',
 LOCATION='Y2',
 CDS_LIB='pure_quanta',
 CDS_PART_NAME='Q_XTAL_4P_13BI_24GND-48MHZ,SMLF,MISC,BG648000076',
 PART_NUMBER='BG648000076',
 VALUE='48MHZ',
 PRIM_FILE='./archive_libs/logical/q_xtal_4p_13bi_24gnd/chips/chips.prt';

PART_NAME
 Y3 'Q_CRYSTAL_SMLF-32.768KHZ,IC,BG632768012':;

SECTION_NUMBER 1
 '@T6G_MB_LIB.T6G(SCH_1):PAGE28_I140@PURE_QUANTA.Q_CRYSTAL(CHIPS)':
 C_PATH='@t6g_mb_lib.t6g(sch_1):page28_i140@pure_quanta.q_crystal(chips)',
 P_PATH='@t6g_mb_lib.t6g(sch_1):page28_i140@pure_quanta.q_crystal(chips)',
 PATH='I140',
 DRAWING='@T6G_MB_LIB.T6G(SCH_1):PAGE28',
 MATERIAL='IC',
 PHYS_PAGE='28',
 XY='(-3350,8750)',
 ROT='0',
 VER='1',
 PACK_TYPE='SMLF',
 LOCATION='Y3',
 CDS_LIB='pure_quanta',
 CDS_PART_NAME='Q_CRYSTAL_SMLF-32.768KHZ,IC,BG632768012',
 PART_NUMBER='BG632768012',
 VALUE='32.768KHZ',
 PRIM_FILE='./archive_libs/logical/q_crystal/chips/chips.prt';

PART_NAME
 Y4 'Q_XTAL_4P_13BI_24GND-48MHZ,SMLF,MISC,BG648000076':;

SECTION_NUMBER 1
 '@T6G_MB_LIB.T6G(SCH_1):PAGE55_I12@PURE_QUANTA.Q_XTAL_4P_13BI_24GND(CHIPS)':
 C_PATH='@t6g_mb_lib.t6g(sch_1):page55_i12@pure_quanta.q_xtal_4p_13bi_24gnd(chip~
s)',
 P_PATH='@t6g_mb_lib.t6g(sch_1):page55_i12@pure_quanta.q_xtal_4p_13bi_24gnd(chip~
s)',
 PATH='I12',
 DRAWING='@T6G_MB_LIB.T6G(SCH_1):PAGE55',
 PIN_NAMES_ROTATE='True',
 PART_TYPE='SMLF',
 MATERIAL='MISC',
 PHYS_PAGE='55',
 XY='(-5525,1575)',
 ROT='0',
 VER='1',
 LOCATION='Y4',
 CDS_LIB='pure_quanta',
 CDS_PART_NAME='Q_XTAL_4P_13BI_24GND-48MHZ,SMLF,MISC,BG648000076',
 PART_NUMBER='BG648000076',
 VALUE='48MHZ',
 PRIM_FILE='./archive_libs/logical/q_xtal_4p_13bi_24gnd/chips/chips.prt';

PART_NAME
 Y5 'Q_CRYSTAL_SMLF-32.768KHZ,EMPTY,BG632768012':;

SECTION_NUMBER 1
 '@T6G_MB_LIB.T6G(SCH_1):PAGE55_I7@PURE_QUANTA.Q_CRYSTAL(CHIPS)':
 C_PATH='@t6g_mb_lib.t6g(sch_1):page55_i7@pure_quanta.q_crystal(chips)',
 P_PATH='@t6g_mb_lib.t6g(sch_1):page55_i7@pure_quanta.q_crystal(chips)',
 PATH='I7',
 DRAWING='@T6G_MB_LIB.T6G(SCH_1):PAGE55',
 MATERIAL='EMPTY',
 PHYS_PAGE='55',
 XY='(-3625,1750)',
 ROT='0',
 VER='1',
 PACK_TYPE='SMLF',
 LOCATION='Y5',
 CDS_LIB='pure_quanta',
 CDS_PART_NAME='Q_CRYSTAL_SMLF-32.768KHZ,EMPTY,BG632768012',
 PART_NUMBER='BG632768012',
 VALUE='32.768KHZ',
 PRIM_FILE='./archive_libs/logical/q_crystal/chips/chips.prt';

PART_NAME
 Y9 'Q_XTAL_4P_13BI_24GND-26MHZ,SMLF,MISC,BG626000049':
 ROOM='USB3_HUB1_CYP';

SECTION_NUMBER 1
 '@T6G_MB_LIB.T6G(SCH_1):PAGE153_I14@PURE_QUANTA.Q_XTAL_4P_13BI_24GND(CHIPS)':
 C_PATH='@t6g_mb_lib.t6g(sch_1):page153_i14@pure_quanta.q_xtal_4p_13bi_24gnd(chi~
ps)',
 P_PATH='@t6g_mb_lib.t6g(sch_1):page176_i14@pure_quanta.q_xtal_4p_13bi_24gnd(chi~
ps)',
 PATH='I14',
 DRAWING='@T6G_MB_LIB.T6G(SCH_1):PAGE153',
 SEC_TYPE='',
 PIN_NAMES_ROTATE='True',
 PART_TYPE='SMLF',
 MATERIAL='MISC',
 PHYS_PAGE='176',
 XY='(-7000,1675)',
 ROT='2',
 VER='1',
 LOCATION='Y9',
 SEC='1',
 CDS_LIB='pure_quanta',
 CDS_PART_NAME='Q_XTAL_4P_13BI_24GND-26MHZ,SMLF,MISC,BG626000049',
 ROOM='USB3_HUB1_CYP',
 PART_NUMBER='BG626000049',
 VALUE='26MHZ',
 PRIM_FILE='./archive_libs/logical/q_xtal_4p_13bi_24gnd/chips/chips.prt';

PART_NAME
 Y6000 'Q_XTAL_4P_13BI_24GND-24MHZ,SMLF,MISC,BG624000101':
 ROOM='USB3_HUB2';

SECTION_NUMBER 1
 '@T6G_MB_LIB.T6G(SCH_1):PAGE157_I164@PURE_QUANTA.Q_XTAL_4P_13BI_24GND(CHIPS)':
 C_PATH='@t6g_mb_lib.t6g(sch_1):page157_i164@pure_quanta.q_xtal_4p_13bi_24gnd(ch~
ips)',
 P_PATH='@t6g_mb_lib.t6g(sch_1):page179_i164@pure_quanta.q_xtal_4p_13bi_24gnd(ch~
ips)',
 PATH='I164',
 DRAWING='@T6G_MB_LIB.T6G(SCH_1):PAGE157',
 SEC_TYPE='',
 PIN_NAMES_ROTATE='True',
 PART_TYPE='SMLF',
 MATERIAL='MISC',
 PHYS_PAGE='179',
 XY='(-6825,3050)',
 ROT='2',
 VER='1',
 LOCATION='Y6000',
 SEC='1',
 CDS_LIB='pure_quanta',
 CDS_PART_NAME='Q_XTAL_4P_13BI_24GND-24MHZ,SMLF,MISC,BG624000101',
 ROOM='USB3_HUB2',
 PART_NUMBER='BG624000101',
 VALUE='24MHZ',
 PRIM_FILE='./archive_libs/logical/q_xtal_4p_13bi_24gnd/chips/chips.prt';

PART_NAME
 Y8003 'Q_XTAL_4P_13BI_24GND-25MHZ,SMLF,MISC,BG6250000L4':;

SECTION_NUMBER 1
 '@T6G_MB_LIB.T6G(SCH_1):PAGE232_I14@PURE_QUANTA.Q_XTAL_4P_13BI_24GND(CHIPS)':
 C_PATH='@t6g_mb_lib.t6g(sch_1):page232_i14@pure_quanta.q_xtal_4p_13bi_24gnd(chi~
ps)',
 P_PATH='@t6g_mb_lib.t6g(sch_1):page233_i14@pure_quanta.q_xtal_4p_13bi_24gnd(chi~
ps)',
 PATH='I14',
 DRAWING='@T6G_MB_LIB.T6G(SCH_1):PAGE232',
 PIN_NAMES_ROTATE='True',
 PART_TYPE='SMLF',
 MATERIAL='MISC',
 PHYS_PAGE='233',
 XY='(-6800,4025)',
 ROT='0',
 VER='1',
 LOCATION='Y8003',
 CDS_LIB='pure_quanta',
 CDS_PART_NAME='Q_XTAL_4P_13BI_24GND-25MHZ,SMLF,MISC,BG6250000L4',
 PART_NUMBER='BG6250000L4',
 VALUE='25MHZ',
 PRIM_FILE='./archive_libs/logical/q_xtal_4p_13bi_24gnd/chips/chips.prt';

PART_NAME
 Y8004 'Q_XTAL_4P_13BI_24GND-12MHZ,SMLF,MISC,BG6120000B0':
 ROOM='USB2 BOM1';

SECTION_NUMBER 1
 '@T6G_MB_LIB.T6G(SCH_1):PAGE358_I210@PURE_QUANTA.Q_XTAL_4P_13BI_24GND(CHIPS)':
 C_PATH='@t6g_mb_lib.t6g(sch_1):page358_i210@pure_quanta.q_xtal_4p_13bi_24gnd(ch~
ips)',
 P_PATH='@t6g_mb_lib.t6g(sch_1):page234_i210@pure_quanta.q_xtal_4p_13bi_24gnd(ch~
ips)',
 PATH='I210',
 DRAWING='@T6G_MB_LIB.T6G(SCH_1):PAGE358',
 SEC_TYPE='',
 PIN_NAMES_ROTATE='True',
 PART_TYPE='SMLF',
 MATERIAL='MISC',
 PHYS_PAGE='234',
 XY='(4025,4550)',
 ROT='0',
 VER='1',
 LOCATION='Y8004',
 SEC='1',
 CDS_LIB='pure_quanta',
 CDS_PART_NAME='Q_XTAL_4P_13BI_24GND-12MHZ,SMLF,MISC,BG6120000B0',
 ROOM='USB2 BOM1',
 PART_NUMBER='BG6120000B0',
 VALUE='12MHZ',
 PRIM_FILE='./archive_libs/logical/q_xtal_4p_13bi_24gnd/chips/chips.prt';

END.
